(kicad_pcb
	(version 20260206)
	(generator "pcbnew")
	(generator_version "10.0")
	(general
		(thickness 1.6)
		(legacy_teardrops no)
	)
	(paper "A4")
	(layers
		(0 "F.Cu" signal "TOP")
		(4 "In1.Cu" signal "LYR2")
		(6 "In2.Cu" signal "LYR3")
		(8 "In3.Cu" signal "LYR4")
		(10 "In4.Cu" signal "LYR5")
		(12 "In5.Cu" signal "LYR6")
		(14 "In6.Cu" signal "LYR7")
		(2 "B.Cu" signal "BOTTOM")
		(9 "F.Adhes" user "F.Adhesive")
		(11 "B.Adhes" user "B.Adhesive")
		(13 "F.Paste" user "Package Geometry/Pastemask Top")
		(15 "B.Paste" user "Package Geometry/Pastemask Bottom")
		(5 "F.SilkS" user "Ref Des/Silkscreen Top")
		(7 "B.SilkS" user "Ref Des/Silkscreen Bottom")
		(1 "F.Mask" user "Board Geometry/Soldermask Top")
		(3 "B.Mask" user "Board Geometry/Soldermask Bottom")
		(17 "Dwgs.User" user "User.Drawings")
		(19 "Cmts.User" user "User.Comments")
		(21 "Eco1.User" user "User.Eco1")
		(23 "Eco2.User" user "User.Eco2")
		(25 "Edge.Cuts" user "Board Geometry/Outline")
		(27 "Margin" user)
		(31 "F.CrtYd" user "Package Geometry/Place Bound Top")
		(29 "B.CrtYd" user "Package Geometry/Place Bound Bottom")
		(35 "F.Fab" user "Ref Des/Assembly Top")
		(33 "B.Fab" user "Ref Des/Assembly Bottom")
	)
	(setup
		(pad_to_mask_clearance 0)
		(allow_soldermask_bridges_in_footprints no)
		(tenting
			(front yes)
			(back yes)
		)
		(covering
			(front no)
			(back no)
		)
		(plugging
			(front no)
			(back no)
		)
		(capping no)
		(filling no)
		(pcbplotparams
			(layerselection 0x00000000_00000000_55555555_5755f5ff)
			(plot_on_all_layers_selection 0x00000000_00000000_00000000_00000000)
			(disableapertmacros no)
			(usegerberextensions no)
			(usegerberattributes yes)
			(usegerberadvancedattributes yes)
			(creategerberjobfile yes)
			(dashed_line_dash_ratio 12)
			(dashed_line_gap_ratio 3)
			(svgprecision 4)
			(plotframeref no)
			(mode 1)
			(useauxorigin no)
			(pdf_front_fp_property_popups yes)
			(pdf_back_fp_property_popups yes)
			(pdf_metadata yes)
			(pdf_single_document no)
			(dxfpolygonmode yes)
			(dxfimperialunits yes)
			(dxfusepcbnewfont yes)
			(psnegative no)
			(psa4output no)
			(plot_black_and_white yes)
			(sketchpadsonfab no)
			(plotpadnumbers no)
			(hidednponfab no)
			(sketchdnponfab yes)
			(crossoutdnponfab yes)
			(subtractmaskfromsilk no)
			(outputformat 1)
			(mirror no)
			(drillshape 1)
			(scaleselection 1)
			(outputdirectory "")
		)
	)
	(footprint ""
		(layer "F.Cu")
		(at -269.044001 12.916002 90)
		(property "Reference" "C29"
			(at -2.430678 -0.180759 90)
			(unlocked yes)
			(layer "F.SilkS")
			(effects
				(font
					(size 0.762 0.5334)
					(thickness 0.1016)
				)
			)
		)
		(property "Value" ""
			(at 0 0 90)
			(layer "F.Fab")
			(effects
				(font
					(size 1.27 1.27)
				)
			)
		)
		(duplicate_pad_numbers_are_jumpers no)
		(fp_poly
			(pts
				(xy -0.999299 0.504) (xy -0.999299 -0.503999) (xy 0.9993 -0.503999) (xy 0.9993 0.504)
			)
			(stroke
				(width 0)
				(type default)
			)
			(fill no)
			(layer "F.CrtYd")
		)
		(fp_line
			(start 0.499999 -0.249999)
			(end 0.499999 0.25)
			(stroke
				(width 0.1)
				(type default)
			)
			(layer "F.Fab")
		)
		(fp_line
			(start -0.499999 -0.249999)
			(end 0.499999 -0.249999)
			(stroke
				(width 0.1)
				(type default)
			)
			(layer "F.Fab")
		)
		(fp_line
			(start 0.499999 0.25)
			(end -0.499999 0.25)
			(stroke
				(width 0.1)
				(type default)
			)
			(layer "F.Fab")
		)
		(fp_line
			(start -0.499999 0.25)
			(end -0.499999 -0.249999)
			(stroke
				(width 0.1)
				(type default)
			)
			(layer "F.Fab")
		)
		(pad "1" smd rect
			(at -0.4572 0 180)
			(size 0.508 0.5842)
			(layers "F.Cu" "F.Mask" "F.Paste")
			(net "P3V3_40G_B1_VCC1")
		)
		(pad "2" smd rect
			(at 0.4572 0 180)
			(size 0.508 0.5842)
			(layers "F.Cu" "F.Mask" "F.Paste")
			(net "GND")
		)
	)
	(footprint ""
		(layer "F.Cu")
		(at -110.8456 18.8214)
		(property "Reference" "R34"
			(at 2.5146 0.0127 0)
			(unlocked yes)
			(layer "F.SilkS")
			(effects
				(font
					(size 0.762 0.5334)
					(thickness 0.1016)
				)
			)
		)
		(property "Value" ""
			(at 0 0 0)
			(layer "F.Fab")
			(effects
				(font
					(size 1.27 1.27)
				)
			)
		)
		(duplicate_pad_numbers_are_jumpers no)
		(fp_line
			(start 0 -0.381)
			(end 0 0.381)
			(stroke
				(width 0.127)
				(type default)
			)
			(layer "F.SilkS")
		)
		(fp_poly
			(pts
				(xy 1.255601 0.6564) (xy -1.255601 0.6564) (xy -1.255601 -0.656399) (xy 1.255601 -0.656399)
			)
			(stroke
				(width 0)
				(type default)
			)
			(fill no)
			(layer "F.CrtYd")
		)
		(fp_line
			(start -0.800001 -0.399999)
			(end -0.800001 0.399999)
			(stroke
				(width 0.1)
				(type default)
			)
			(layer "F.Fab")
		)
		(fp_line
			(start -0.800001 0.399999)
			(end 0.800001 0.399999)
			(stroke
				(width 0.1)
				(type default)
			)
			(layer "F.Fab")
		)
		(fp_line
			(start 0.800001 -0.399999)
			(end -0.800001 -0.399999)
			(stroke
				(width 0.1)
				(type default)
			)
			(layer "F.Fab")
		)
		(fp_line
			(start 0.800001 0.399999)
			(end 0.800001 -0.399999)
			(stroke
				(width 0.1)
				(type default)
			)
			(layer "F.Fab")
		)
		(pad "1" smd rect
			(at -0.650001 0)
			(size 0.7112 0.8128)
			(layers "F.Cu" "F.Mask" "F.Paste")
			(net "P3V3_B2_QSFP")
		)
		(pad "2" smd rect
			(at 0.650001 0 180)
			(size 0.7112 0.8128)
			(layers "F.Cu" "F.Mask" "F.Paste")
			(net "SKU_B2_ID2")
		)
	)
	(footprint ""
		(layer "F.Cu")
		(at -75.3618 9.652)
		(property "Reference" "R50"
			(at 2.9718 0.1143 0)
			(unlocked yes)
			(layer "F.SilkS")
			(effects
				(font
					(size 0.762 0.5334)
					(thickness 0.1016)
				)
			)
		)
		(property "Value" ""
			(at 0 0 0)
			(layer "F.Fab")
			(effects
				(font
					(size 1.27 1.27)
				)
			)
		)
		(duplicate_pad_numbers_are_jumpers no)
		(fp_line
			(start 0 -0.381)
			(end 0 0.381)
			(stroke
				(width 0.127)
				(type default)
			)
			(layer "F.SilkS")
		)
		(fp_poly
			(pts
				(xy 1.255601 0.6564) (xy -1.255601 0.6564) (xy -1.255601 -0.656399) (xy 1.255601 -0.656399)
			)
			(stroke
				(width 0)
				(type default)
			)
			(fill no)
			(layer "F.CrtYd")
		)
		(fp_line
			(start -0.800001 -0.399999)
			(end -0.800001 0.399999)
			(stroke
				(width 0.1)
				(type default)
			)
			(layer "F.Fab")
		)
		(fp_line
			(start -0.800001 0.399999)
			(end 0.800001 0.399999)
			(stroke
				(width 0.1)
				(type default)
			)
			(layer "F.Fab")
		)
		(fp_line
			(start 0.800001 -0.399999)
			(end -0.800001 -0.399999)
			(stroke
				(width 0.1)
				(type default)
			)
			(layer "F.Fab")
		)
		(fp_line
			(start 0.800001 0.399999)
			(end 0.800001 -0.399999)
			(stroke
				(width 0.1)
				(type default)
			)
			(layer "F.Fab")
		)
		(pad "1" smd rect
			(at -0.650001 0)
			(size 0.7112 0.8128)
			(layers "F.Cu" "F.Mask" "F.Paste")
			(net "P3V3_B2_QSFP")
		)
		(pad "2" smd rect
			(at 0.650001 0 180)
			(size 0.7112 0.8128)
			(layers "F.Cu" "F.Mask" "F.Paste")
			(net "ETH10G_B2_RS0")
		)
	)
	(footprint ""
		(layer "F.Cu")
		(at -75.329199 3.873398)
		(property "Reference" "R53"
			(at 2.812199 0.101702 0)
			(unlocked yes)
			(layer "F.SilkS")
			(effects
				(font
					(size 0.762 0.5334)
					(thickness 0.1016)
				)
			)
		)
		(property "Value" ""
			(at 0 0 0)
			(layer "F.Fab")
			(effects
				(font
					(size 1.27 1.27)
				)
			)
		)
		(duplicate_pad_numbers_are_jumpers no)
		(fp_line
			(start 0 -0.381)
			(end 0 0.381)
			(stroke
				(width 0.127)
				(type default)
			)
			(layer "F.SilkS")
		)
		(fp_poly
			(pts
				(xy 1.255601 0.6564) (xy -1.255601 0.6564) (xy -1.255601 -0.656399) (xy 1.255601 -0.656399)
			)
			(stroke
				(width 0)
				(type default)
			)
			(fill no)
			(layer "F.CrtYd")
		)
		(fp_line
			(start -0.800001 -0.399999)
			(end -0.800001 0.4)
			(stroke
				(width 0.1)
				(type default)
			)
			(layer "F.Fab")
		)
		(fp_line
			(start -0.800001 0.4)
			(end 0.800001 0.4)
			(stroke
				(width 0.1)
				(type default)
			)
			(layer "F.Fab")
		)
		(fp_line
			(start 0.800001 -0.399999)
			(end -0.800001 -0.399999)
			(stroke
				(width 0.1)
				(type default)
			)
			(layer "F.Fab")
		)
		(fp_line
			(start 0.800001 0.4)
			(end 0.800001 -0.399999)
			(stroke
				(width 0.1)
				(type default)
			)
			(layer "F.Fab")
		)
		(pad "1" smd rect
			(at -0.650001 0)
			(size 0.7112 0.8128)
			(layers "F.Cu" "F.Mask" "F.Paste")
			(net "ETH10G_B2_RS1")
		)
		(pad "2" smd rect
			(at 0.650001 0 180)
			(size 0.7112 0.8128)
			(layers "F.Cu" "F.Mask" "F.Paste")
			(net "GND")
		)
	)
	(footprint ""
		(layer "F.Cu")
		(at -115.221601 21.272602 90)
		(property "Reference" "C15"
			(at -2.857398 -0.056299 90)
			(unlocked yes)
			(layer "F.SilkS")
			(effects
				(font
					(size 0.762 0.5334)
					(thickness 0.1016)
				)
			)
		)
		(property "Value" ""
			(at 0 0 90)
			(layer "F.Fab")
			(effects
				(font
					(size 1.27 1.27)
				)
			)
		)
		(duplicate_pad_numbers_are_jumpers no)
		(fp_poly
			(pts
				(xy -0.999299 0.504) (xy -0.999299 -0.503999) (xy 0.9993 -0.503999) (xy 0.9993 0.504)
			)
			(stroke
				(width 0)
				(type default)
			)
			(fill no)
			(layer "F.CrtYd")
		)
		(fp_line
			(start 0.499999 -0.249999)
			(end 0.499999 0.25)
			(stroke
				(width 0.1)
				(type default)
			)
			(layer "F.Fab")
		)
		(fp_line
			(start -0.499999 -0.249999)
			(end 0.499999 -0.249999)
			(stroke
				(width 0.1)
				(type default)
			)
			(layer "F.Fab")
		)
		(fp_line
			(start 0.499999 0.25)
			(end -0.499999 0.25)
			(stroke
				(width 0.1)
				(type default)
			)
			(layer "F.Fab")
		)
		(fp_line
			(start -0.499999 0.25)
			(end -0.499999 -0.249999)
			(stroke
				(width 0.1)
				(type default)
			)
			(layer "F.Fab")
		)
		(pad "1" smd rect
			(at -0.4572 0 180)
			(size 0.508 0.5842)
			(layers "F.Cu" "F.Mask" "F.Paste")
			(net "P12V")
		)
		(pad "2" smd rect
			(at 0.4572 0 180)
			(size 0.508 0.5842)
			(layers "F.Cu" "F.Mask" "F.Paste")
			(net "GND")
		)
	)
	(footprint ""
		(layer "F.Cu")
		(at -240.919 43.942 -90)
		(property "Reference" "R1"
			(at 0.412775 -1.400449 90)
			(unlocked yes)
			(layer "F.SilkS")
			(effects
				(font
					(size 0.762 0.5334)
					(thickness 0.1016)
				)
			)
		)
		(property "Value" ""
			(at 0 0 270)
			(layer "F.Fab")
			(effects
				(font
					(size 1.27 1.27)
				)
			)
		)
		(duplicate_pad_numbers_are_jumpers no)
		(fp_line
			(start 0 -0.381)
			(end 0 0.381)
			(stroke
				(width 0.127)
				(type default)
			)
			(layer "F.SilkS")
		)
		(fp_poly
			(pts
				(xy 1.255601 0.6564) (xy -1.255601 0.6564) (xy -1.255601 -0.656399) (xy 1.255601 -0.656399)
			)
			(stroke
				(width 0)
				(type default)
			)
			(fill no)
			(layer "F.CrtYd")
		)
		(fp_line
			(start -0.800001 0.399999)
			(end 0.800001 0.399999)
			(stroke
				(width 0.1)
				(type default)
			)
			(layer "F.Fab")
		)
		(fp_line
			(start 0.800001 0.399999)
			(end 0.800001 -0.399999)
			(stroke
				(width 0.1)
				(type default)
			)
			(layer "F.Fab")
		)
		(fp_line
			(start -0.800001 -0.399999)
			(end -0.800001 0.399999)
			(stroke
				(width 0.1)
				(type default)
			)
			(layer "F.Fab")
		)
		(fp_line
			(start 0.800001 -0.399999)
			(end -0.800001 -0.399999)
			(stroke
				(width 0.1)
				(type default)
			)
			(layer "F.Fab")
		)
		(pad "1" smd rect
			(at -0.650001 0 270)
			(size 0.7112 0.8128)
			(layers "F.Cu" "F.Mask" "F.Paste")
			(net "GND")
		)
		(pad "2" smd rect
			(at 0.650001 0 90)
			(size 0.7112 0.8128)
			(layers "F.Cu" "F.Mask" "F.Paste")
			(net "JBOD_B1_MATED_N")
		)
	)
	(footprint ""
		(layer "F.Cu")
		(at -123.551 4.7244 -90)
		(property "Reference" "R39"
			(at 0.08128 1.22904 90)
			(unlocked yes)
			(layer "F.SilkS")
			(effects
				(font
					(size 0.762 0.5334)
					(thickness 0.1016)
				)
			)
		)
		(property "Value" ""
			(at 0 0 270)
			(layer "F.Fab")
			(effects
				(font
					(size 1.27 1.27)
				)
			)
		)
		(duplicate_pad_numbers_are_jumpers no)
		(fp_line
			(start 0 -0.381)
			(end 0 0.381)
			(stroke
				(width 0.127)
				(type default)
			)
			(layer "F.SilkS")
		)
		(fp_poly
			(pts
				(xy 1.255601 0.6564) (xy -1.255601 0.6564) (xy -1.255601 -0.656399) (xy 1.255601 -0.656399)
			)
			(stroke
				(width 0)
				(type default)
			)
			(fill no)
			(layer "F.CrtYd")
		)
		(fp_line
			(start -0.800001 0.399999)
			(end 0.800001 0.399999)
			(stroke
				(width 0.1)
				(type default)
			)
			(layer "F.Fab")
		)
		(fp_line
			(start 0.800001 0.399999)
			(end 0.800001 -0.399999)
			(stroke
				(width 0.1)
				(type default)
			)
			(layer "F.Fab")
		)
		(fp_line
			(start -0.800001 -0.399999)
			(end -0.800001 0.399999)
			(stroke
				(width 0.1)
				(type default)
			)
			(layer "F.Fab")
		)
		(fp_line
			(start 0.800001 -0.399999)
			(end -0.800001 -0.399999)
			(stroke
				(width 0.1)
				(type default)
			)
			(layer "F.Fab")
		)
		(pad "1" smd rect
			(at -0.650001 0 270)
			(size 0.7112 0.8128)
			(layers "F.Cu" "F.Mask" "F.Paste")
			(net "UNNAMED_6_1X2HDR_I56_IO")
		)
		(pad "2" smd rect
			(at 0.650001 0 90)
			(size 0.7112 0.8128)
			(layers "F.Cu" "F.Mask" "F.Paste")
			(net "GND")
		)
	)
	(footprint ""
		(layer "F.Cu")
		(at -337.250049 32.460001)
		(property "Reference" "J4"
			(at 4.129049 -6.767901 0)
			(unlocked yes)
			(layer "F.SilkS")
			(effects
				(font
					(size 0.762 0.5334)
					(thickness 0.1016)
				)
			)
		)
		(property "Value" ""
			(at 0 0 0)
			(layer "F.Fab")
			(effects
				(font
					(size 1.27 1.27)
				)
			)
		)
		(duplicate_pad_numbers_are_jumpers no)
		(fp_line
			(start -1.925 -5.549999)
			(end 9.924999 -5.549999)
			(stroke
				(width 0.127)
				(type default)
			)
			(layer "F.SilkS")
		)
		(fp_line
			(start -1.925 23.750001)
			(end -1.925 -5.549999)
			(stroke
				(width 0.127)
				(type default)
			)
			(layer "F.SilkS")
		)
		(fp_line
			(start 9.924999 -5.549999)
			(end 9.924999 23.750001)
			(stroke
				(width 0.127)
				(type default)
			)
			(layer "F.SilkS")
		)
		(fp_line
			(start 9.924999 23.750001)
			(end -1.925 23.750001)
			(stroke
				(width 0.127)
				(type default)
			)
			(layer "F.SilkS")
		)
		(fp_poly
			(pts
				(arc
					(start 7.999999 -5.2)
					(mid 11.676954 -3.676955)
					(end 13.199999 0)
				)
				(arc
					(start 13.199999 11.999999)
					(mid 11.676955 15.676956)
					(end 7.999999 17.200001)
				)
				(arc
					(start 0 17.200001)
					(mid -3.676956 15.676955)
					(end -5.2 11.999999)
				)
				(arc
					(start -5.2 0)
					(mid -3.676955 -3.676955)
					(end 0 -5.2)
				)
			)
			(stroke
				(width 0)
				(type default)
			)
			(fill no)
			(layer "B.CrtYd")
		)
		(fp_poly
			(pts
				(xy 10.924999 24.749999) (xy -2.925001 24.749999) (xy -2.925001 -6.549999) (xy 10.924999 -6.549999)
			)
			(stroke
				(width 0)
				(type default)
			)
			(fill no)
			(layer "F.CrtYd")
		)
		(fp_line
			(start -1.925 -5.549999)
			(end 9.924999 -5.549999)
			(stroke
				(width 0.1)
				(type default)
			)
			(layer "F.Fab")
		)
		(fp_line
			(start -1.925 23.750001)
			(end -1.925 -5.549999)
			(stroke
				(width 0.1)
				(type default)
			)
			(layer "F.Fab")
		)
		(fp_line
			(start 9.924999 -5.549999)
			(end 9.924999 23.750001)
			(stroke
				(width 0.1)
				(type default)
			)
			(layer "F.Fab")
		)
		(fp_line
			(start 9.924999 23.750001)
			(end -1.925 23.750001)
			(stroke
				(width 0.1)
				(type default)
			)
			(layer "F.Fab")
		)
		(fp_text user "*"
			(at -0.360401 -6.425001 90)
			(unlocked yes)
			(layer "F.SilkS")
			(effects
				(font
					(size 0.381 0.381)
					(thickness 0.381)
				)
			)
		)
		(fp_text user "2"
			(at 10.499999 -0.3469 0)
			(unlocked yes)
			(layer "F.SilkS")
			(effects
				(font
					(size 0.762 0.5334)
					(thickness 0.1016)
				)
			)
		)
		(fp_text user "3"
			(at 10.499999 7.907099 0)
			(unlocked yes)
			(layer "F.SilkS")
			(effects
				(font
					(size 0.762 0.5334)
					(thickness 0.1016)
				)
			)
		)
		(pad "" np_thru_hole circle
			(at 4 5.499999)
			(size 1.27 1.27)
			(drill 2.1844)
			(layers "*.Cu" "*.Mask")
		)
		(pad "1A" thru_hole rect
			(at 0 0)
			(size 1.3716 1.3716)
			(drill 0.762)
			(layers "*.Cu" "*.Mask")
			(remove_unused_layers no)
			(net "GND")
			(padstack
				(mode front_inner_back)
				(layer "Inner"
					(shape circle)
					(size 1.3716 1.3716)
				)
				(layer "B.Cu"
					(shape rect)
					(size 1.3716 1.3716)
				)
			)
		)
		(pad "1B" thru_hole circle
			(at 2.000001 0)
			(size 1.3716 1.3716)
			(drill 0.762)
			(layers "*.Cu" "*.Mask")
			(remove_unused_layers no)
			(net "GND")
		)
		(pad "1C" thru_hole circle
			(at 0 2.000001)
			(size 1.3716 1.3716)
			(drill 0.762)
			(layers "*.Cu" "*.Mask")
			(remove_unused_layers no)
			(net "GND")
		)
		(pad "1D" thru_hole circle
			(at 2.000001 2.000001)
			(size 1.3716 1.3716)
			(drill 0.762)
			(layers "*.Cu" "*.Mask")
			(remove_unused_layers no)
			(net "GND")
		)
		(pad "1E" thru_hole circle
			(at 0 4)
			(size 1.3716 1.3716)
			(drill 0.762)
			(layers "*.Cu" "*.Mask")
			(remove_unused_layers no)
			(net "GND")
		)
		(pad "1F" thru_hole circle
			(at 2.000001 4)
			(size 1.3716 1.3716)
			(drill 0.762)
			(layers "*.Cu" "*.Mask")
			(remove_unused_layers no)
			(net "GND")
		)
		(pad "2A" thru_hole circle
			(at 6.000001 0)
			(size 1.3716 1.3716)
			(drill 0.762)
			(layers "*.Cu" "*.Mask")
			(remove_unused_layers no)
			(net "P12V")
		)
		(pad "2B" thru_hole circle
			(at 7.999999 0)
			(size 1.3716 1.3716)
			(drill 0.762)
			(layers "*.Cu" "*.Mask")
			(remove_unused_layers no)
			(net "P12V")
		)
		(pad "2C" thru_hole circle
			(at 6.000001 2.000001)
			(size 1.3716 1.3716)
			(drill 0.762)
			(layers "*.Cu" "*.Mask")
			(remove_unused_layers no)
			(net "P12V")
		)
		(pad "2D" thru_hole circle
			(at 7.999999 2.000001)
			(size 1.3716 1.3716)
			(drill 0.762)
			(layers "*.Cu" "*.Mask")
			(remove_unused_layers no)
			(net "P12V")
		)
		(pad "2E" thru_hole circle
			(at 6.000001 4)
			(size 1.3716 1.3716)
			(drill 0.762)
			(layers "*.Cu" "*.Mask")
			(remove_unused_layers no)
			(net "P12V")
		)
		(pad "2F" thru_hole circle
			(at 7.999999 4)
			(size 1.3716 1.3716)
			(drill 0.762)
			(layers "*.Cu" "*.Mask")
			(remove_unused_layers no)
			(net "P12V")
		)
		(pad "3A" thru_hole circle
			(at 6.000001 7.999999)
			(size 1.3716 1.3716)
			(drill 0.762)
			(layers "*.Cu" "*.Mask")
			(remove_unused_layers no)
			(net "P12V")
		)
		(pad "3B" thru_hole circle
			(at 7.999999 7.999999)
			(size 1.3716 1.3716)
			(drill 0.762)
			(layers "*.Cu" "*.Mask")
			(remove_unused_layers no)
			(net "P12V")
		)
		(pad "3C" thru_hole circle
			(at 6.000001 10)
			(size 1.3716 1.3716)
			(drill 0.762)
			(layers "*.Cu" "*.Mask")
			(remove_unused_layers no)
			(net "P12V")
		)
		(pad "3D" thru_hole circle
			(at 7.999999 10)
			(size 1.3716 1.3716)
			(drill 0.762)
			(layers "*.Cu" "*.Mask")
			(remove_unused_layers no)
			(net "P12V")
		)
		(pad "3E" thru_hole circle
			(at 6.000001 11.999999)
			(size 1.3716 1.3716)
			(drill 0.762)
			(layers "*.Cu" "*.Mask")
			(remove_unused_layers no)
			(net "P12V")
		)
		(pad "3F" thru_hole circle
			(at 7.999999 11.999999)
			(size 1.3716 1.3716)
			(drill 0.762)
			(layers "*.Cu" "*.Mask")
			(remove_unused_layers no)
			(net "P12V")
		)
		(pad "4A" thru_hole circle
			(at 0 7.999999)
			(size 1.3716 1.3716)
			(drill 0.762)
			(layers "*.Cu" "*.Mask")
			(remove_unused_layers no)
			(net "GND")
		)
		(pad "4B" thru_hole circle
			(at 2.000001 7.999999)
			(size 1.3716 1.3716)
			(drill 0.762)
			(layers "*.Cu" "*.Mask")
			(remove_unused_layers no)
			(net "GND")
		)
		(pad "4C" thru_hole circle
			(at 0 10)
			(size 1.3716 1.3716)
			(drill 0.762)
			(layers "*.Cu" "*.Mask")
			(remove_unused_layers no)
			(net "GND")
		)
		(pad "4D" thru_hole circle
			(at 2.000001 10)
			(size 1.3716 1.3716)
			(drill 0.762)
			(layers "*.Cu" "*.Mask")
			(remove_unused_layers no)
			(net "GND")
		)
		(pad "4E" thru_hole circle
			(at 0 11.999999)
			(size 1.3716 1.3716)
			(drill 0.762)
			(layers "*.Cu" "*.Mask")
			(remove_unused_layers no)
			(net "GND")
		)
		(pad "4F" thru_hole circle
			(at 2.000001 11.999999)
			(size 1.3716 1.3716)
			(drill 0.762)
			(layers "*.Cu" "*.Mask")
			(remove_unused_layers no)
			(net "GND")
		)
		(zone
			(layers "F.Cu" "B.Cu" "In1.Cu" "In2.Cu" "In3.Cu" "In4.Cu" "In5.Cu" "In6.Cu")
			(hatch none 0.5)
			(connect_pads
				(clearance 0)
			)
			(min_thickness 0.25)
			(keepout
				(tracks not_allowed)
				(vias allowed)
				(pads allowed)
				(copperpour not_allowed)
				(footprints allowed)
			)
			(placement
				(enabled no)
				(sheetname "")
			)
			(fill
				(thermal_gap 0.5)
				(thermal_bridge_width 0.5)
				(island_removal_mode 0)
			)
			(polygon
				(pts
					(arc
						(start -331.77685 37.96)
						(mid -334.72325 37.96)
						(end -331.77685 37.96)
					)
				)
			)
		)
	)
	(footprint ""
		(layer "F.Cu")
		(at -300.99 10.287)
		(property "Reference" "R12"
			(at -3.175 0.0381 0)
			(unlocked yes)
			(layer "F.SilkS")
			(effects
				(font
					(size 0.762 0.5334)
					(thickness 0.1016)
				)
			)
		)
		(property "Value" ""
			(at 0 0 0)
			(layer "F.Fab")
			(effects
				(font
					(size 1.27 1.27)
				)
			)
		)
		(duplicate_pad_numbers_are_jumpers no)
		(fp_line
			(start 0 -0.381)
			(end 0 0.381)
			(stroke
				(width 0.127)
				(type default)
			)
			(layer "F.SilkS")
		)
		(fp_poly
			(pts
				(xy 1.255601 0.6564) (xy -1.255601 0.6564) (xy -1.255601 -0.656399) (xy 1.255601 -0.656399)
			)
			(stroke
				(width 0)
				(type default)
			)
			(fill no)
			(layer "F.CrtYd")
		)
		(fp_line
			(start -0.800001 -0.399999)
			(end -0.800001 0.399999)
			(stroke
				(width 0.1)
				(type default)
			)
			(layer "F.Fab")
		)
		(fp_line
			(start -0.800001 0.399999)
			(end 0.800001 0.399999)
			(stroke
				(width 0.1)
				(type default)
			)
			(layer "F.Fab")
		)
		(fp_line
			(start 0.800001 -0.399999)
			(end -0.800001 -0.399999)
			(stroke
				(width 0.1)
				(type default)
			)
			(layer "F.Fab")
		)
		(fp_line
			(start 0.800001 0.399999)
			(end 0.800001 -0.399999)
			(stroke
				(width 0.1)
				(type default)
			)
			(layer "F.Fab")
		)
		(pad "1" smd rect
			(at -0.650001 0)
			(size 0.7112 0.8128)
			(layers "F.Cu" "F.Mask" "F.Paste")
			(net "BLADE_B1_MATED_N<1>")
		)
		(pad "2" smd rect
			(at 0.650001 0 180)
			(size 0.7112 0.8128)
			(layers "F.Cu" "F.Mask" "F.Paste")
			(net "GND")
		)
	)
	(footprint ""
		(layer "F.Cu")
		(at -266.446 7.4676 180)
		(property "Reference" "FB8"
			(at -1.651 -0.0635 0)
			(unlocked yes)
			(layer "F.SilkS")
			(effects
				(font
					(size 0.762 0.5334)
					(thickness 0.1016)
				)
				(justify left)
			)
		)
		(property "Value" ""
			(at 0 0 180)
			(layer "F.Fab")
			(effects
				(font
					(size 1.27 1.27)
				)
			)
		)
		(duplicate_pad_numbers_are_jumpers no)
		(fp_poly
			(pts
				(xy -1.016 0.508) (xy -1.016 -0.508) (xy 1.016 -0.508) (xy 1.016 0.508)
			)
			(stroke
				(width 0)
				(type default)
			)
			(fill no)
			(layer "F.CrtYd")
		)
		(fp_line
			(start 0.508 0.254)
			(end -0.508 0.254)
			(stroke
				(width 0.1)
				(type default)
			)
			(layer "F.Fab")
		)
		(fp_line
			(start 0.508 -0.254)
			(end 0.508 0.254)
			(stroke
				(width 0.1)
				(type default)
			)
			(layer "F.Fab")
		)
		(fp_line
			(start -0.508 0.254)
			(end -0.508 -0.254)
			(stroke
				(width 0.1)
				(type default)
			)
			(layer "F.Fab")
		)
		(fp_line
			(start -0.508 -0.254)
			(end 0.508 -0.254)
			(stroke
				(width 0.1)
				(type default)
			)
			(layer "F.Fab")
		)
		(pad "1" smd rect
			(at -0.4572 0 270)
			(size 0.508 0.5842)
			(layers "F.Cu" "F.Mask" "F.Paste")
			(net "UNNAMED_16_FERRITE_I115_A")
		)
		(pad "2" smd rect
			(at 0.4572 0 270)
			(size 0.508 0.5842)
			(layers "F.Cu" "F.Mask" "F.Paste")
			(net "P3V3_40G_B1_VCC_TX")
		)
	)
	(footprint ""
		(layer "F.Cu")
		(at -47.663001 12.789002 90)
		(property "Reference" "C17"
			(at -2.644038 0.027841 90)
			(unlocked yes)
			(layer "F.SilkS")
			(effects
				(font
					(size 0.762 0.5334)
					(thickness 0.1016)
				)
			)
		)
		(property "Value" ""
			(at 0 0 90)
			(layer "F.Fab")
			(effects
				(font
					(size 1.27 1.27)
				)
			)
		)
		(duplicate_pad_numbers_are_jumpers no)
		(fp_poly
			(pts
				(xy -0.999299 0.504) (xy -0.999299 -0.503999) (xy 0.9993 -0.503999) (xy 0.9993 0.504)
			)
			(stroke
				(width 0)
				(type default)
			)
			(fill no)
			(layer "F.CrtYd")
		)
		(fp_line
			(start 0.499999 -0.249999)
			(end 0.499999 0.25)
			(stroke
				(width 0.1)
				(type default)
			)
			(layer "F.Fab")
		)
		(fp_line
			(start -0.499999 -0.249999)
			(end 0.499999 -0.249999)
			(stroke
				(width 0.1)
				(type default)
			)
			(layer "F.Fab")
		)
		(fp_line
			(start 0.499999 0.25)
			(end -0.499999 0.25)
			(stroke
				(width 0.1)
				(type default)
			)
			(layer "F.Fab")
		)
		(fp_line
			(start -0.499999 0.25)
			(end -0.499999 -0.249999)
			(stroke
				(width 0.1)
				(type default)
			)
			(layer "F.Fab")
		)
		(pad "1" smd rect
			(at -0.4572 0 180)
			(size 0.508 0.5842)
			(layers "F.Cu" "F.Mask" "F.Paste")
			(net "P3V3_40G_B2_VCC1")
		)
		(pad "2" smd rect
			(at 0.4572 0 180)
			(size 0.508 0.5842)
			(layers "F.Cu" "F.Mask" "F.Paste")
			(net "GND")
		)
	)
	(footprint ""
		(layer "F.Cu")
		(at -334.449001 21.171002 90)
		(property "Reference" "C1"
			(at -0.672998 1.366101 90)
			(unlocked yes)
			(layer "F.SilkS")
			(effects
				(font
					(size 0.762 0.5334)
					(thickness 0.1016)
				)
			)
		)
		(property "Value" ""
			(at 0 0 90)
			(layer "F.Fab")
			(effects
				(font
					(size 1.27 1.27)
				)
			)
		)
		(duplicate_pad_numbers_are_jumpers no)
		(fp_line
			(start 0 -0.381)
			(end 0 0.381)
			(stroke
				(width 0.127)
				(type default)
			)
			(layer "F.SilkS")
		)
		(fp_poly
			(pts
				(xy 1.2533 0.6564) (xy -1.253299 0.6564) (xy -1.253299 -0.656399) (xy 1.2533 -0.656399)
			)
			(stroke
				(width 0)
				(type default)
			)
			(fill no)
			(layer "F.CrtYd")
		)
		(fp_line
			(start 0.762 -0.381)
			(end -0.762 -0.381)
			(stroke
				(width 0.1)
				(type default)
			)
			(layer "F.Fab")
		)
		(fp_line
			(start -0.762 -0.381)
			(end -0.762 0.381)
			(stroke
				(width 0.1)
				(type default)
			)
			(layer "F.Fab")
		)
		(fp_line
			(start 0.762 0.381)
			(end 0.762 -0.381)
			(stroke
				(width 0.1)
				(type default)
			)
			(layer "F.Fab")
		)
		(fp_line
			(start -0.762 0.381)
			(end 0.762 0.381)
			(stroke
				(width 0.1)
				(type default)
			)
			(layer "F.Fab")
		)
		(pad "1" smd rect
			(at -0.6477 0 90)
			(size 0.7112 0.8128)
			(layers "F.Cu" "F.Mask" "F.Paste")
			(net "P12V")
		)
		(pad "2" smd rect
			(at 0.6477 0 270)
			(size 0.7112 0.8128)
			(layers "F.Cu" "F.Mask" "F.Paste")
			(net "GND")
		)
	)
	(footprint ""
		(layer "F.Cu")
		(at -48.856801 12.789002 90)
		(property "Reference" "C18"
			(at 0 -0.942899 90)
			(unlocked yes)
			(layer "F.SilkS")
			(effects
				(font
					(size 0.762 0.5334)
					(thickness 0.1016)
				)
			)
		)
		(property "Value" ""
			(at 0 0 90)
			(layer "F.Fab")
			(effects
				(font
					(size 1.27 1.27)
				)
			)
		)
		(duplicate_pad_numbers_are_jumpers no)
		(fp_line
			(start 0 -0.381)
			(end 0 0.381)
			(stroke
				(width 0.127)
				(type default)
			)
			(layer "F.SilkS")
		)
		(fp_poly
			(pts
				(xy 1.2533 0.6564) (xy -1.253299 0.6564) (xy -1.253299 -0.656399) (xy 1.2533 -0.656399)
			)
			(stroke
				(width 0)
				(type default)
			)
			(fill no)
			(layer "F.CrtYd")
		)
		(fp_line
			(start 0.762 -0.381)
			(end -0.762 -0.381)
			(stroke
				(width 0.1)
				(type default)
			)
			(layer "F.Fab")
		)
		(fp_line
			(start -0.762 -0.381)
			(end -0.762 0.381)
			(stroke
				(width 0.1)
				(type default)
			)
			(layer "F.Fab")
		)
		(fp_line
			(start 0.762 0.381)
			(end 0.762 -0.381)
			(stroke
				(width 0.1)
				(type default)
			)
			(layer "F.Fab")
		)
		(fp_line
			(start -0.762 0.381)
			(end 0.762 0.381)
			(stroke
				(width 0.1)
				(type default)
			)
			(layer "F.Fab")
		)
		(pad "1" smd rect
			(at -0.6477 0 90)
			(size 0.7112 0.8128)
			(layers "F.Cu" "F.Mask" "F.Paste")
			(net "P3V3_40G_B2_VCC1")
		)
		(pad "2" smd rect
			(at 0.6477 0 270)
			(size 0.7112 0.8128)
			(layers "F.Cu" "F.Mask" "F.Paste")
			(net "GND")
		)
	)
	(footprint ""
		(layer "F.Cu")
		(at -165.0238 31.1912 90)
		(property "Reference" "R86"
			(at 0.77216 1.60274 90)
			(unlocked yes)
			(layer "F.SilkS")
			(effects
				(font
					(size 0.762 0.5334)
					(thickness 0.1016)
				)
			)
		)
		(property "Value" ""
			(at 0 0 90)
			(layer "F.Fab")
			(effects
				(font
					(size 1.27 1.27)
				)
			)
		)
		(duplicate_pad_numbers_are_jumpers no)
		(fp_line
			(start 0 -0.381)
			(end 0 0.381)
			(stroke
				(width 0.127)
				(type default)
			)
			(layer "F.SilkS")
		)
		(fp_poly
			(pts
				(xy 1.255601 0.656399) (xy -1.255601 0.656399) (xy -1.255601 -0.6564) (xy 1.255601 -0.6564)
			)
			(stroke
				(width 0)
				(type default)
			)
			(fill no)
			(layer "F.CrtYd")
		)
		(fp_line
			(start 0.800001 -0.399999)
			(end -0.800001 -0.399999)
			(stroke
				(width 0.1)
				(type default)
			)
			(layer "F.Fab")
		)
		(fp_line
			(start -0.800001 -0.399999)
			(end -0.800001 0.399999)
			(stroke
				(width 0.1)
				(type default)
			)
			(layer "F.Fab")
		)
		(fp_line
			(start 0.800001 0.399999)
			(end 0.800001 -0.399999)
			(stroke
				(width 0.1)
				(type default)
			)
			(layer "F.Fab")
		)
		(fp_line
			(start -0.800001 0.399999)
			(end 0.800001 0.399999)
			(stroke
				(width 0.1)
				(type default)
			)
			(layer "F.Fab")
		)
		(pad "1" smd rect
			(at -0.650001 0 90)
			(size 0.7112 0.8128)
			(layers "F.Cu" "F.Mask" "F.Paste")
			(net "GND")
		)
		(pad "2" smd rect
			(at 0.650001 0 270)
			(size 0.7112 0.8128)
			(layers "F.Cu" "F.Mask" "F.Paste")
			(net "BLADE_MATED_B2_N<0>")
		)
	)
	(footprint ""
		(layer "F.Cu")
		(at -316.25 39.010001 180)
		(property "Reference" "J8"
			(at 8.91572 -8.726759 0)
			(unlocked yes)
			(layer "F.SilkS")
			(effects
				(font
					(size 0.762 0.5334)
					(thickness 0.1016)
				)
			)
		)
		(property "Value" ""
			(at 0 0 180)
			(layer "F.Fab")
			(effects
				(font
					(size 1.27 1.27)
				)
			)
		)
		(duplicate_pad_numbers_are_jumpers no)
		(fp_line
			(start 9.1 5.750001)
			(end 9.1 4.093401)
			(stroke
				(width 0.127)
				(type default)
			)
			(layer "F.SilkS")
		)
		(fp_line
			(start 9.1 -5.750001)
			(end 9.1 1.507599)
			(stroke
				(width 0.127)
				(type default)
			)
			(layer "F.SilkS")
		)
		(fp_line
			(start 7.5211 -5.750001)
			(end 9.1 -5.750001)
			(stroke
				(width 0.127)
				(type default)
			)
			(layer "F.SilkS")
		)
		(fp_line
			(start -8.029301 -5.750001)
			(end -9.1 -5.750001)
			(stroke
				(width 0.127)
				(type default)
			)
			(layer "F.SilkS")
		)
		(fp_line
			(start -9.1 5.750001)
			(end 9.1 5.750001)
			(stroke
				(width 0.127)
				(type default)
			)
			(layer "F.SilkS")
		)
		(fp_line
			(start -9.1 4.0408)
			(end -9.1 5.750001)
			(stroke
				(width 0.127)
				(type default)
			)
			(layer "F.SilkS")
		)
		(fp_line
			(start -9.1 -5.750001)
			(end -9.1 1.446101)
			(stroke
				(width 0.127)
				(type default)
			)
			(layer "F.SilkS")
		)
		(fp_rect
			(start -9.608 6.258001)
			(end 9.607999 -6.258002)
			(stroke
				(width 0)
				(type default)
			)
			(fill no)
			(layer "F.CrtYd")
		)
		(fp_line
			(start 9.1 5.750001)
			(end 9.1 -5.750001)
			(stroke
				(width 0.1)
				(type default)
			)
			(layer "F.Fab")
		)
		(fp_line
			(start 9.1 -5.750001)
			(end -9.1 -5.750001)
			(stroke
				(width 0.1)
				(type default)
			)
			(layer "F.Fab")
		)
		(fp_line
			(start -9.1 5.750001)
			(end 9.1 5.750001)
			(stroke
				(width 0.1)
				(type default)
			)
			(layer "F.Fab")
		)
		(fp_line
			(start -9.1 -5.750001)
			(end -9.1 5.750001)
			(stroke
				(width 0.1)
				(type default)
			)
			(layer "F.Fab")
		)
		(fp_text user "19"
			(at 8.41026 -0.309199 0)
			(unlocked yes)
			(layer "F.SilkS")
			(effects
				(font
					(size 0.762 0.5334)
					(thickness 0.1016)
				)
			)
		)
		(fp_text user "20"
			(at 8.0445 -3.941399 0)
			(unlocked yes)
			(layer "F.SilkS")
			(effects
				(font
					(size 0.762 0.5334)
					(thickness 0.1016)
				)
			)
		)
		(fp_text user "*"
			(at -8.06926 -0.909909 0)
			(unlocked yes)
			(layer "F.SilkS")
			(effects
				(font
					(size 0.381 0.381)
					(thickness 0.381)
				)
			)
		)
		(pad "" np_thru_hole circle
			(at -8.400001 2.849999 270)
			(size 1.27 1.27)
			(drill 1.5494)
			(layers "*.Cu" "*.Mask")
		)
		(pad "" np_thru_hole circle
			(at 8.400001 2.849999 270)
			(size 1.27 1.27)
			(drill 1.5494)
			(layers "*.Cu" "*.Mask")
		)
		(pad "1" smd oval
			(at -7.000001 -2.33 180)
			(size 0.3556 1.8034)
			(layers "F.Cu" "F.Mask" "F.Paste")
			(net "GND")
		)
		(pad "2" smd oval
			(at -6.2 -2.33 180)
			(size 0.3556 1.8034)
			(layers "F.Cu" "F.Mask" "F.Paste")
			(net "ETH40G_B1_TX1N")
		)
		(pad "3" smd oval
			(at -5.399999 -2.33 180)
			(size 0.3556 1.8034)
			(layers "F.Cu" "F.Mask" "F.Paste")
			(net "ETH40G_B1_TX1P")
		)
		(pad "4" smd oval
			(at -4.600001 -2.33 180)
			(size 0.3556 1.8034)
			(layers "F.Cu" "F.Mask" "F.Paste")
			(net "GND")
		)
		(pad "5" smd oval
			(at -3.8 -2.33 180)
			(size 0.3556 1.8034)
			(layers "F.Cu" "F.Mask" "F.Paste")
			(net "ETH40G_B1_TX3N")
		)
		(pad "6" smd oval
			(at -2.999999 -2.33 180)
			(size 0.3556 1.8034)
			(layers "F.Cu" "F.Mask" "F.Paste")
			(net "ETH40G_B1_TX3P")
		)
		(pad "7" smd oval
			(at -2.200001 -2.33 180)
			(size 0.3556 1.8034)
			(layers "F.Cu" "F.Mask" "F.Paste")
			(net "GND")
		)
		(pad "8" smd oval
			(at -1.4 -2.33 180)
			(size 0.3556 1.8034)
			(layers "F.Cu" "F.Mask" "F.Paste")
			(net "ETH40G_B1_MODSEL_N")
		)
		(pad "9" smd oval
			(at -0.599999 -2.33 180)
			(size 0.3556 1.8034)
			(layers "F.Cu" "F.Mask" "F.Paste")
			(net "ETH40G_B1_RESET_N")
		)
		(pad "10" smd oval
			(at 0.2 -2.33 180)
			(size 0.3556 1.8034)
			(layers "F.Cu" "F.Mask" "F.Paste")
			(net "P3V3_40G_B1_VCC_RX")
		)
		(pad "11" smd oval
			(at 1.000001 -2.33 180)
			(size 0.3556 1.8034)
			(layers "F.Cu" "F.Mask" "F.Paste")
			(net "ETH40G_B1_SCL")
		)
		(pad "12" smd oval
			(at 1.799999 -2.33 180)
			(size 0.3556 1.8034)
			(layers "F.Cu" "F.Mask" "F.Paste")
			(net "ETH40G_B1_SDA")
		)
		(pad "13" smd oval
			(at 2.6 -2.33 180)
			(size 0.3556 1.8034)
			(layers "F.Cu" "F.Mask" "F.Paste")
			(net "GND")
		)
		(pad "14" smd oval
			(at 3.400001 -2.33 180)
			(size 0.3556 1.8034)
			(layers "F.Cu" "F.Mask" "F.Paste")
			(net "ETH40G_B1_RX2P")
		)
		(pad "15" smd oval
			(at 4.199999 -2.33 180)
			(size 0.3556 1.8034)
			(layers "F.Cu" "F.Mask" "F.Paste")
			(net "ETH40G_B1_RX2N")
		)
		(pad "16" smd oval
			(at 5 -2.33 180)
			(size 0.3556 1.8034)
			(layers "F.Cu" "F.Mask" "F.Paste")
			(net "GND")
		)
		(pad "17" smd oval
			(at 5.800001 -2.33 180)
			(size 0.3556 1.8034)
			(layers "F.Cu" "F.Mask" "F.Paste")
			(net "ETH40G_B1_RX0P")
		)
		(pad "18" smd oval
			(at 6.6 -2.33 180)
			(size 0.3556 1.8034)
			(layers "F.Cu" "F.Mask" "F.Paste")
			(net "ETH40G_B1_RX0N")
		)
		(pad "19" smd oval
			(at 7.4 -2.33 180)
			(size 0.3556 1.8034)
			(layers "F.Cu" "F.Mask" "F.Paste")
			(net "GND")
		)
		(pad "20" smd oval
			(at 7.000001 -4.830001 180)
			(size 0.3556 1.8034)
			(layers "F.Cu" "F.Mask" "F.Paste")
			(net "GND")
		)
		(pad "21" smd oval
			(at 6.2 -4.830001 180)
			(size 0.3556 1.8034)
			(layers "F.Cu" "F.Mask" "F.Paste")
			(net "ETH40G_B1_RX1N")
		)
		(pad "22" smd oval
			(at 5.399999 -4.830001 180)
			(size 0.3556 1.8034)
			(layers "F.Cu" "F.Mask" "F.Paste")
			(net "ETH40G_B1_RX1P")
		)
		(pad "23" smd oval
			(at 4.600001 -4.830001 180)
			(size 0.3556 1.8034)
			(layers "F.Cu" "F.Mask" "F.Paste")
			(net "GND")
		)
		(pad "24" smd oval
			(at 3.8 -4.830001 180)
			(size 0.3556 1.8034)
			(layers "F.Cu" "F.Mask" "F.Paste")
			(net "ETH40G_B1_RX3N")
		)
		(pad "25" smd oval
			(at 2.999999 -4.830001 180)
			(size 0.3556 1.8034)
			(layers "F.Cu" "F.Mask" "F.Paste")
			(net "ETH40G_B1_RX3P")
		)
		(pad "26" smd oval
			(at 2.200001 -4.830001 180)
			(size 0.3556 1.8034)
			(layers "F.Cu" "F.Mask" "F.Paste")
			(net "GND")
		)
		(pad "27" smd oval
			(at 1.4 -4.830001 180)
			(size 0.3556 1.8034)
			(layers "F.Cu" "F.Mask" "F.Paste")
			(net "ETH40G_B1_MODPRS_N")
		)
		(pad "28" smd oval
			(at 0.599999 -4.830001 180)
			(size 0.3556 1.8034)
			(layers "F.Cu" "F.Mask" "F.Paste")
			(net "ETH40G_B1_INT_N")
		)
		(pad "29" smd oval
			(at -0.2 -4.830001 180)
			(size 0.3556 1.8034)
			(layers "F.Cu" "F.Mask" "F.Paste")
			(net "P3V3_40G_B1_VCC_TX")
		)
		(pad "30" smd oval
			(at -1.000001 -4.830001 180)
			(size 0.3556 1.8034)
			(layers "F.Cu" "F.Mask" "F.Paste")
			(net "P3V3_40G_B1_VCC1")
		)
		(pad "31" smd oval
			(at -1.799999 -4.830001 180)
			(size 0.3556 1.8034)
			(layers "F.Cu" "F.Mask" "F.Paste")
			(net "ETH40G_B1_LPMODE")
		)
		(pad "32" smd oval
			(at -2.6 -4.830001 180)
			(size 0.3556 1.8034)
			(layers "F.Cu" "F.Mask" "F.Paste")
			(net "GND")
		)
		(pad "33" smd oval
			(at -3.400001 -4.830001 180)
			(size 0.3556 1.8034)
			(layers "F.Cu" "F.Mask" "F.Paste")
			(net "ETH40G_B1_TX2P")
		)
		(pad "34" smd oval
			(at -4.199999 -4.830001 180)
			(size 0.3556 1.8034)
			(layers "F.Cu" "F.Mask" "F.Paste")
			(net "ETH40G_B1_TX2N")
		)
		(pad "35" smd oval
			(at -5 -4.830001 180)
			(size 0.3556 1.8034)
			(layers "F.Cu" "F.Mask" "F.Paste")
			(net "GND")
		)
		(pad "36" smd oval
			(at -5.800001 -4.830001 180)
			(size 0.3556 1.8034)
			(layers "F.Cu" "F.Mask" "F.Paste")
			(net "ETH40G_B1_TX0P")
		)
		(pad "37" smd oval
			(at -6.6 -4.830001 180)
			(size 0.3556 1.8034)
			(layers "F.Cu" "F.Mask" "F.Paste")
			(net "ETH40G_B1_TX0N")
		)
		(pad "38" smd oval
			(at -7.4 -4.830001 180)
			(size 0.3556 1.8034)
			(layers "F.Cu" "F.Mask" "F.Paste")
			(net "GND")
		)
		(zone
			(layers "F.Cu" "B.Cu" "In1.Cu" "In2.Cu" "In3.Cu" "In4.Cu" "In5.Cu" "In6.Cu")
			(hatch none 0.5)
			(connect_pads
				(clearance 0)
			)
			(min_thickness 0.25)
			(keepout
				(tracks not_allowed)
				(vias allowed)
				(pads allowed)
				(copperpour not_allowed)
				(footprints allowed)
			)
			(placement
				(enabled no)
				(sheetname "")
			)
			(fill
				(thermal_gap 0.5)
				(thermal_bridge_width 0.5)
				(island_removal_mode 0)
			)
			(polygon
				(pts
					(arc
						(start -325.805701 36.160001)
						(mid -323.494301 36.160001)
						(end -325.805701 36.160001)
					)
				)
			)
		)
		(zone
			(layers "F.Cu" "B.Cu" "In1.Cu" "In2.Cu" "In3.Cu" "In4.Cu" "In5.Cu" "In6.Cu")
			(hatch none 0.5)
			(connect_pads
				(clearance 0)
			)
			(min_thickness 0.25)
			(keepout
				(tracks not_allowed)
				(vias allowed)
				(pads allowed)
				(copperpour not_allowed)
				(footprints allowed)
			)
			(placement
				(enabled no)
				(sheetname "")
			)
			(fill
				(thermal_gap 0.5)
				(thermal_bridge_width 0.5)
				(island_removal_mode 0)
			)
			(polygon
				(pts
					(arc
						(start -309.005699 36.160001)
						(mid -306.694299 36.160001)
						(end -309.005699 36.160001)
					)
				)
			)
		)
	)
	(footprint ""
		(layer "F.Cu")
		(at -300.99 11.811)
		(property "Reference" "R80"
			(at -3.175 0.0381 0)
			(unlocked yes)
			(layer "F.SilkS")
			(effects
				(font
					(size 0.762 0.5334)
					(thickness 0.1016)
				)
			)
		)
		(property "Value" ""
			(at 0 0 0)
			(layer "F.Fab")
			(effects
				(font
					(size 1.27 1.27)
				)
			)
		)
		(duplicate_pad_numbers_are_jumpers no)
		(fp_line
			(start 0 -0.381)
			(end 0 0.381)
			(stroke
				(width 0.127)
				(type default)
			)
			(layer "F.SilkS")
		)
		(fp_poly
			(pts
				(xy 1.255601 0.6564) (xy -1.255601 0.6564) (xy -1.255601 -0.656399) (xy 1.255601 -0.656399)
			)
			(stroke
				(width 0)
				(type default)
			)
			(fill no)
			(layer "F.CrtYd")
		)
		(fp_line
			(start -0.800001 -0.399999)
			(end -0.800001 0.399999)
			(stroke
				(width 0.1)
				(type default)
			)
			(layer "F.Fab")
		)
		(fp_line
			(start -0.800001 0.399999)
			(end 0.800001 0.399999)
			(stroke
				(width 0.1)
				(type default)
			)
			(layer "F.Fab")
		)
		(fp_line
			(start 0.800001 -0.399999)
			(end -0.800001 -0.399999)
			(stroke
				(width 0.1)
				(type default)
			)
			(layer "F.Fab")
		)
		(fp_line
			(start 0.800001 0.399999)
			(end 0.800001 -0.399999)
			(stroke
				(width 0.1)
				(type default)
			)
			(layer "F.Fab")
		)
		(pad "1" smd rect
			(at -0.650001 0)
			(size 0.7112 0.8128)
			(layers "F.Cu" "F.Mask" "F.Paste")
			(net "ETH40G_B1_MODPRS_N")
		)
		(pad "2" smd rect
			(at 0.650001 0 180)
			(size 0.7112 0.8128)
			(layers "F.Cu" "F.Mask" "F.Paste")
			(net "ETH40G_B1_PRES_N")
		)
	)
	(footprint ""
		(layer "F.Cu")
		(at -154.079999 30.959999 90)
		(property "Reference" "J14"
			(at 17.078899 0.028999 0)
			(unlocked yes)
			(layer "F.SilkS")
			(effects
				(font
					(size 0.762 0.5334)
					(thickness 0.1016)
				)
			)
		)
		(property "Value" ""
			(at 0 0 90)
			(layer "F.Fab")
			(effects
				(font
					(size 1.27 1.27)
				)
			)
		)
		(duplicate_pad_numbers_are_jumpers no)
		(fp_line
			(start 16.0274 -5.3721)
			(end -16.0274 -5.3721)
			(stroke
				(width 0.127)
				(type default)
			)
			(layer "F.SilkS")
		)
		(fp_line
			(start -16.0274 -5.3721)
			(end -16.0274 5.3721)
			(stroke
				(width 0.127)
				(type default)
			)
			(layer "F.SilkS")
		)
		(fp_line
			(start 16.0274 5.3721)
			(end 16.0274 -5.3721)
			(stroke
				(width 0.127)
				(type default)
			)
			(layer "F.SilkS")
		)
		(fp_line
			(start -16.0274 5.3721)
			(end 16.0274 5.3721)
			(stroke
				(width 0.127)
				(type default)
			)
			(layer "F.SilkS")
		)
		(fp_rect
			(start -16.5354 5.8801)
			(end 16.5354 -5.8801)
			(stroke
				(width 0)
				(type default)
			)
			(fill no)
			(layer "F.CrtYd")
		)
		(fp_line
			(start 16.0274 -5.3721)
			(end -16.0274 -5.3721)
			(stroke
				(width 0.1)
				(type default)
			)
			(layer "F.Fab")
		)
		(fp_line
			(start -16.0274 -5.3721)
			(end -16.0274 5.3721)
			(stroke
				(width 0.1)
				(type default)
			)
			(layer "F.Fab")
		)
		(fp_line
			(start 16.0274 5.3721)
			(end 16.0274 -5.3721)
			(stroke
				(width 0.1)
				(type default)
			)
			(layer "F.Fab")
		)
		(fp_line
			(start -16.0274 5.3721)
			(end 16.0274 5.3721)
			(stroke
				(width 0.1)
				(type default)
			)
			(layer "F.Fab")
		)
		(fp_text user "153"
			(at 12.125899 -6.702001 0)
			(unlocked yes)
			(layer "F.SilkS")
			(effects
				(font
					(size 0.762 0.5334)
					(thickness 0.1016)
				)
			)
		)
		(fp_text user "*"
			(at -12.065 -6.17855 270)
			(unlocked yes)
			(layer "F.SilkS")
			(effects
				(font
					(size 0.381 0.381)
					(thickness 0.381)
				)
			)
		)
		(fp_text user "8"
			(at -12.385101 6.251999 0)
			(unlocked yes)
			(layer "F.SilkS")
			(effects
				(font
					(size 0.762 0.5334)
					(thickness 0.1016)
				)
			)
		)
		(fp_text user "160"
			(at 12.1539 6.477 0)
			(unlocked yes)
			(layer "F.SilkS")
			(effects
				(font
					(size 0.762 0.5334)
					(thickness 0.1016)
				)
			)
		)
		(pad "" np_thru_hole circle
			(at -14.4907 -3.048 90)
			(size 0.508 0.508)
			(drill 1.27)
			(layers "*.Cu" "*.Mask")
		)
		(pad "" np_thru_hole circle
			(at 14.4907 0 90)
			(size 0.508 0.508)
			(drill 1.27)
			(layers "*.Cu" "*.Mask")
		)
		(pad "1" smd circle
			(at -12.065 -4.445 90)
			(size 0.635 0.635)
			(layers "F.Cu" "F.Mask" "F.Paste")
			(net "GND")
		)
		(pad "2" smd circle
			(at -12.065 -3.175 90)
			(size 0.635 0.635)
			(layers "F.Cu" "F.Mask" "F.Paste")
			(net "PCIE_T2B_B2_RX_DP<7>")
		)
		(pad "3" smd circle
			(at -12.065 -1.905 90)
			(size 0.635 0.635)
			(layers "F.Cu" "F.Mask" "F.Paste")
			(net "GND")
		)
		(pad "4" smd circle
			(at -12.065 -0.635 90)
			(size 0.635 0.635)
			(layers "F.Cu" "F.Mask" "F.Paste")
			(net "PCIE_T2B_B2_RX_DP<15>")
		)
		(pad "5" smd circle
			(at -12.065 0.635 90)
			(size 0.635 0.635)
			(layers "F.Cu" "F.Mask" "F.Paste")
			(net "GND")
		)
		(pad "6" smd circle
			(at -12.065 1.905 90)
			(size 0.635 0.635)
			(layers "F.Cu" "F.Mask" "F.Paste")
			(net "PCIE_B2T_B2_TX_DP<7>")
		)
		(pad "7" smd circle
			(at -12.065 3.175 90)
			(size 0.635 0.635)
			(layers "F.Cu" "F.Mask" "F.Paste")
			(net "GND")
		)
		(pad "8" smd circle
			(at -12.065 4.445 90)
			(size 0.635 0.635)
			(layers "F.Cu" "F.Mask" "F.Paste")
			(net "PCIE_B2T_B2_TX_DP<15>")
		)
		(pad "9" smd circle
			(at -10.795 -4.445 90)
			(size 0.635 0.635)
			(layers "F.Cu" "F.Mask" "F.Paste")
			(net "GND")
		)
		(pad "10" smd circle
			(at -10.795 -3.175 90)
			(size 0.635 0.635)
			(layers "F.Cu" "F.Mask" "F.Paste")
			(net "PCIE_T2B_B2_RX_DN<7>")
		)
		(pad "11" smd circle
			(at -10.795 -1.905 90)
			(size 0.635 0.635)
			(layers "F.Cu" "F.Mask" "F.Paste")
			(net "GND")
		)
		(pad "12" smd circle
			(at -10.795 -0.635 90)
			(size 0.635 0.635)
			(layers "F.Cu" "F.Mask" "F.Paste")
			(net "PCIE_T2B_B2_RX_DN<15>")
		)
		(pad "13" smd circle
			(at -10.795 0.635 90)
			(size 0.635 0.635)
			(layers "F.Cu" "F.Mask" "F.Paste")
			(net "GND")
		)
		(pad "14" smd circle
			(at -10.795 1.905 90)
			(size 0.635 0.635)
			(layers "F.Cu" "F.Mask" "F.Paste")
			(net "PCIE_B2T_B2_TX_DN<7>")
		)
		(pad "15" smd circle
			(at -10.795 3.175 90)
			(size 0.635 0.635)
			(layers "F.Cu" "F.Mask" "F.Paste")
			(net "GND")
		)
		(pad "16" smd circle
			(at -10.795 4.445 90)
			(size 0.635 0.635)
			(layers "F.Cu" "F.Mask" "F.Paste")
			(net "PCIE_B2T_B2_TX_DN<15>")
		)
		(pad "17" smd circle
			(at -9.525 -4.445 90)
			(size 0.635 0.635)
			(layers "F.Cu" "F.Mask" "F.Paste")
			(net "PCIE_T2B_B2_RX_DP<6>")
		)
		(pad "18" smd circle
			(at -9.525 -3.175 90)
			(size 0.635 0.635)
			(layers "F.Cu" "F.Mask" "F.Paste")
			(net "GND")
		)
		(pad "19" smd circle
			(at -9.525 -1.905 90)
			(size 0.635 0.635)
			(layers "F.Cu" "F.Mask" "F.Paste")
			(net "PCIE_T2B_B2_RX_DP<14>")
		)
		(pad "20" smd circle
			(at -9.525 -0.635 90)
			(size 0.635 0.635)
			(layers "F.Cu" "F.Mask" "F.Paste")
			(net "GND")
		)
		(pad "21" smd circle
			(at -9.525 0.635 90)
			(size 0.635 0.635)
			(layers "F.Cu" "F.Mask" "F.Paste")
			(net "PCIE_B2T_B2_TX_DP<6>")
		)
		(pad "22" smd circle
			(at -9.525 1.905 90)
			(size 0.635 0.635)
			(layers "F.Cu" "F.Mask" "F.Paste")
			(net "GND")
		)
		(pad "23" smd circle
			(at -9.525 3.175 90)
			(size 0.635 0.635)
			(layers "F.Cu" "F.Mask" "F.Paste")
			(net "PCIE_B2T_B2_TX_DP<14>")
		)
		(pad "24" smd circle
			(at -9.525 4.445 90)
			(size 0.635 0.635)
			(layers "F.Cu" "F.Mask" "F.Paste")
			(net "GND")
		)
		(pad "25" smd circle
			(at -8.255 -4.445 90)
			(size 0.635 0.635)
			(layers "F.Cu" "F.Mask" "F.Paste")
			(net "PCIE_T2B_B2_RX_DN<6>")
		)
		(pad "26" smd circle
			(at -8.255 -3.175 90)
			(size 0.635 0.635)
			(layers "F.Cu" "F.Mask" "F.Paste")
			(net "GND")
		)
		(pad "27" smd circle
			(at -8.255 -1.905 90)
			(size 0.635 0.635)
			(layers "F.Cu" "F.Mask" "F.Paste")
			(net "PCIE_T2B_B2_RX_DN<14>")
		)
		(pad "28" smd circle
			(at -8.255 -0.635 90)
			(size 0.635 0.635)
			(layers "F.Cu" "F.Mask" "F.Paste")
			(net "GND")
		)
		(pad "29" smd circle
			(at -8.255 0.635 90)
			(size 0.635 0.635)
			(layers "F.Cu" "F.Mask" "F.Paste")
			(net "PCIE_B2T_B2_TX_DN<6>")
		)
		(pad "30" smd circle
			(at -8.255 1.905 90)
			(size 0.635 0.635)
			(layers "F.Cu" "F.Mask" "F.Paste")
			(net "GND")
		)
		(pad "31" smd circle
			(at -8.255 3.175 90)
			(size 0.635 0.635)
			(layers "F.Cu" "F.Mask" "F.Paste")
			(net "PCIE_B2T_B2_TX_DN<14>")
		)
		(pad "32" smd circle
			(at -8.255 4.445 90)
			(size 0.635 0.635)
			(layers "F.Cu" "F.Mask" "F.Paste")
			(net "GND")
		)
		(pad "33" smd circle
			(at -6.985 -4.445 90)
			(size 0.635 0.635)
			(layers "F.Cu" "F.Mask" "F.Paste")
			(net "GND")
		)
		(pad "34" smd circle
			(at -6.985 -3.175 90)
			(size 0.635 0.635)
			(layers "F.Cu" "F.Mask" "F.Paste")
			(net "PCIE_T2B_B2_RX_DP<5>")
		)
		(pad "35" smd circle
			(at -6.985 -1.905 90)
			(size 0.635 0.635)
			(layers "F.Cu" "F.Mask" "F.Paste")
			(net "GND")
		)
		(pad "36" smd circle
			(at -6.985 -0.635 90)
			(size 0.635 0.635)
			(layers "F.Cu" "F.Mask" "F.Paste")
			(net "PCIE_T2B_B2_RX_DP<13>")
		)
		(pad "37" smd circle
			(at -6.985 0.635 90)
			(size 0.635 0.635)
			(layers "F.Cu" "F.Mask" "F.Paste")
			(net "GND")
		)
		(pad "38" smd circle
			(at -6.985 1.905 90)
			(size 0.635 0.635)
			(layers "F.Cu" "F.Mask" "F.Paste")
			(net "PCIE_B2T_B2_TX_DP<5>")
		)
		(pad "39" smd circle
			(at -6.985 3.175 90)
			(size 0.635 0.635)
			(layers "F.Cu" "F.Mask" "F.Paste")
			(net "GND")
		)
		(pad "40" smd circle
			(at -6.985 4.445 90)
			(size 0.635 0.635)
			(layers "F.Cu" "F.Mask" "F.Paste")
			(net "PCIE_B2T_B2_TX_DP<13>")
		)
		(pad "41" smd circle
			(at -5.715 -4.445 90)
			(size 0.635 0.635)
			(layers "F.Cu" "F.Mask" "F.Paste")
			(net "GND")
		)
		(pad "42" smd circle
			(at -5.715 -3.175 90)
			(size 0.635 0.635)
			(layers "F.Cu" "F.Mask" "F.Paste")
			(net "PCIE_T2B_B2_RX_DN<5>")
		)
		(pad "43" smd circle
			(at -5.715 -1.905 90)
			(size 0.635 0.635)
			(layers "F.Cu" "F.Mask" "F.Paste")
			(net "GND")
		)
		(pad "44" smd circle
			(at -5.715 -0.635 90)
			(size 0.635 0.635)
			(layers "F.Cu" "F.Mask" "F.Paste")
			(net "PCIE_T2B_B2_RX_DN<13>")
		)
		(pad "45" smd circle
			(at -5.715 0.635 90)
			(size 0.635 0.635)
			(layers "F.Cu" "F.Mask" "F.Paste")
			(net "GND")
		)
		(pad "46" smd circle
			(at -5.715 1.905 90)
			(size 0.635 0.635)
			(layers "F.Cu" "F.Mask" "F.Paste")
			(net "PCIE_B2T_B2_TX_DN<5>")
		)
		(pad "47" smd circle
			(at -5.715 3.175 90)
			(size 0.635 0.635)
			(layers "F.Cu" "F.Mask" "F.Paste")
			(net "GND")
		)
		(pad "48" smd circle
			(at -5.715 4.445 90)
			(size 0.635 0.635)
			(layers "F.Cu" "F.Mask" "F.Paste")
			(net "PCIE_B2T_B2_TX_DN<13>")
		)
		(pad "49" smd circle
			(at -4.445 -4.445 90)
			(size 0.635 0.635)
			(layers "F.Cu" "F.Mask" "F.Paste")
			(net "PCIE_T2B_B2_RX_DP<4>")
		)
		(pad "50" smd circle
			(at -4.445 -3.175 90)
			(size 0.635 0.635)
			(layers "F.Cu" "F.Mask" "F.Paste")
			(net "GND")
		)
		(pad "51" smd circle
			(at -4.445 -1.905 90)
			(size 0.635 0.635)
			(layers "F.Cu" "F.Mask" "F.Paste")
			(net "PCIE_T2B_B2_RX_DP<12>")
		)
		(pad "52" smd circle
			(at -4.445 -0.635 90)
			(size 0.635 0.635)
			(layers "F.Cu" "F.Mask" "F.Paste")
			(net "GND")
		)
		(pad "53" smd circle
			(at -4.445 0.635 90)
			(size 0.635 0.635)
			(layers "F.Cu" "F.Mask" "F.Paste")
			(net "PCIE_B2T_B2_TX_DP<4>")
		)
		(pad "54" smd circle
			(at -4.445 1.905 90)
			(size 0.635 0.635)
			(layers "F.Cu" "F.Mask" "F.Paste")
			(net "GND")
		)
		(pad "55" smd circle
			(at -4.445 3.175 90)
			(size 0.635 0.635)
			(layers "F.Cu" "F.Mask" "F.Paste")
			(net "PCIE_B2T_B2_TX_DP<12>")
		)
		(pad "56" smd circle
			(at -4.445 4.445 90)
			(size 0.635 0.635)
			(layers "F.Cu" "F.Mask" "F.Paste")
			(net "GND")
		)
		(pad "57" smd circle
			(at -3.175 -4.445 90)
			(size 0.635 0.635)
			(layers "F.Cu" "F.Mask" "F.Paste")
			(net "PCIE_T2B_B2_RX_DN<4>")
		)
		(pad "58" smd circle
			(at -3.175 -3.175 90)
			(size 0.635 0.635)
			(layers "F.Cu" "F.Mask" "F.Paste")
			(net "GND")
		)
		(pad "59" smd circle
			(at -3.175 -1.905 90)
			(size 0.635 0.635)
			(layers "F.Cu" "F.Mask" "F.Paste")
			(net "PCIE_T2B_B2_RX_DN<12>")
		)
		(pad "60" smd circle
			(at -3.175 -0.635 90)
			(size 0.635 0.635)
			(layers "F.Cu" "F.Mask" "F.Paste")
			(net "GND")
		)
		(pad "61" smd circle
			(at -3.175 0.635 90)
			(size 0.635 0.635)
			(layers "F.Cu" "F.Mask" "F.Paste")
			(net "PCIE_B2T_B2_TX_DN<4>")
		)
		(pad "62" smd circle
			(at -3.175 1.905 90)
			(size 0.635 0.635)
			(layers "F.Cu" "F.Mask" "F.Paste")
			(net "GND")
		)
		(pad "63" smd circle
			(at -3.175 3.175 90)
			(size 0.635 0.635)
			(layers "F.Cu" "F.Mask" "F.Paste")
			(net "PCIE_B2T_B2_TX_DN<12>")
		)
		(pad "64" smd circle
			(at -3.175 4.445 90)
			(size 0.635 0.635)
			(layers "F.Cu" "F.Mask" "F.Paste")
			(net "GND")
		)
		(pad "65" smd circle
			(at -1.905 -4.445 90)
			(size 0.635 0.635)
			(layers "F.Cu" "F.Mask" "F.Paste")
			(net "GND")
		)
		(pad "66" smd circle
			(at -1.905 -3.175 90)
			(size 0.635 0.635)
			(layers "F.Cu" "F.Mask" "F.Paste")
			(net "PCIE_T2B_B2_RX_DP<3>")
		)
		(pad "67" smd circle
			(at -1.905 -1.905 90)
			(size 0.635 0.635)
			(layers "F.Cu" "F.Mask" "F.Paste")
			(net "GND")
		)
		(pad "68" smd circle
			(at -1.905 -0.635 90)
			(size 0.635 0.635)
			(layers "F.Cu" "F.Mask" "F.Paste")
			(net "PCIE_T2B_B2_RX_DP<11>")
		)
		(pad "69" smd circle
			(at -1.905 0.635 90)
			(size 0.635 0.635)
			(layers "F.Cu" "F.Mask" "F.Paste")
			(net "GND")
		)
		(pad "70" smd circle
			(at -1.905 1.905 90)
			(size 0.635 0.635)
			(layers "F.Cu" "F.Mask" "F.Paste")
			(net "PCIE_B2T_B2_TX_DP<3>")
		)
		(pad "71" smd circle
			(at -1.905 3.175 90)
			(size 0.635 0.635)
			(layers "F.Cu" "F.Mask" "F.Paste")
			(net "GND")
		)
		(pad "72" smd circle
			(at -1.905 4.445 90)
			(size 0.635 0.635)
			(layers "F.Cu" "F.Mask" "F.Paste")
			(net "PCIE_B2T_B2_TX_DP<11>")
		)
		(pad "73" smd circle
			(at -0.635 -4.445 90)
			(size 0.635 0.635)
			(layers "F.Cu" "F.Mask" "F.Paste")
			(net "GND")
		)
		(pad "74" smd circle
			(at -0.635 -3.175 90)
			(size 0.635 0.635)
			(layers "F.Cu" "F.Mask" "F.Paste")
			(net "PCIE_T2B_B2_RX_DN<3>")
		)
		(pad "75" smd circle
			(at -0.635 -1.905 90)
			(size 0.635 0.635)
			(layers "F.Cu" "F.Mask" "F.Paste")
			(net "GND")
		)
		(pad "76" smd circle
			(at -0.635 -0.635 90)
			(size 0.635 0.635)
			(layers "F.Cu" "F.Mask" "F.Paste")
			(net "PCIE_T2B_B2_RX_DN<11>")
		)
		(pad "77" smd circle
			(at -0.635 0.635 90)
			(size 0.635 0.635)
			(layers "F.Cu" "F.Mask" "F.Paste")
			(net "GND")
		)
		(pad "78" smd circle
			(at -0.635 1.905 90)
			(size 0.635 0.635)
			(layers "F.Cu" "F.Mask" "F.Paste")
			(net "PCIE_B2T_B2_TX_DN<3>")
		)
		(pad "79" smd circle
			(at -0.635 3.175 90)
			(size 0.635 0.635)
			(layers "F.Cu" "F.Mask" "F.Paste")
			(net "GND")
		)
		(pad "80" smd circle
			(at -0.635 4.445 90)
			(size 0.635 0.635)
			(layers "F.Cu" "F.Mask" "F.Paste")
			(net "PCIE_B2T_B2_TX_DN<11>")
		)
		(pad "81" smd circle
			(at 0.635 -4.445 90)
			(size 0.635 0.635)
			(layers "F.Cu" "F.Mask" "F.Paste")
			(net "PCIE_T2B_B2_RX_DP<2>")
		)
		(pad "82" smd circle
			(at 0.635 -3.175 90)
			(size 0.635 0.635)
			(layers "F.Cu" "F.Mask" "F.Paste")
			(net "GND")
		)
		(pad "83" smd circle
			(at 0.635 -1.905 90)
			(size 0.635 0.635)
			(layers "F.Cu" "F.Mask" "F.Paste")
			(net "PCIE_T2B_B2_RX_DP<10>")
		)
		(pad "84" smd circle
			(at 0.635 -0.635 90)
			(size 0.635 0.635)
			(layers "F.Cu" "F.Mask" "F.Paste")
			(net "GND")
		)
		(pad "85" smd circle
			(at 0.635 0.635 90)
			(size 0.635 0.635)
			(layers "F.Cu" "F.Mask" "F.Paste")
			(net "PCIE_B2T_B2_TX_DP<2>")
		)
		(pad "86" smd circle
			(at 0.635 1.905 90)
			(size 0.635 0.635)
			(layers "F.Cu" "F.Mask" "F.Paste")
			(net "GND")
		)
		(pad "87" smd circle
			(at 0.635 3.175 90)
			(size 0.635 0.635)
			(layers "F.Cu" "F.Mask" "F.Paste")
			(net "PCIE_B2T_B2_TX_DP<10>")
		)
		(pad "88" smd circle
			(at 0.635 4.445 90)
			(size 0.635 0.635)
			(layers "F.Cu" "F.Mask" "F.Paste")
			(net "GND")
		)
		(pad "89" smd circle
			(at 1.905 -4.445 90)
			(size 0.635 0.635)
			(layers "F.Cu" "F.Mask" "F.Paste")
			(net "PCIE_T2B_B2_RX_DN<2>")
		)
		(pad "90" smd circle
			(at 1.905 -3.175 90)
			(size 0.635 0.635)
			(layers "F.Cu" "F.Mask" "F.Paste")
			(net "GND")
		)
		(pad "91" smd circle
			(at 1.905 -1.905 90)
			(size 0.635 0.635)
			(layers "F.Cu" "F.Mask" "F.Paste")
			(net "PCIE_T2B_B2_RX_DN<10>")
		)
		(pad "92" smd circle
			(at 1.905 -0.635 90)
			(size 0.635 0.635)
			(layers "F.Cu" "F.Mask" "F.Paste")
			(net "GND")
		)
		(pad "93" smd circle
			(at 1.905 0.635 90)
			(size 0.635 0.635)
			(layers "F.Cu" "F.Mask" "F.Paste")
			(net "PCIE_B2T_B2_TX_DN<2>")
		)
		(pad "94" smd circle
			(at 1.905 1.905 90)
			(size 0.635 0.635)
			(layers "F.Cu" "F.Mask" "F.Paste")
			(net "GND")
		)
		(pad "95" smd circle
			(at 1.905 3.175 90)
			(size 0.635 0.635)
			(layers "F.Cu" "F.Mask" "F.Paste")
			(net "PCIE_B2T_B2_TX_DN<10>")
		)
		(pad "96" smd circle
			(at 1.905 4.445 90)
			(size 0.635 0.635)
			(layers "F.Cu" "F.Mask" "F.Paste")
			(net "GND")
		)
		(pad "97" smd circle
			(at 3.175 -4.445 90)
			(size 0.635 0.635)
			(layers "F.Cu" "F.Mask" "F.Paste")
			(net "GND")
		)
		(pad "98" smd circle
			(at 3.175 -3.175 90)
			(size 0.635 0.635)
			(layers "F.Cu" "F.Mask" "F.Paste")
			(net "PCIE_T2B_B2_RX_DP<1>")
		)
		(pad "99" smd circle
			(at 3.175 -1.905 90)
			(size 0.635 0.635)
			(layers "F.Cu" "F.Mask" "F.Paste")
			(net "GND")
		)
		(pad "100" smd circle
			(at 3.175 -0.635 90)
			(size 0.635 0.635)
			(layers "F.Cu" "F.Mask" "F.Paste")
			(net "PCIE_T2B_B2_RX_DP<9>")
		)
		(pad "101" smd circle
			(at 3.175 0.635 90)
			(size 0.635 0.635)
			(layers "F.Cu" "F.Mask" "F.Paste")
			(net "GND")
		)
		(pad "102" smd circle
			(at 3.175 1.905 90)
			(size 0.635 0.635)
			(layers "F.Cu" "F.Mask" "F.Paste")
			(net "PCIE_B2T_B2_TX_DP<1>")
		)
		(pad "103" smd circle
			(at 3.175 3.175 90)
			(size 0.635 0.635)
			(layers "F.Cu" "F.Mask" "F.Paste")
			(net "GND")
		)
		(pad "104" smd circle
			(at 3.175 4.445 90)
			(size 0.635 0.635)
			(layers "F.Cu" "F.Mask" "F.Paste")
			(net "PCIE_B2T_B2_TX_DP<9>")
		)
		(pad "105" smd circle
			(at 4.445 -4.445 90)
			(size 0.635 0.635)
			(layers "F.Cu" "F.Mask" "F.Paste")
			(net "GND")
		)
		(pad "106" smd circle
			(at 4.445 -3.175 90)
			(size 0.635 0.635)
			(layers "F.Cu" "F.Mask" "F.Paste")
			(net "PCIE_T2B_B2_RX_DN<1>")
		)
		(pad "107" smd circle
			(at 4.445 -1.905 90)
			(size 0.635 0.635)
			(layers "F.Cu" "F.Mask" "F.Paste")
			(net "GND")
		)
		(pad "108" smd circle
			(at 4.445 -0.635 90)
			(size 0.635 0.635)
			(layers "F.Cu" "F.Mask" "F.Paste")
			(net "PCIE_T2B_B2_RX_DN<9>")
		)
		(pad "109" smd circle
			(at 4.445 0.635 90)
			(size 0.635 0.635)
			(layers "F.Cu" "F.Mask" "F.Paste")
			(net "GND")
		)
		(pad "110" smd circle
			(at 4.445 1.905 90)
			(size 0.635 0.635)
			(layers "F.Cu" "F.Mask" "F.Paste")
			(net "PCIE_B2T_B2_TX_DN<1>")
		)
		(pad "111" smd circle
			(at 4.445 3.175 90)
			(size 0.635 0.635)
			(layers "F.Cu" "F.Mask" "F.Paste")
			(net "GND")
		)
		(pad "112" smd circle
			(at 4.445 4.445 90)
			(size 0.635 0.635)
			(layers "F.Cu" "F.Mask" "F.Paste")
			(net "PCIE_B2T_B2_TX_DN<9>")
		)
		(pad "113" smd circle
			(at 5.715 -4.445 90)
			(size 0.635 0.635)
			(layers "F.Cu" "F.Mask" "F.Paste")
			(net "PCIE_T2B_B2_RX_DP<0>")
		)
		(pad "114" smd circle
			(at 5.715 -3.175 90)
			(size 0.635 0.635)
			(layers "F.Cu" "F.Mask" "F.Paste")
			(net "GND")
		)
		(pad "115" smd circle
			(at 5.715 -1.905 90)
			(size 0.635 0.635)
			(layers "F.Cu" "F.Mask" "F.Paste")
			(net "PCIE_T2B_B2_RX_DP<8>")
		)
		(pad "116" smd circle
			(at 5.715 -0.635 90)
			(size 0.635 0.635)
			(layers "F.Cu" "F.Mask" "F.Paste")
			(net "GND")
		)
		(pad "117" smd circle
			(at 5.715 0.635 90)
			(size 0.635 0.635)
			(layers "F.Cu" "F.Mask" "F.Paste")
			(net "PCIE_B2T_B2_TX_DP<0>")
		)
		(pad "118" smd circle
			(at 5.715 1.905 90)
			(size 0.635 0.635)
			(layers "F.Cu" "F.Mask" "F.Paste")
			(net "GND")
		)
		(pad "119" smd circle
			(at 5.715 3.175 90)
			(size 0.635 0.635)
			(layers "F.Cu" "F.Mask" "F.Paste")
			(net "PCIE_B2T_B2_TX_DP<8>")
		)
		(pad "120" smd circle
			(at 5.715 4.445 90)
			(size 0.635 0.635)
			(layers "F.Cu" "F.Mask" "F.Paste")
			(net "GND")
		)
		(pad "121" smd circle
			(at 6.985 -4.445 90)
			(size 0.635 0.635)
			(layers "F.Cu" "F.Mask" "F.Paste")
			(net "PCIE_T2B_B2_RX_DN<0>")
		)
		(pad "122" smd circle
			(at 6.985 -3.175 90)
			(size 0.635 0.635)
			(layers "F.Cu" "F.Mask" "F.Paste")
			(net "GND")
		)
		(pad "123" smd circle
			(at 6.985 -1.905 90)
			(size 0.635 0.635)
			(layers "F.Cu" "F.Mask" "F.Paste")
			(net "PCIE_T2B_B2_RX_DN<8>")
		)
		(pad "124" smd circle
			(at 6.985 -0.635 90)
			(size 0.635 0.635)
			(layers "F.Cu" "F.Mask" "F.Paste")
			(net "GND")
		)
		(pad "125" smd circle
			(at 6.985 0.635 90)
			(size 0.635 0.635)
			(layers "F.Cu" "F.Mask" "F.Paste")
			(net "PCIE_B2T_B2_TX_DN<0>")
		)
		(pad "126" smd circle
			(at 6.985 1.905 90)
			(size 0.635 0.635)
			(layers "F.Cu" "F.Mask" "F.Paste")
			(net "GND")
		)
		(pad "127" smd circle
			(at 6.985 3.175 90)
			(size 0.635 0.635)
			(layers "F.Cu" "F.Mask" "F.Paste")
			(net "PCIE_B2T_B2_TX_DN<8>")
		)
		(pad "128" smd circle
			(at 6.985 4.445 90)
			(size 0.635 0.635)
			(layers "F.Cu" "F.Mask" "F.Paste")
			(net "GND")
		)
		(pad "129" smd circle
			(at 8.255 -4.445 90)
			(size 0.635 0.635)
			(layers "F.Cu" "F.Mask" "F.Paste")
			(net "GND")
		)
		(pad "130" smd circle
			(at 8.255 -3.175 90)
			(size 0.635 0.635)
			(layers "F.Cu" "F.Mask" "F.Paste")
			(net "CLK_100M_B2_P<0>")
		)
		(pad "131" smd circle
			(at 8.255 -1.905 90)
			(size 0.635 0.635)
			(layers "F.Cu" "F.Mask" "F.Paste")
			(net "GND")
		)
		(pad "132" smd circle
			(at 8.255 -0.635 90)
			(size 0.635 0.635)
			(layers "F.Cu" "F.Mask" "F.Paste")
			(net "CLK_100M_B2_P<1>")
		)
		(pad "133" smd circle
			(at 8.255 0.635 90)
			(size 0.635 0.635)
			(layers "F.Cu" "F.Mask" "F.Paste")
			(net "GND")
		)
		(pad "134" smd circle
			(at 8.255 1.905 90)
			(size 0.635 0.635)
			(layers "F.Cu" "F.Mask" "F.Paste")
			(net "CLK_100M_B2_P<2>")
		)
		(pad "135" smd circle
			(at 8.255 3.175 90)
			(size 0.635 0.635)
			(layers "F.Cu" "F.Mask" "F.Paste")
			(net "GND")
		)
		(pad "136" smd circle
			(at 8.255 4.445 90)
			(size 0.635 0.635)
			(layers "F.Cu" "F.Mask" "F.Paste")
			(net "CLK_100M_B2_P<3>")
		)
		(pad "137" smd circle
			(at 9.525 -4.445 90)
			(size 0.635 0.635)
			(layers "F.Cu" "F.Mask" "F.Paste")
			(net "P12V_MEZZ_B2")
		)
		(pad "138" smd circle
			(at 9.525 -3.175 90)
			(size 0.635 0.635)
			(layers "F.Cu" "F.Mask" "F.Paste")
			(net "CLK_100M_B2_N<0>")
		)
		(pad "139" smd circle
			(at 9.525 -1.905 90)
			(size 0.635 0.635)
			(layers "F.Cu" "F.Mask" "F.Paste")
			(net "GND")
		)
		(pad "140" smd circle
			(at 9.525 -0.635 90)
			(size 0.635 0.635)
			(layers "F.Cu" "F.Mask" "F.Paste")
			(net "CLK_100M_B2_N<1>")
		)
		(pad "141" smd circle
			(at 9.525 0.635 90)
			(size 0.635 0.635)
			(layers "F.Cu" "F.Mask" "F.Paste")
			(net "GND")
		)
		(pad "142" smd circle
			(at 9.525 1.905 90)
			(size 0.635 0.635)
			(layers "F.Cu" "F.Mask" "F.Paste")
			(net "CLK_100M_B2_N<2>")
		)
		(pad "143" smd circle
			(at 9.525 3.175 90)
			(size 0.635 0.635)
			(layers "F.Cu" "F.Mask" "F.Paste")
			(net "PCIE_RESET_B2_N<2>")
		)
		(pad "144" smd circle
			(at 9.525 4.445 90)
			(size 0.635 0.635)
			(layers "F.Cu" "F.Mask" "F.Paste")
			(net "CLK_100M_B2_N<3>")
		)
		(pad "145" smd circle
			(at 10.795 -4.445 90)
			(size 0.635 0.635)
			(layers "F.Cu" "F.Mask" "F.Paste")
			(net "P12V_MEZZ_B2")
		)
		(pad "146" smd circle
			(at 10.795 -3.175 90)
			(size 0.635 0.635)
			(layers "F.Cu" "F.Mask" "F.Paste")
			(net "GND")
		)
		(pad "147" smd circle
			(at 10.795 -1.905 90)
			(size 0.635 0.635)
			(layers "F.Cu" "F.Mask" "F.Paste")
			(net "GND")
		)
		(pad "148" smd circle
			(at 10.795 -0.635 90)
			(size 0.635 0.635)
			(layers "F.Cu" "F.Mask" "F.Paste")
			(net "PCIE_CFG_B2_ID1")
		)
		(pad "149" smd circle
			(at 10.795 0.635 90)
			(size 0.635 0.635)
			(layers "F.Cu" "F.Mask" "F.Paste")
			(net "PCIE_CFG_B2_ID0")
		)
		(pad "150" smd circle
			(at 10.795 1.905 90)
			(size 0.635 0.635)
			(layers "F.Cu" "F.Mask" "F.Paste")
			(net "PCIE_RESET_B2_N<0>")
		)
		(pad "151" smd circle
			(at 10.795 3.175 90)
			(size 0.635 0.635)
			(layers "F.Cu" "F.Mask" "F.Paste")
			(net "PCIE_RESET_B2_N<1>")
		)
		(pad "152" smd circle
			(at 10.795 4.445 90)
			(size 0.635 0.635)
			(layers "F.Cu" "F.Mask" "F.Paste")
			(net "PCIE_RESET_B2_N<3>")
		)
		(pad "153" smd circle
			(at 12.065 -4.445 90)
			(size 0.635 0.635)
			(layers "F.Cu" "F.Mask" "F.Paste")
			(net "P12V_MEZZ_B2")
		)
		(pad "154" smd circle
			(at 12.065 -3.175 90)
			(size 0.635 0.635)
			(layers "F.Cu" "F.Mask" "F.Paste")
			(net "P12V_MEZZ_B2")
		)
		(pad "155" smd circle
			(at 12.065 -1.905 90)
			(size 0.635 0.635)
			(layers "F.Cu" "F.Mask" "F.Paste")
			(net "P12V_MEZZ_B2")
		)
		(pad "156" smd circle
			(at 12.065 -0.635 90)
			(size 0.635 0.635)
			(layers "F.Cu" "F.Mask" "F.Paste")
			(net "MEZZ_B2_SCL")
		)
		(pad "157" smd circle
			(at 12.065 0.635 90)
			(size 0.635 0.635)
			(layers "F.Cu" "F.Mask" "F.Paste")
			(net "MEZZ_B2_EN")
		)
		(pad "158" smd circle
			(at 12.065 1.905 90)
			(size 0.635 0.635)
			(layers "F.Cu" "F.Mask" "F.Paste")
			(net "MEZZ_B2_SDA")
		)
		(pad "159" smd circle
			(at 12.065 3.175 90)
			(size 0.635 0.635)
			(layers "F.Cu" "F.Mask" "F.Paste")
			(net "PCIE_WAKE_B2_N")
		)
		(pad "160" smd circle
			(at 12.065 4.445 90)
			(size 0.635 0.635)
			(layers "F.Cu" "F.Mask" "F.Paste")
			(net "MEZZ_PRESENT_B2_N")
		)
		(zone
			(layers "F.Cu" "B.Cu" "In1.Cu" "In2.Cu" "In3.Cu" "In4.Cu" "In5.Cu" "In6.Cu")
			(hatch none 0.5)
			(connect_pads
				(clearance 0)
			)
			(min_thickness 0.25)
			(keepout
				(tracks not_allowed)
				(vias allowed)
				(pads allowed)
				(copperpour not_allowed)
				(footprints allowed)
			)
			(placement
				(enabled no)
				(sheetname "")
			)
			(fill
				(thermal_gap 0.5)
				(thermal_bridge_width 0.5)
				(island_removal_mode 0)
			)
			(polygon
				(pts
					(arc
						(start -157.127999 44.434699)
						(mid -157.127999 46.466699)
						(end -157.127999 44.434699)
					)
				)
			)
		)
		(zone
			(layers "F.Cu" "B.Cu" "In1.Cu" "In2.Cu" "In3.Cu" "In4.Cu" "In5.Cu" "In6.Cu")
			(hatch none 0.5)
			(connect_pads
				(clearance 0)
			)
			(min_thickness 0.25)
			(keepout
				(tracks not_allowed)
				(vias allowed)
				(pads allowed)
				(copperpour not_allowed)
				(footprints allowed)
			)
			(placement
				(enabled no)
				(sheetname "")
			)
			(fill
				(thermal_gap 0.5)
				(thermal_bridge_width 0.5)
				(island_removal_mode 0)
			)
			(polygon
				(pts
					(arc
						(start -154.079999 15.453299)
						(mid -154.079999 17.485299)
						(end -154.079999 15.453299)
					)
				)
			)
		)
	)
	(footprint ""
		(layer "F.Cu")
		(at -110.8456 9.0424)
		(property "Reference" "R62"
			(at 2.8956 0.0127 0)
			(unlocked yes)
			(layer "F.SilkS")
			(effects
				(font
					(size 0.762 0.5334)
					(thickness 0.1016)
				)
			)
		)
		(property "Value" ""
			(at 0 0 0)
			(layer "F.Fab")
			(effects
				(font
					(size 1.27 1.27)
				)
			)
		)
		(duplicate_pad_numbers_are_jumpers no)
		(fp_line
			(start 0 -0.381)
			(end 0 0.381)
			(stroke
				(width 0.127)
				(type default)
			)
			(layer "F.SilkS")
		)
		(fp_poly
			(pts
				(xy 1.255601 0.6564) (xy -1.255601 0.6564) (xy -1.255601 -0.656399) (xy 1.255601 -0.656399)
			)
			(stroke
				(width 0)
				(type default)
			)
			(fill no)
			(layer "F.CrtYd")
		)
		(fp_line
			(start -0.800001 -0.399999)
			(end -0.800001 0.399999)
			(stroke
				(width 0.1)
				(type default)
			)
			(layer "F.Fab")
		)
		(fp_line
			(start -0.800001 0.399999)
			(end 0.800001 0.399999)
			(stroke
				(width 0.1)
				(type default)
			)
			(layer "F.Fab")
		)
		(fp_line
			(start 0.800001 -0.399999)
			(end -0.800001 -0.399999)
			(stroke
				(width 0.1)
				(type default)
			)
			(layer "F.Fab")
		)
		(fp_line
			(start 0.800001 0.399999)
			(end 0.800001 -0.399999)
			(stroke
				(width 0.1)
				(type default)
			)
			(layer "F.Fab")
		)
		(pad "1" smd rect
			(at -0.650001 0)
			(size 0.7112 0.8128)
			(layers "F.Cu" "F.Mask" "F.Paste")
			(net "P3V3_B2_QSFP")
		)
		(pad "2" smd rect
			(at 0.650001 0 180)
			(size 0.7112 0.8128)
			(layers "F.Cu" "F.Mask" "F.Paste")
			(net "ETH40G_B2_MODSEL_N")
		)
	)
	(footprint ""
		(layer "F.Cu")
		(at -266.4714 5.842)
		(property "Reference" "FS8"
			(at 2.3114 0.1651 0)
			(unlocked yes)
			(layer "F.SilkS")
			(effects
				(font
					(size 0.762 0.5334)
					(thickness 0.1016)
				)
			)
		)
		(property "Value" ""
			(at 0 0 0)
			(layer "F.Fab")
			(effects
				(font
					(size 1.27 1.27)
				)
			)
		)
		(duplicate_pad_numbers_are_jumpers no)
		(fp_poly
			(pts
				(xy -1.002101 0.504) (xy -1.002101 -0.503999) (xy 1.002101 -0.503999) (xy 1.002101 0.504)
			)
			(stroke
				(width 0)
				(type default)
			)
			(fill no)
			(layer "F.CrtYd")
		)
		(fp_line
			(start -0.499999 -0.249999)
			(end -0.499999 0.25)
			(stroke
				(width 0.1)
				(type default)
			)
			(layer "F.Fab")
		)
		(fp_line
			(start -0.499999 0.25)
			(end 0.499999 0.25)
			(stroke
				(width 0.1)
				(type default)
			)
			(layer "F.Fab")
		)
		(fp_line
			(start 0.499999 -0.249999)
			(end -0.499999 -0.249999)
			(stroke
				(width 0.1)
				(type default)
			)
			(layer "F.Fab")
		)
		(fp_line
			(start 0.499999 0.25)
			(end 0.499999 -0.249999)
			(stroke
				(width 0.1)
				(type default)
			)
			(layer "F.Fab")
		)
		(pad "1" smd rect
			(at -0.459999 0 90)
			(size 0.508 0.5842)
			(layers "F.Cu" "F.Mask" "F.Paste")
			(net "P3V3_B1_QSFP")
		)
		(pad "2" smd rect
			(at 0.459999 0 90)
			(size 0.508 0.5842)
			(layers "F.Cu" "F.Mask" "F.Paste")
			(net "UNNAMED_16_FERRITE_I115_A")
		)
	)
	(footprint ""
		(layer "F.Cu")
		(at -75.292801 5.270602 180)
		(property "Reference" "R49"
			(at -2.521801 0.025502 0)
			(unlocked yes)
			(layer "F.SilkS")
			(effects
				(font
					(size 0.762 0.5334)
					(thickness 0.1016)
				)
			)
		)
		(property "Value" ""
			(at 0 0 180)
			(layer "F.Fab")
			(effects
				(font
					(size 1.27 1.27)
				)
			)
		)
		(duplicate_pad_numbers_are_jumpers no)
		(fp_line
			(start 0 -0.381)
			(end 0 0.381)
			(stroke
				(width 0.127)
				(type default)
			)
			(layer "F.SilkS")
		)
		(fp_poly
			(pts
				(xy 1.255601 0.6564) (xy -1.255601 0.6564) (xy -1.255601 -0.656399) (xy 1.255601 -0.656399)
			)
			(stroke
				(width 0)
				(type default)
			)
			(fill no)
			(layer "F.CrtYd")
		)
		(fp_line
			(start 0.800001 0.4)
			(end 0.800001 -0.399999)
			(stroke
				(width 0.1)
				(type default)
			)
			(layer "F.Fab")
		)
		(fp_line
			(start 0.800001 -0.399999)
			(end -0.800001 -0.399999)
			(stroke
				(width 0.1)
				(type default)
			)
			(layer "F.Fab")
		)
		(fp_line
			(start -0.800001 0.4)
			(end 0.800001 0.4)
			(stroke
				(width 0.1)
				(type default)
			)
			(layer "F.Fab")
		)
		(fp_line
			(start -0.800001 -0.399999)
			(end -0.800001 0.4)
			(stroke
				(width 0.1)
				(type default)
			)
			(layer "F.Fab")
		)
		(pad "1" smd rect
			(at -0.650001 0 180)
			(size 0.7112 0.8128)
			(layers "F.Cu" "F.Mask" "F.Paste")
			(net "ETH10G_B2_TX_DIS")
		)
		(pad "2" smd rect
			(at 0.650001 0)
			(size 0.7112 0.8128)
			(layers "F.Cu" "F.Mask" "F.Paste")
			(net "GND")
		)
	)
	(footprint ""
		(layer "F.Cu")
		(at -300.951798 3.080601)
		(property "Reference" "R27"
			(at -3.340202 0.005499 0)
			(unlocked yes)
			(layer "F.SilkS")
			(effects
				(font
					(size 0.762 0.5334)
					(thickness 0.1016)
				)
			)
		)
		(property "Value" ""
			(at 0 0 0)
			(layer "F.Fab")
			(effects
				(font
					(size 1.27 1.27)
				)
			)
		)
		(duplicate_pad_numbers_are_jumpers no)
		(fp_line
			(start 0 -0.381)
			(end 0 0.381)
			(stroke
				(width 0.127)
				(type default)
			)
			(layer "F.SilkS")
		)
		(fp_poly
			(pts
				(xy 1.2556 0.656399) (xy -1.255601 0.656399) (xy -1.255601 -0.6564) (xy 1.2556 -0.6564)
			)
			(stroke
				(width 0)
				(type default)
			)
			(fill no)
			(layer "F.CrtYd")
		)
		(fp_line
			(start -0.800001 -0.399999)
			(end -0.800001 0.399999)
			(stroke
				(width 0.1)
				(type default)
			)
			(layer "F.Fab")
		)
		(fp_line
			(start -0.800001 0.399999)
			(end 0.800001 0.399999)
			(stroke
				(width 0.1)
				(type default)
			)
			(layer "F.Fab")
		)
		(fp_line
			(start 0.800001 -0.399999)
			(end -0.800001 -0.399999)
			(stroke
				(width 0.1)
				(type default)
			)
			(layer "F.Fab")
		)
		(fp_line
			(start 0.800001 0.399999)
			(end 0.800001 -0.399999)
			(stroke
				(width 0.1)
				(type default)
			)
			(layer "F.Fab")
		)
		(pad "1" smd rect
			(at -0.650001 0)
			(size 0.7112 0.8128)
			(layers "F.Cu" "F.Mask" "F.Paste")
			(net "P3V3_B1_QSFP")
		)
		(pad "2" smd rect
			(at 0.650001 0 180)
			(size 0.7112 0.8128)
			(layers "F.Cu" "F.Mask" "F.Paste")
			(net "ETH10G_B1_RX_LOS")
		)
	)
	(footprint ""
		(layer "F.Cu")
		(at -331.47 16.0528)
		(property "Reference" "R81"
			(at 3.175 -0.0127 0)
			(unlocked yes)
			(layer "F.SilkS")
			(effects
				(font
					(size 0.762 0.5334)
					(thickness 0.1016)
				)
			)
		)
		(property "Value" ""
			(at 0 0 0)
			(layer "F.Fab")
			(effects
				(font
					(size 1.27 1.27)
				)
			)
		)
		(duplicate_pad_numbers_are_jumpers no)
		(fp_line
			(start 0 -0.381)
			(end 0 0.381)
			(stroke
				(width 0.127)
				(type default)
			)
			(layer "F.SilkS")
		)
		(fp_poly
			(pts
				(xy 1.255601 0.6564) (xy -1.255601 0.6564) (xy -1.255601 -0.656399) (xy 1.255601 -0.656399)
			)
			(stroke
				(width 0)
				(type default)
			)
			(fill no)
			(layer "F.CrtYd")
		)
		(fp_line
			(start -0.800001 -0.399999)
			(end -0.800001 0.399999)
			(stroke
				(width 0.1)
				(type default)
			)
			(layer "F.Fab")
		)
		(fp_line
			(start -0.800001 0.399999)
			(end 0.800001 0.399999)
			(stroke
				(width 0.1)
				(type default)
			)
			(layer "F.Fab")
		)
		(fp_line
			(start 0.800001 -0.399999)
			(end -0.800001 -0.399999)
			(stroke
				(width 0.1)
				(type default)
			)
			(layer "F.Fab")
		)
		(fp_line
			(start 0.800001 0.399999)
			(end 0.800001 -0.399999)
			(stroke
				(width 0.1)
				(type default)
			)
			(layer "F.Fab")
		)
		(pad "1" smd rect
			(at -0.650001 0)
			(size 0.7112 0.8128)
			(layers "F.Cu" "F.Mask" "F.Paste")
			(net "P3V3_B1_QSFP")
		)
		(pad "2" smd rect
			(at 0.650001 0 180)
			(size 0.7112 0.8128)
			(layers "F.Cu" "F.Mask" "F.Paste")
			(net "ETH40G_B1_SDA")
		)
	)
	(footprint ""
		(layer "F.Cu")
		(at -165.770001 39.357399)
		(property "Reference" "MH4"
			(at 0 -4.9149 0)
			(unlocked yes)
			(layer "F.SilkS")
			(effects
				(font
					(size 0.762 0.5334)
					(thickness 0.1016)
				)
			)
		)
		(property "Value" ""
			(at 0 0 0)
			(layer "F.Fab")
			(effects
				(font
					(size 1.27 1.27)
				)
			)
		)
		(duplicate_pad_numbers_are_jumpers no)
		(fp_poly
			(pts
				(arc
					(start 4.0132 0)
					(mid -4.0132 0)
					(end 4.0132 0)
				)
			)
			(stroke
				(width 0)
				(type default)
			)
			(fill no)
			(layer "B.CrtYd")
		)
		(fp_poly
			(pts
				(arc
					(start 4.0132 0)
					(mid -4.0132 0)
					(end 4.0132 0)
				)
			)
			(stroke
				(width 0)
				(type default)
			)
			(fill no)
			(layer "F.CrtYd")
		)
		(pad "1" thru_hole circle
			(at 0 0)
			(size 7.0104 7.0104)
			(drill 3.5052)
			(layers "*.Cu" "*.Mask")
			(remove_unused_layers no)
			(net "GND")
			(padstack
				(mode front_inner_back)
				(layer "Inner"
					(shape circle)
					(size 4.5212 4.5212)
				)
				(layer "B.Cu"
					(shape circle)
					(size 7.0104 7.0104)
				)
			)
		)
		(pad "2" thru_hole circle
			(at 0 -2.794)
			(size 0.6604 0.6604)
			(drill 0.3556)
			(layers "*.Cu" "*.Mask")
			(remove_unused_layers no)
			(net "GND")
		)
		(pad "3" thru_hole circle
			(at -1.905 -2.032)
			(size 0.6604 0.6604)
			(drill 0.3556)
			(layers "*.Cu" "*.Mask")
			(remove_unused_layers no)
			(net "GND")
		)
		(pad "4" thru_hole circle
			(at -2.794 0)
			(size 0.6604 0.6604)
			(drill 0.3556)
			(layers "*.Cu" "*.Mask")
			(remove_unused_layers no)
			(net "GND")
		)
		(pad "5" thru_hole circle
			(at -2.032 1.905)
			(size 0.6604 0.6604)
			(drill 0.3556)
			(layers "*.Cu" "*.Mask")
			(remove_unused_layers no)
			(net "GND")
		)
		(pad "6" thru_hole circle
			(at 0 2.794)
			(size 0.6604 0.6604)
			(drill 0.3556)
			(layers "*.Cu" "*.Mask")
			(remove_unused_layers no)
			(net "GND")
		)
		(pad "7" thru_hole circle
			(at 2.032 1.905)
			(size 0.6604 0.6604)
			(drill 0.3556)
			(layers "*.Cu" "*.Mask")
			(remove_unused_layers no)
			(net "GND")
		)
		(pad "8" thru_hole circle
			(at 2.794 0)
			(size 0.6604 0.6604)
			(drill 0.3556)
			(layers "*.Cu" "*.Mask")
			(remove_unused_layers no)
			(net "GND")
		)
		(pad "9" thru_hole circle
			(at 1.905 -2.032)
			(size 0.6604 0.6604)
			(drill 0.3556)
			(layers "*.Cu" "*.Mask")
			(remove_unused_layers no)
			(net "GND")
		)
	)
	(footprint ""
		(layer "F.Cu")
		(at -266.109699 20.000001)
		(property "Reference" "MH3"
			(at -0.011181 -4.617761 0)
			(unlocked yes)
			(layer "F.SilkS")
			(effects
				(font
					(size 0.762 0.5334)
					(thickness 0.1016)
				)
			)
		)
		(property "Value" ""
			(at 0 0 0)
			(layer "F.Fab")
			(effects
				(font
					(size 1.27 1.27)
				)
			)
		)
		(duplicate_pad_numbers_are_jumpers no)
		(fp_poly
			(pts
				(arc
					(start 4.0132 0)
					(mid -4.0132 0)
					(end 4.0132 0)
				)
			)
			(stroke
				(width 0)
				(type default)
			)
			(fill no)
			(layer "B.CrtYd")
		)
		(fp_poly
			(pts
				(arc
					(start 4.0132 0)
					(mid -4.0132 0)
					(end 4.0132 0)
				)
			)
			(stroke
				(width 0)
				(type default)
			)
			(fill no)
			(layer "F.CrtYd")
		)
		(pad "1" thru_hole circle
			(at 0 0)
			(size 7.0104 7.0104)
			(drill 3.5052)
			(layers "*.Cu" "*.Mask")
			(remove_unused_layers no)
			(net "GND")
			(padstack
				(mode front_inner_back)
				(layer "Inner"
					(shape circle)
					(size 4.5212 4.5212)
				)
				(layer "B.Cu"
					(shape circle)
					(size 7.0104 7.0104)
				)
			)
		)
		(pad "2" thru_hole circle
			(at 0 -2.794)
			(size 0.6604 0.6604)
			(drill 0.3556)
			(layers "*.Cu" "*.Mask")
			(remove_unused_layers no)
			(net "GND")
		)
		(pad "3" thru_hole circle
			(at -1.905 -2.032)
			(size 0.6604 0.6604)
			(drill 0.3556)
			(layers "*.Cu" "*.Mask")
			(remove_unused_layers no)
			(net "GND")
		)
		(pad "4" thru_hole circle
			(at -2.794 0)
			(size 0.6604 0.6604)
			(drill 0.3556)
			(layers "*.Cu" "*.Mask")
			(remove_unused_layers no)
			(net "GND")
		)
		(pad "5" thru_hole circle
			(at -2.032 1.905)
			(size 0.6604 0.6604)
			(drill 0.3556)
			(layers "*.Cu" "*.Mask")
			(remove_unused_layers no)
			(net "GND")
		)
		(pad "6" thru_hole circle
			(at 0 2.794)
			(size 0.6604 0.6604)
			(drill 0.3556)
			(layers "*.Cu" "*.Mask")
			(remove_unused_layers no)
			(net "GND")
		)
		(pad "7" thru_hole circle
			(at 2.032 1.905)
			(size 0.6604 0.6604)
			(drill 0.3556)
			(layers "*.Cu" "*.Mask")
			(remove_unused_layers no)
			(net "GND")
		)
		(pad "8" thru_hole circle
			(at 2.794 0)
			(size 0.6604 0.6604)
			(drill 0.3556)
			(layers "*.Cu" "*.Mask")
			(remove_unused_layers no)
			(net "GND")
		)
		(pad "9" thru_hole circle
			(at 1.905 -2.032)
			(size 0.6604 0.6604)
			(drill 0.3556)
			(layers "*.Cu" "*.Mask")
			(remove_unused_layers no)
			(net "GND")
		)
	)
	(footprint ""
		(layer "F.Cu")
		(at -113.824601 21.145602 90)
		(property "Reference" "C13"
			(at -3.111398 -0.056299 90)
			(unlocked yes)
			(layer "F.SilkS")
			(effects
				(font
					(size 0.762 0.5334)
					(thickness 0.1016)
				)
			)
		)
		(property "Value" ""
			(at 0 0 90)
			(layer "F.Fab")
			(effects
				(font
					(size 1.27 1.27)
				)
			)
		)
		(duplicate_pad_numbers_are_jumpers no)
		(fp_line
			(start 0 -0.381)
			(end 0 0.381)
			(stroke
				(width 0.127)
				(type default)
			)
			(layer "F.SilkS")
		)
		(fp_poly
			(pts
				(xy 1.2533 0.6564) (xy -1.253299 0.6564) (xy -1.253299 -0.656399) (xy 1.2533 -0.656399)
			)
			(stroke
				(width 0)
				(type default)
			)
			(fill no)
			(layer "F.CrtYd")
		)
		(fp_line
			(start 0.762 -0.381)
			(end -0.762 -0.381)
			(stroke
				(width 0.1)
				(type default)
			)
			(layer "F.Fab")
		)
		(fp_line
			(start -0.762 -0.381)
			(end -0.762 0.381)
			(stroke
				(width 0.1)
				(type default)
			)
			(layer "F.Fab")
		)
		(fp_line
			(start 0.762 0.381)
			(end 0.762 -0.381)
			(stroke
				(width 0.1)
				(type default)
			)
			(layer "F.Fab")
		)
		(fp_line
			(start -0.762 0.381)
			(end 0.762 0.381)
			(stroke
				(width 0.1)
				(type default)
			)
			(layer "F.Fab")
		)
		(pad "1" smd rect
			(at -0.6477 0 90)
			(size 0.7112 0.8128)
			(layers "F.Cu" "F.Mask" "F.Paste")
			(net "P12V")
		)
		(pad "2" smd rect
			(at 0.6477 0 270)
			(size 0.7112 0.8128)
			(layers "F.Cu" "F.Mask" "F.Paste")
			(net "GND")
		)
	)
	(footprint ""
		(layer "F.Cu")
		(at -44.7802 4.191 180)
		(property "Reference" "C27"
			(at -2.97434 -0.5715 0)
			(unlocked yes)
			(layer "F.SilkS")
			(effects
				(font
					(size 0.762 0.5334)
					(thickness 0.1016)
				)
			)
		)
		(property "Value" ""
			(at 0 0 180)
			(layer "F.Fab")
			(effects
				(font
					(size 1.27 1.27)
				)
			)
		)
		(duplicate_pad_numbers_are_jumpers no)
		(fp_line
			(start 0 -0.381)
			(end 0 0.381)
			(stroke
				(width 0.127)
				(type default)
			)
			(layer "F.SilkS")
		)
		(fp_poly
			(pts
				(xy 1.2533 0.656399) (xy -1.253299 0.656399) (xy -1.253299 -0.6564) (xy 1.2533 -0.6564)
			)
			(stroke
				(width 0)
				(type default)
			)
			(fill no)
			(layer "F.CrtYd")
		)
		(fp_line
			(start 0.762 0.381)
			(end 0.762 -0.381)
			(stroke
				(width 0.1)
				(type default)
			)
			(layer "F.Fab")
		)
		(fp_line
			(start 0.762 -0.381)
			(end -0.762 -0.381)
			(stroke
				(width 0.1)
				(type default)
			)
			(layer "F.Fab")
		)
		(fp_line
			(start -0.762 0.381)
			(end 0.762 0.381)
			(stroke
				(width 0.1)
				(type default)
			)
			(layer "F.Fab")
		)
		(fp_line
			(start -0.762 -0.381)
			(end -0.762 0.381)
			(stroke
				(width 0.1)
				(type default)
			)
			(layer "F.Fab")
		)
		(pad "1" smd rect
			(at -0.6477 0 180)
			(size 0.7112 0.8128)
			(layers "F.Cu" "F.Mask" "F.Paste")
			(net "P3V3_B2_QSFP")
		)
		(pad "2" smd rect
			(at 0.6477 0)
			(size 0.7112 0.8128)
			(layers "F.Cu" "F.Mask" "F.Paste")
			(net "GND")
		)
	)
	(footprint ""
		(layer "F.Cu")
		(at -354.6094 34.0614 90)
		(property "Reference" "C2"
			(at -2.159 -0.0889 90)
			(unlocked yes)
			(layer "F.SilkS")
			(effects
				(font
					(size 0.762 0.5334)
					(thickness 0.1016)
				)
			)
		)
		(property "Value" ""
			(at 0 0 90)
			(layer "F.Fab")
			(effects
				(font
					(size 1.27 1.27)
				)
			)
		)
		(duplicate_pad_numbers_are_jumpers no)
		(fp_line
			(start 0 -0.381)
			(end 0 0.381)
			(stroke
				(width 0.127)
				(type default)
			)
			(layer "F.SilkS")
		)
		(fp_poly
			(pts
				(xy 1.253299 0.656399) (xy -1.2533 0.656399) (xy -1.2533 -0.6564) (xy 1.253299 -0.6564)
			)
			(stroke
				(width 0)
				(type default)
			)
			(fill no)
			(layer "F.CrtYd")
		)
		(fp_line
			(start 0.762 -0.381)
			(end -0.762 -0.381)
			(stroke
				(width 0.1)
				(type default)
			)
			(layer "F.Fab")
		)
		(fp_line
			(start -0.762 -0.381)
			(end -0.762 0.381)
			(stroke
				(width 0.1)
				(type default)
			)
			(layer "F.Fab")
		)
		(fp_line
			(start 0.762 0.381)
			(end 0.762 -0.381)
			(stroke
				(width 0.1)
				(type default)
			)
			(layer "F.Fab")
		)
		(fp_line
			(start -0.762 0.381)
			(end 0.762 0.381)
			(stroke
				(width 0.1)
				(type default)
			)
			(layer "F.Fab")
		)
		(pad "1" smd rect
			(at -0.6477 0 90)
			(size 0.7112 0.8128)
			(layers "F.Cu" "F.Mask" "F.Paste")
			(net "P12V")
		)
		(pad "2" smd rect
			(at 0.6477 0 270)
			(size 0.7112 0.8128)
			(layers "F.Cu" "F.Mask" "F.Paste")
			(net "GND")
		)
	)
	(footprint ""
		(layer "F.Cu")
		(at -110.5462 3.0226 -90)
		(property "Reference" "J28"
			(at 0.6858 -4.00082 90)
			(unlocked yes)
			(layer "F.SilkS")
			(effects
				(font
					(size 0.762 0.5334)
					(thickness 0.1016)
				)
			)
		)
		(property "Value" ""
			(at 0 0 270)
			(layer "F.Fab")
			(effects
				(font
					(size 1.27 1.27)
				)
			)
		)
		(duplicate_pad_numbers_are_jumpers no)
		(fp_line
			(start -2.54 1.27)
			(end 0.127 1.27)
			(stroke
				(width 0.127)
				(type default)
			)
			(layer "F.SilkS")
		)
		(fp_line
			(start 2.443175 1.257198)
			(end 2.570175 1.257198)
			(stroke
				(width 0.127)
				(type default)
			)
			(layer "F.SilkS")
		)
		(fp_line
			(start 2.570175 1.257198)
			(end 2.570175 -1.282802)
			(stroke
				(width 0.127)
				(type default)
			)
			(layer "F.SilkS")
		)
		(fp_line
			(start -2.54 -1.27)
			(end -2.54 1.27)
			(stroke
				(width 0.127)
				(type default)
			)
			(layer "F.SilkS")
		)
		(fp_line
			(start -2.413 -1.27)
			(end -2.54 -1.27)
			(stroke
				(width 0.127)
				(type default)
			)
			(layer "F.SilkS")
		)
		(fp_line
			(start 2.570175 -1.282802)
			(end -0.096825 -1.282802)
			(stroke
				(width 0.127)
				(type default)
			)
			(layer "F.SilkS")
		)
		(fp_poly
			(pts
				(xy 0.127 3.683) (xy 0.127 1.778) (xy -3.048 1.778) (xy -3.048 -1.778) (xy -2.413 -1.778) (xy -2.413 -3.683)
				(xy -0.127 -3.683) (xy -0.127 -1.778) (xy 3.048 -1.778) (xy 3.048 1.778) (xy 2.413 1.778) (xy 2.413 3.683)
			)
			(stroke
				(width 0)
				(type default)
			)
			(fill no)
			(layer "F.CrtYd")
		)
		(fp_line
			(start -2.54 1.27)
			(end -2.54 -1.27)
			(stroke
				(width 0.1)
				(type default)
			)
			(layer "F.Fab")
		)
		(fp_line
			(start 2.54 1.27)
			(end -2.54 1.27)
			(stroke
				(width 0.1)
				(type default)
			)
			(layer "F.Fab")
		)
		(fp_line
			(start -2.54 -1.27)
			(end 2.54 -1.27)
			(stroke
				(width 0.1)
				(type default)
			)
			(layer "F.Fab")
		)
		(fp_line
			(start 2.54 -1.27)
			(end 2.54 1.27)
			(stroke
				(width 0.1)
				(type default)
			)
			(layer "F.Fab")
		)
		(fp_text user "*"
			(at -1.27 -3.89255 90)
			(unlocked yes)
			(layer "F.SilkS")
			(effects
				(font
					(size 0.381 0.381)
					(thickness 0.381)
				)
			)
		)
		(pad "1" smd rect
			(at -1.27 -1.4605 270)
			(size 1.27 3.429)
			(layers "F.Cu" "F.Mask" "F.Paste")
			(net "BLADE_B2_EN1")
		)
		(pad "2" smd rect
			(at 1.27 1.4605 270)
			(size 1.27 3.429)
			(layers "F.Cu" "F.Mask" "F.Paste")
			(net "UNNAMED_6_1X2HDR_I52_IO")
		)
	)
	(footprint ""
		(layer "F.Cu")
		(at -118.3694 2.794 -90)
		(property "Reference" "J29"
			(at 0.15748 3.94938 90)
			(unlocked yes)
			(layer "F.SilkS")
			(effects
				(font
					(size 0.762 0.5334)
					(thickness 0.1016)
				)
			)
		)
		(property "Value" ""
			(at 0 0 270)
			(layer "F.Fab")
			(effects
				(font
					(size 1.27 1.27)
				)
			)
		)
		(duplicate_pad_numbers_are_jumpers no)
		(fp_line
			(start -2.54 1.27)
			(end 0.127 1.27)
			(stroke
				(width 0.127)
				(type default)
			)
			(layer "F.SilkS")
		)
		(fp_line
			(start 2.443175 1.257198)
			(end 2.570175 1.257198)
			(stroke
				(width 0.127)
				(type default)
			)
			(layer "F.SilkS")
		)
		(fp_line
			(start 2.570175 1.257198)
			(end 2.570175 -1.282802)
			(stroke
				(width 0.127)
				(type default)
			)
			(layer "F.SilkS")
		)
		(fp_line
			(start -2.54 -1.27)
			(end -2.54 1.27)
			(stroke
				(width 0.127)
				(type default)
			)
			(layer "F.SilkS")
		)
		(fp_line
			(start -2.413 -1.27)
			(end -2.54 -1.27)
			(stroke
				(width 0.127)
				(type default)
			)
			(layer "F.SilkS")
		)
		(fp_line
			(start 2.570175 -1.282802)
			(end -0.096825 -1.282802)
			(stroke
				(width 0.127)
				(type default)
			)
			(layer "F.SilkS")
		)
		(fp_poly
			(pts
				(xy 0.127 3.683) (xy 0.127 1.778) (xy -3.048 1.778) (xy -3.048 -1.778) (xy -2.413 -1.778) (xy -2.413 -3.683)
				(xy -0.127 -3.683) (xy -0.127 -1.778) (xy 3.048 -1.778) (xy 3.048 1.778) (xy 2.413 1.778) (xy 2.413 3.683)
			)
			(stroke
				(width 0)
				(type default)
			)
			(fill no)
			(layer "F.CrtYd")
		)
		(fp_line
			(start -2.54 1.27)
			(end -2.54 -1.27)
			(stroke
				(width 0.1)
				(type default)
			)
			(layer "F.Fab")
		)
		(fp_line
			(start 2.54 1.27)
			(end -2.54 1.27)
			(stroke
				(width 0.1)
				(type default)
			)
			(layer "F.Fab")
		)
		(fp_line
			(start -2.54 -1.27)
			(end 2.54 -1.27)
			(stroke
				(width 0.1)
				(type default)
			)
			(layer "F.Fab")
		)
		(fp_line
			(start 2.54 -1.27)
			(end 2.54 1.27)
			(stroke
				(width 0.1)
				(type default)
			)
			(layer "F.Fab")
		)
		(fp_text user "*"
			(at -1.27 -3.89255 90)
			(unlocked yes)
			(layer "F.SilkS")
			(effects
				(font
					(size 0.381 0.381)
					(thickness 0.381)
				)
			)
		)
		(pad "1" smd rect
			(at -1.27 -1.4605 270)
			(size 1.27 3.429)
			(layers "F.Cu" "F.Mask" "F.Paste")
			(net "PSU_B2_ALERT_N")
		)
		(pad "2" smd rect
			(at 1.27 1.4605 270)
			(size 1.27 3.429)
			(layers "F.Cu" "F.Mask" "F.Paste")
			(net "UNNAMED_6_1X2HDR_I56_IO")
		)
	)
	(footprint ""
		(layer "F.Cu")
		(at -110.8456 13.2334)
		(property "Reference" "R64"
			(at 3.0226 0.0127 0)
			(unlocked yes)
			(layer "F.SilkS")
			(effects
				(font
					(size 0.762 0.5334)
					(thickness 0.1016)
				)
			)
		)
		(property "Value" ""
			(at 0 0 0)
			(layer "F.Fab")
			(effects
				(font
					(size 1.27 1.27)
				)
			)
		)
		(duplicate_pad_numbers_are_jumpers no)
		(fp_line
			(start 0 -0.381)
			(end 0 0.381)
			(stroke
				(width 0.127)
				(type default)
			)
			(layer "F.SilkS")
		)
		(fp_poly
			(pts
				(xy 1.255601 0.6564) (xy -1.255601 0.6564) (xy -1.255601 -0.656399) (xy 1.255601 -0.656399)
			)
			(stroke
				(width 0)
				(type default)
			)
			(fill no)
			(layer "F.CrtYd")
		)
		(fp_line
			(start -0.800001 -0.399999)
			(end -0.800001 0.399999)
			(stroke
				(width 0.1)
				(type default)
			)
			(layer "F.Fab")
		)
		(fp_line
			(start -0.800001 0.399999)
			(end 0.800001 0.399999)
			(stroke
				(width 0.1)
				(type default)
			)
			(layer "F.Fab")
		)
		(fp_line
			(start 0.800001 -0.399999)
			(end -0.800001 -0.399999)
			(stroke
				(width 0.1)
				(type default)
			)
			(layer "F.Fab")
		)
		(fp_line
			(start 0.800001 0.399999)
			(end 0.800001 -0.399999)
			(stroke
				(width 0.1)
				(type default)
			)
			(layer "F.Fab")
		)
		(pad "1" smd rect
			(at -0.650001 0)
			(size 0.7112 0.8128)
			(layers "F.Cu" "F.Mask" "F.Paste")
			(net "P3V3_B2_QSFP")
		)
		(pad "2" smd rect
			(at 0.650001 0 180)
			(size 0.7112 0.8128)
			(layers "F.Cu" "F.Mask" "F.Paste")
			(net "ETH40G_B2_INT_N")
		)
	)
	(footprint ""
		(layer "F.Cu")
		(at -44.8056 8.75538 180)
		(property "Reference" "R58"
			(at -2.8956 -0.04572 0)
			(unlocked yes)
			(layer "F.SilkS")
			(effects
				(font
					(size 0.762 0.5334)
					(thickness 0.1016)
				)
			)
		)
		(property "Value" ""
			(at 0 0 180)
			(layer "F.Fab")
			(effects
				(font
					(size 1.27 1.27)
				)
			)
		)
		(duplicate_pad_numbers_are_jumpers no)
		(fp_line
			(start 0 -0.381)
			(end 0 0.381)
			(stroke
				(width 0.127)
				(type default)
			)
			(layer "F.SilkS")
		)
		(fp_poly
			(pts
				(xy 1.255601 0.656399) (xy -1.255601 0.656399) (xy -1.255601 -0.6564) (xy 1.255601 -0.6564)
			)
			(stroke
				(width 0)
				(type default)
			)
			(fill no)
			(layer "F.CrtYd")
		)
		(fp_line
			(start 0.800001 0.399999)
			(end 0.800001 -0.399999)
			(stroke
				(width 0.1)
				(type default)
			)
			(layer "F.Fab")
		)
		(fp_line
			(start 0.800001 -0.399999)
			(end -0.800001 -0.399999)
			(stroke
				(width 0.1)
				(type default)
			)
			(layer "F.Fab")
		)
		(fp_line
			(start -0.800001 0.399999)
			(end 0.800001 0.399999)
			(stroke
				(width 0.1)
				(type default)
			)
			(layer "F.Fab")
		)
		(fp_line
			(start -0.800001 -0.399999)
			(end -0.800001 0.399999)
			(stroke
				(width 0.1)
				(type default)
			)
			(layer "F.Fab")
		)
		(pad "1" smd rect
			(at -0.650001 0 180)
			(size 0.7112 0.8128)
			(layers "F.Cu" "F.Mask" "F.Paste")
			(net "P3V3_B2_QSFP")
		)
		(pad "2" smd rect
			(at 0.650001 0)
			(size 0.7112 0.8128)
			(layers "F.Cu" "F.Mask" "F.Paste")
			(net "P3V3_40G_B2_VCC_TX")
		)
	)
	(footprint ""
		(layer "F.Cu")
		(at -268.224 9.017 -90)
		(property "Reference" "C31"
			(at 0.99822 -1.50114 0)
			(unlocked yes)
			(layer "F.SilkS")
			(effects
				(font
					(size 0.762 0.5334)
					(thickness 0.1016)
				)
			)
		)
		(property "Value" ""
			(at 0 0 270)
			(layer "F.Fab")
			(effects
				(font
					(size 1.27 1.27)
				)
			)
		)
		(duplicate_pad_numbers_are_jumpers no)
		(fp_poly
			(pts
				(xy -0.999299 0.504) (xy -0.999299 -0.503999) (xy 0.9993 -0.503999) (xy 0.9993 0.504)
			)
			(stroke
				(width 0)
				(type default)
			)
			(fill no)
			(layer "F.CrtYd")
		)
		(fp_line
			(start -0.499999 0.25)
			(end -0.499999 -0.249999)
			(stroke
				(width 0.1)
				(type default)
			)
			(layer "F.Fab")
		)
		(fp_line
			(start 0.499999 0.25)
			(end -0.499999 0.25)
			(stroke
				(width 0.1)
				(type default)
			)
			(layer "F.Fab")
		)
		(fp_line
			(start -0.499999 -0.249999)
			(end 0.499999 -0.249999)
			(stroke
				(width 0.1)
				(type default)
			)
			(layer "F.Fab")
		)
		(fp_line
			(start 0.499999 -0.249999)
			(end 0.499999 0.25)
			(stroke
				(width 0.1)
				(type default)
			)
			(layer "F.Fab")
		)
		(pad "1" smd rect
			(at -0.4572 0)
			(size 0.508 0.5842)
			(layers "F.Cu" "F.Mask" "F.Paste")
			(net "P3V3_40G_B1_VCC_TX")
		)
		(pad "2" smd rect
			(at 0.4572 0)
			(size 0.508 0.5842)
			(layers "F.Cu" "F.Mask" "F.Paste")
			(net "GND")
		)
	)
	(footprint ""
		(layer "F.Cu")
		(at -61.785401 44.869202 90)
		(property "Reference" "R41"
			(at 4.102202 0.228501 90)
			(unlocked yes)
			(layer "F.SilkS")
			(effects
				(font
					(size 0.762 0.5334)
					(thickness 0.1016)
				)
			)
		)
		(property "Value" ""
			(at 0 0 90)
			(layer "F.Fab")
			(effects
				(font
					(size 1.27 1.27)
				)
			)
		)
		(duplicate_pad_numbers_are_jumpers no)
		(fp_line
			(start 0 -0.381)
			(end 0 0.381)
			(stroke
				(width 0.127)
				(type default)
			)
			(layer "F.SilkS")
		)
		(fp_poly
			(pts
				(xy 1.255601 0.6564) (xy -1.2556 0.6564) (xy -1.2556 -0.656399) (xy 1.255601 -0.656399)
			)
			(stroke
				(width 0)
				(type default)
			)
			(fill no)
			(layer "F.CrtYd")
		)
		(fp_line
			(start 0.800001 -0.399999)
			(end -0.800001 -0.399999)
			(stroke
				(width 0.1)
				(type default)
			)
			(layer "F.Fab")
		)
		(fp_line
			(start -0.800001 -0.399999)
			(end -0.800001 0.399999)
			(stroke
				(width 0.1)
				(type default)
			)
			(layer "F.Fab")
		)
		(fp_line
			(start 0.800001 0.399999)
			(end 0.800001 -0.399999)
			(stroke
				(width 0.1)
				(type default)
			)
			(layer "F.Fab")
		)
		(fp_line
			(start -0.800001 0.399999)
			(end 0.800001 0.399999)
			(stroke
				(width 0.1)
				(type default)
			)
			(layer "F.Fab")
		)
		(pad "1" smd rect
			(at -0.650001 0 90)
			(size 0.7112 0.8128)
			(layers "F.Cu" "F.Mask" "F.Paste")
			(net "P3V3_B2_QSFP")
		)
		(pad "2" smd rect
			(at 0.650001 0 270)
			(size 0.7112 0.8128)
			(layers "F.Cu" "F.Mask" "F.Paste")
			(net "P3V3_10G_B2_VCCR")
		)
	)
	(footprint ""
		(layer "F.Cu")
		(at 1.749999 42.660001)
		(property "Reference" "MH6"
			(at 0 -4.9149 0)
			(unlocked yes)
			(layer "F.SilkS")
			(effects
				(font
					(size 0.762 0.5334)
					(thickness 0.1016)
				)
			)
		)
		(property "Value" ""
			(at 0 0 0)
			(layer "F.Fab")
			(effects
				(font
					(size 1.27 1.27)
				)
			)
		)
		(duplicate_pad_numbers_are_jumpers no)
		(fp_poly
			(pts
				(arc
					(start 4.0132 0)
					(mid -4.0132 0)
					(end 4.0132 0)
				)
			)
			(stroke
				(width 0)
				(type default)
			)
			(fill no)
			(layer "B.CrtYd")
		)
		(fp_poly
			(pts
				(arc
					(start 4.0132 0)
					(mid -4.0132 0)
					(end 4.0132 0)
				)
			)
			(stroke
				(width 0)
				(type default)
			)
			(fill no)
			(layer "F.CrtYd")
		)
		(pad "1" thru_hole circle
			(at 0 0)
			(size 7.0104 7.0104)
			(drill 3.5052)
			(layers "*.Cu" "*.Mask")
			(remove_unused_layers no)
			(net "GND")
			(padstack
				(mode front_inner_back)
				(layer "Inner"
					(shape circle)
					(size 4.5212 4.5212)
				)
				(layer "B.Cu"
					(shape circle)
					(size 7.0104 7.0104)
				)
			)
		)
		(pad "2" thru_hole circle
			(at 0 -2.794)
			(size 0.6604 0.6604)
			(drill 0.3556)
			(layers "*.Cu" "*.Mask")
			(remove_unused_layers no)
			(net "GND")
		)
		(pad "3" thru_hole circle
			(at -1.905 -2.032)
			(size 0.6604 0.6604)
			(drill 0.3556)
			(layers "*.Cu" "*.Mask")
			(remove_unused_layers no)
			(net "GND")
		)
		(pad "4" thru_hole circle
			(at -2.794 0)
			(size 0.6604 0.6604)
			(drill 0.3556)
			(layers "*.Cu" "*.Mask")
			(remove_unused_layers no)
			(net "GND")
		)
		(pad "5" thru_hole circle
			(at -2.032 1.905)
			(size 0.6604 0.6604)
			(drill 0.3556)
			(layers "*.Cu" "*.Mask")
			(remove_unused_layers no)
			(net "GND")
		)
		(pad "6" thru_hole circle
			(at 0 2.794)
			(size 0.6604 0.6604)
			(drill 0.3556)
			(layers "*.Cu" "*.Mask")
			(remove_unused_layers no)
			(net "GND")
		)
		(pad "7" thru_hole circle
			(at 2.032 1.905)
			(size 0.6604 0.6604)
			(drill 0.3556)
			(layers "*.Cu" "*.Mask")
			(remove_unused_layers no)
			(net "GND")
		)
		(pad "8" thru_hole circle
			(at 2.794 0)
			(size 0.6604 0.6604)
			(drill 0.3556)
			(layers "*.Cu" "*.Mask")
			(remove_unused_layers no)
			(net "GND")
		)
		(pad "9" thru_hole circle
			(at 1.905 -2.032)
			(size 0.6604 0.6604)
			(drill 0.3556)
			(layers "*.Cu" "*.Mask")
			(remove_unused_layers no)
			(net "GND")
		)
	)
	(footprint ""
		(layer "F.Cu")
		(at -45.109699 20.000001)
		(property "Reference" "MH5"
			(at 0.011999 -4.229141 0)
			(unlocked yes)
			(layer "F.SilkS")
			(effects
				(font
					(size 0.762 0.5334)
					(thickness 0.1016)
				)
			)
		)
		(property "Value" ""
			(at 0 0 0)
			(layer "F.Fab")
			(effects
				(font
					(size 1.27 1.27)
				)
			)
		)
		(duplicate_pad_numbers_are_jumpers no)
		(fp_poly
			(pts
				(arc
					(start 4.0132 0)
					(mid -4.0132 0)
					(end 4.0132 0)
				)
			)
			(stroke
				(width 0)
				(type default)
			)
			(fill no)
			(layer "B.CrtYd")
		)
		(fp_poly
			(pts
				(arc
					(start 4.0132 0)
					(mid -4.0132 0)
					(end 4.0132 0)
				)
			)
			(stroke
				(width 0)
				(type default)
			)
			(fill no)
			(layer "F.CrtYd")
		)
		(pad "1" thru_hole circle
			(at 0 0)
			(size 7.0104 7.0104)
			(drill 3.5052)
			(layers "*.Cu" "*.Mask")
			(remove_unused_layers no)
			(net "GND")
			(padstack
				(mode front_inner_back)
				(layer "Inner"
					(shape circle)
					(size 4.5212 4.5212)
				)
				(layer "B.Cu"
					(shape circle)
					(size 7.0104 7.0104)
				)
			)
		)
		(pad "2" thru_hole circle
			(at 0 -2.794)
			(size 0.6604 0.6604)
			(drill 0.3556)
			(layers "*.Cu" "*.Mask")
			(remove_unused_layers no)
			(net "GND")
		)
		(pad "3" thru_hole circle
			(at -1.905 -2.032)
			(size 0.6604 0.6604)
			(drill 0.3556)
			(layers "*.Cu" "*.Mask")
			(remove_unused_layers no)
			(net "GND")
		)
		(pad "4" thru_hole circle
			(at -2.794 0)
			(size 0.6604 0.6604)
			(drill 0.3556)
			(layers "*.Cu" "*.Mask")
			(remove_unused_layers no)
			(net "GND")
		)
		(pad "5" thru_hole circle
			(at -2.032 1.905)
			(size 0.6604 0.6604)
			(drill 0.3556)
			(layers "*.Cu" "*.Mask")
			(remove_unused_layers no)
			(net "GND")
		)
		(pad "6" thru_hole circle
			(at 0 2.794)
			(size 0.6604 0.6604)
			(drill 0.3556)
			(layers "*.Cu" "*.Mask")
			(remove_unused_layers no)
			(net "GND")
		)
		(pad "7" thru_hole circle
			(at 2.032 1.905)
			(size 0.6604 0.6604)
			(drill 0.3556)
			(layers "*.Cu" "*.Mask")
			(remove_unused_layers no)
			(net "GND")
		)
		(pad "8" thru_hole circle
			(at 2.794 0)
			(size 0.6604 0.6604)
			(drill 0.3556)
			(layers "*.Cu" "*.Mask")
			(remove_unused_layers no)
			(net "GND")
		)
		(pad "9" thru_hole circle
			(at 1.905 -2.032)
			(size 0.6604 0.6604)
			(drill 0.3556)
			(layers "*.Cu" "*.Mask")
			(remove_unused_layers no)
			(net "GND")
		)
	)
	(footprint ""
		(layer "F.Cu")
		(at -45.631001 13.297002)
		(property "Reference" "R60"
			(at 0.419001 1.219098 0)
			(unlocked yes)
			(layer "F.SilkS")
			(effects
				(font
					(size 0.762 0.5334)
					(thickness 0.1016)
				)
			)
		)
		(property "Value" ""
			(at 0 0 0)
			(layer "F.Fab")
			(effects
				(font
					(size 1.27 1.27)
				)
			)
		)
		(duplicate_pad_numbers_are_jumpers no)
		(fp_line
			(start 0 -0.381)
			(end 0 0.381)
			(stroke
				(width 0.127)
				(type default)
			)
			(layer "F.SilkS")
		)
		(fp_poly
			(pts
				(xy 1.255601 0.656399) (xy -1.255601 0.656399) (xy -1.255601 -0.6564) (xy 1.255601 -0.6564)
			)
			(stroke
				(width 0)
				(type default)
			)
			(fill no)
			(layer "F.CrtYd")
		)
		(fp_line
			(start -0.800001 -0.4)
			(end -0.800001 0.399999)
			(stroke
				(width 0.1)
				(type default)
			)
			(layer "F.Fab")
		)
		(fp_line
			(start -0.800001 0.399999)
			(end 0.800001 0.399999)
			(stroke
				(width 0.1)
				(type default)
			)
			(layer "F.Fab")
		)
		(fp_line
			(start 0.800001 -0.4)
			(end -0.800001 -0.4)
			(stroke
				(width 0.1)
				(type default)
			)
			(layer "F.Fab")
		)
		(fp_line
			(start 0.800001 0.399999)
			(end 0.800001 -0.4)
			(stroke
				(width 0.1)
				(type default)
			)
			(layer "F.Fab")
		)
		(pad "1" smd rect
			(at -0.650001 0)
			(size 0.7112 0.8128)
			(layers "F.Cu" "F.Mask" "F.Paste")
			(net "P3V3_40G_B2_VCC1")
		)
		(pad "2" smd rect
			(at 0.650001 0 180)
			(size 0.7112 0.8128)
			(layers "F.Cu" "F.Mask" "F.Paste")
			(net "P3V3_B2_QSFP")
		)
	)
	(footprint ""
		(layer "F.Cu")
		(at -46.774001 9.233002 -90)
		(property "Reference" "C19"
			(at 0.713638 -1.447701 0)
			(unlocked yes)
			(layer "F.SilkS")
			(effects
				(font
					(size 0.762 0.5334)
					(thickness 0.1016)
				)
			)
		)
		(property "Value" ""
			(at 0 0 270)
			(layer "F.Fab")
			(effects
				(font
					(size 1.27 1.27)
				)
			)
		)
		(duplicate_pad_numbers_are_jumpers no)
		(fp_poly
			(pts
				(xy -0.9993 0.503999) (xy -0.9993 -0.504) (xy 0.999299 -0.504) (xy 0.999299 0.503999)
			)
			(stroke
				(width 0)
				(type default)
			)
			(fill no)
			(layer "F.CrtYd")
		)
		(fp_line
			(start -0.499999 0.249999)
			(end -0.499999 -0.25)
			(stroke
				(width 0.1)
				(type default)
			)
			(layer "F.Fab")
		)
		(fp_line
			(start 0.499999 0.249999)
			(end -0.499999 0.249999)
			(stroke
				(width 0.1)
				(type default)
			)
			(layer "F.Fab")
		)
		(fp_line
			(start -0.499999 -0.25)
			(end 0.499999 -0.25)
			(stroke
				(width 0.1)
				(type default)
			)
			(layer "F.Fab")
		)
		(fp_line
			(start 0.499999 -0.25)
			(end 0.499999 0.249999)
			(stroke
				(width 0.1)
				(type default)
			)
			(layer "F.Fab")
		)
		(pad "1" smd rect
			(at -0.4572 0)
			(size 0.508 0.5842)
			(layers "F.Cu" "F.Mask" "F.Paste")
			(net "P3V3_40G_B2_VCC_TX")
		)
		(pad "2" smd rect
			(at 0.4572 0)
			(size 0.508 0.5842)
			(layers "F.Cu" "F.Mask" "F.Paste")
			(net "GND")
		)
	)
	(footprint ""
		(layer "F.Cu")
		(at -75.292801 6.591402)
		(property "Reference" "R48"
			(at 2.902801 0.050698 0)
			(unlocked yes)
			(layer "F.SilkS")
			(effects
				(font
					(size 0.762 0.5334)
					(thickness 0.1016)
				)
			)
		)
		(property "Value" ""
			(at 0 0 0)
			(layer "F.Fab")
			(effects
				(font
					(size 1.27 1.27)
				)
			)
		)
		(duplicate_pad_numbers_are_jumpers no)
		(fp_line
			(start 0 -0.381)
			(end 0 0.381)
			(stroke
				(width 0.127)
				(type default)
			)
			(layer "F.SilkS")
		)
		(fp_poly
			(pts
				(xy 1.255601 0.656399) (xy -1.255601 0.656399) (xy -1.255601 -0.6564) (xy 1.255601 -0.6564)
			)
			(stroke
				(width 0)
				(type default)
			)
			(fill no)
			(layer "F.CrtYd")
		)
		(fp_line
			(start -0.800001 -0.4)
			(end -0.800001 0.399999)
			(stroke
				(width 0.1)
				(type default)
			)
			(layer "F.Fab")
		)
		(fp_line
			(start -0.800001 0.399999)
			(end 0.800001 0.399999)
			(stroke
				(width 0.1)
				(type default)
			)
			(layer "F.Fab")
		)
		(fp_line
			(start 0.800001 -0.4)
			(end -0.800001 -0.4)
			(stroke
				(width 0.1)
				(type default)
			)
			(layer "F.Fab")
		)
		(fp_line
			(start 0.800001 0.399999)
			(end 0.800001 -0.4)
			(stroke
				(width 0.1)
				(type default)
			)
			(layer "F.Fab")
		)
		(pad "1" smd rect
			(at -0.650001 0)
			(size 0.7112 0.8128)
			(layers "F.Cu" "F.Mask" "F.Paste")
			(net "P3V3_B2_QSFP")
		)
		(pad "2" smd rect
			(at 0.650001 0 180)
			(size 0.7112 0.8128)
			(layers "F.Cu" "F.Mask" "F.Paste")
			(net "ETH10G_B2_TX_DIS")
		)
	)
	(footprint ""
		(layer "F.Cu")
		(at -411.66 -5.840001 180)
		(property "Reference" "U1"
			(at -20.627 -12.228101 0)
			(unlocked yes)
			(layer "F.SilkS")
			(effects
				(font
					(size 0.762 0.5334)
					(thickness 0.1016)
				)
			)
		)
		(property "Value" ""
			(at 0 0 180)
			(layer "F.Fab")
			(effects
				(font
					(size 1.27 1.27)
				)
			)
		)
		(duplicate_pad_numbers_are_jumpers no)
		(fp_poly
			(pts
				(xy -42.28 0.499999) (xy -42.28 -11.000001)
				(arc
					(start -1.3038 -11.000001)
					(mid 0 -11.99996)
					(end 1.303799 -11.000001)
				)
				(xy 11.799999 -11.000001) (xy 11.799999 0.499999)
			)
			(stroke
				(width 0)
				(type default)
			)
			(fill no)
			(layer "B.CrtYd")
		)
		(fp_poly
			(pts
				(xy -42.28 0.499999) (xy -42.28 -11.000001)
				(arc
					(start -1.3038 -11.000001)
					(mid 0 -11.99996)
					(end 1.303799 -11.000001)
				)
				(xy 11.799999 -11.000001) (xy 11.799999 0.499999)
			)
			(stroke
				(width 0)
				(type default)
			)
			(fill no)
			(layer "F.CrtYd")
		)
		(fp_line
			(start 10.800001 0)
			(end -41.280002 0)
			(stroke
				(width 0.1)
				(type default)
			)
			(layer "F.Fab")
		)
		(fp_line
			(start 10.800001 -11.000001)
			(end 10.800001 0)
			(stroke
				(width 0.1)
				(type default)
			)
			(layer "F.Fab")
		)
		(fp_line
			(start -41.280002 0)
			(end -41.280002 -11.000001)
			(stroke
				(width 0.1)
				(type default)
			)
			(layer "F.Fab")
		)
		(fp_line
			(start -41.280002 -11.000001)
			(end 10.800001 -11.000001)
			(stroke
				(width 0.1)
				(type default)
			)
			(layer "F.Fab")
		)
		(fp_text user "S6"
			(at 8.66552 -9.572899 90)
			(unlocked yes)
			(layer "F.SilkS")
			(effects
				(font
					(size 0.762 0.5334)
					(thickness 0.1016)
				)
				(justify left)
			)
		)
		(fp_text user "S1"
			(at 2.31552 -9.572899 90)
			(unlocked yes)
			(layer "F.SilkS")
			(effects
				(font
					(size 0.762 0.5334)
					(thickness 0.1016)
				)
				(justify left)
			)
		)
		(fp_text user "*"
			(at 1.344 -8.716551 0)
			(unlocked yes)
			(layer "F.SilkS")
			(effects
				(font
					(size 0.381 0.381)
					(thickness 0.381)
				)
			)
		)
		(fp_text user "P13-P16"
			(at -4.625 -9.942101 0)
			(unlocked yes)
			(layer "F.SilkS")
			(effects
				(font
					(size 0.762 0.5334)
					(thickness 0.1016)
				)
			)
		)
		(fp_text user "P9-P12"
			(at -16.309 -9.942101 0)
			(unlocked yes)
			(layer "F.SilkS")
			(effects
				(font
					(size 0.762 0.5334)
					(thickness 0.1016)
				)
			)
		)
		(fp_text user "P5-P8"
			(at -26.52996 -9.586501 0)
			(unlocked yes)
			(layer "F.SilkS")
			(effects
				(font
					(size 0.762 0.5334)
					(thickness 0.1016)
				)
			)
		)
		(fp_text user "P1-P4"
			(at -35.4352 -9.632221 0)
			(unlocked yes)
			(layer "F.SilkS")
			(effects
				(font
					(size 0.762 0.5334)
					(thickness 0.1016)
				)
			)
		)
		(fp_text user "S7"
			(at 7.948 -9.307101 0)
			(unlocked yes)
			(layer "B.SilkS")
			(effects
				(font
					(size 0.762 0.5334)
					(thickness 0.1016)
				)
				(justify left mirror)
			)
		)
		(fp_text user "S12"
			(at 1.979 -9.561101 0)
			(unlocked yes)
			(layer "B.SilkS")
			(effects
				(font
					(size 0.762 0.5334)
					(thickness 0.1016)
				)
				(justify left mirror)
			)
		)
		(fp_text user "P17-P20"
			(at -5.133 -10.323101 0)
			(unlocked yes)
			(layer "B.SilkS")
			(effects
				(font
					(size 0.762 0.5334)
					(thickness 0.1016)
				)
				(justify mirror)
			)
		)
		(fp_text user "P21-P24"
			(at -15.547 -10.196101 0)
			(unlocked yes)
			(layer "B.SilkS")
			(effects
				(font
					(size 0.762 0.5334)
					(thickness 0.1016)
				)
				(justify mirror)
			)
		)
		(fp_text user "P25-P28"
			(at -26.12102 -9.586501 0)
			(unlocked yes)
			(layer "B.SilkS")
			(effects
				(font
					(size 0.762 0.5334)
					(thickness 0.1016)
				)
				(justify mirror)
			)
		)
		(fp_text user "P29-P32"
			(at -35.87462 -9.632221 0)
			(unlocked yes)
			(layer "B.SilkS")
			(effects
				(font
					(size 0.762 0.5334)
					(thickness 0.1016)
				)
				(justify mirror)
			)
		)
		(pad "P1-P4" smd rect
			(at -35.56 -4.650001 180)
			(size 9.4488 6.2992)
			(layers "F.Cu" "F.Mask" "F.Paste")
			(net "GND")
		)
		(pad "P5-P8" smd rect
			(at -25.4 -4.650001 180)
			(size 9.4488 6.2992)
			(layers "F.Cu" "F.Mask" "F.Paste")
			(net "GND")
		)
		(pad "P9-P12" smd rect
			(at -15.24 -4.650001 180)
			(size 9.4488 6.2992)
			(layers "F.Cu" "F.Mask" "F.Paste")
			(net "P12V")
		)
		(pad "P13-P16" smd rect
			(at -5.08 -4.650001 180)
			(size 9.4488 6.2992)
			(layers "F.Cu" "F.Mask" "F.Paste")
			(net "P12V")
		)
		(pad "P17-P20" smd rect
			(at -5.08 -4.650001 180)
			(size 9.4488 6.2992)
			(layers "F.Cu" "F.Mask" "F.Paste")
			(net "P12V")
		)
		(pad "P21-P24" smd rect
			(at -15.24 -4.650001 180)
			(size 9.4488 6.2992)
			(layers "F.Cu" "F.Mask" "F.Paste")
			(net "P12V")
		)
		(pad "P25-P28" smd rect
			(at -25.4 -4.650001 180)
			(size 9.4488 6.2992)
			(layers "F.Cu" "F.Mask" "F.Paste")
			(net "GND")
		)
		(pad "P29-P32" smd rect
			(at -35.56 -4.650001 180)
			(size 9.4488 6.2992)
			(layers "F.Cu" "F.Mask" "F.Paste")
			(net "GND")
		)
		(pad "S1" smd rect
			(at 2.230001 -4 180)
			(size 0.8128 5.0038)
			(layers "F.Cu" "F.Mask" "F.Paste")
			(net "SERIAL_B1_TX1")
		)
		(pad "S2" smd rect
			(at 3.500001 -4 180)
			(size 0.8128 5.0038)
			(layers "F.Cu" "F.Mask" "F.Paste")
			(net "SERIAL_B1_RX1")
		)
		(pad "S3" smd rect
			(at 4.770001 -4 180)
			(size 0.8128 5.0038)
			(layers "F.Cu" "F.Mask" "F.Paste")
			(net "BLADE_B1_EN1")
		)
		(pad "S4" smd rect
			(at 6.040001 -4 180)
			(size 0.8128 5.0038)
			(layers "F.Cu" "F.Mask" "F.Paste")
			(net "PSU_B1_ALERT_N")
		)
		(pad "S5" smd rect
			(at 7.310001 -4 180)
			(size 0.8128 5.0038)
			(layers "F.Cu" "F.Mask" "F.Paste")
			(net "SERIAL_B1_TX2")
		)
		(pad "S6" smd rect
			(at 8.580001 -4 180)
			(size 0.8128 5.0038)
			(layers "F.Cu" "F.Mask" "F.Paste")
			(net "SERIAL_B1_RX2")
		)
		(pad "S7" smd rect
			(at 8.580001 -4 180)
			(size 0.8128 5.0038)
			(layers "F.Cu" "F.Mask" "F.Paste")
			(net "SERIAL_B2_RX2")
		)
		(pad "S8" smd rect
			(at 7.310001 -4 180)
			(size 0.8128 5.0038)
			(layers "F.Cu" "F.Mask" "F.Paste")
			(net "SERIAL_B2_TX2")
		)
		(pad "S9" smd rect
			(at 6.040001 -4 180)
			(size 0.8128 5.0038)
			(layers "F.Cu" "F.Mask" "F.Paste")
			(net "PSU_B2_ALERT_N")
		)
		(pad "S10" smd rect
			(at 4.770001 -4 180)
			(size 0.8128 5.0038)
			(layers "F.Cu" "F.Mask" "F.Paste")
			(net "BLADE_B2_EN1")
		)
		(pad "S11" smd rect
			(at 3.500001 -4 180)
			(size 0.8128 5.0038)
			(layers "F.Cu" "F.Mask" "F.Paste")
			(net "SERIAL_B2_RX1")
		)
		(pad "S12" smd rect
			(at 2.230001 -4 180)
			(size 0.8128 5.0038)
			(layers "F.Cu" "F.Mask" "F.Paste")
			(net "SERIAL_B2_TX1")
		)
		(zone
			(layers "F.Cu" "B.Cu" "In1.Cu" "In2.Cu" "In3.Cu" "In4.Cu" "In5.Cu" "In6.Cu")
			(hatch none 0.5)
			(connect_pads
				(clearance 0)
			)
			(min_thickness 0.25)
			(keepout
				(tracks allowed)
				(vias not_allowed)
				(pads allowed)
				(copperpour not_allowed)
				(footprints allowed)
			)
			(placement
				(enabled no)
				(sheetname "")
			)
			(fill
				(thermal_gap 0.5)
				(thermal_bridge_width 0.5)
				(island_removal_mode 0)
			)
			(polygon
				(pts
					(xy -371.9 -5.790001) (xy -370.430001 -4.320002) (xy -370.430001 2.413) (xy -410.3878 2.413) (xy -410.759999 2.785199)
					(xy -410.759999 4.159999)
					(arc
						(start -410.759999 5.16)
						(mid -411.66 5.76)
						(end -412.56 5.16)
					)
					(xy -412.56 4.159999) (xy -422.409998 4.159999) (xy -422.409998 -4.320002) (xy -420.939999 -5.790001)
					(xy -413.509998 -5.790001) (xy -412.059999 -4.340001)
					(arc
						(start -412.059999 4.809998)
						(mid -411.66 5.209997)
						(end -411.26 4.809998)
					)
					(xy -411.26 -4.340001) (xy -409.810001 -5.790001)
				)
			)
		)
	)
	(footprint ""
		(layer "F.Cu")
		(at -344.551 4.7244 -90)
		(property "Reference" "R11"
			(at -0.05588 1.39954 90)
			(unlocked yes)
			(layer "F.SilkS")
			(effects
				(font
					(size 0.762 0.5334)
					(thickness 0.1016)
				)
			)
		)
		(property "Value" ""
			(at 0 0 270)
			(layer "F.Fab")
			(effects
				(font
					(size 1.27 1.27)
				)
			)
		)
		(duplicate_pad_numbers_are_jumpers no)
		(fp_line
			(start 0 -0.381)
			(end 0 0.381)
			(stroke
				(width 0.127)
				(type default)
			)
			(layer "F.SilkS")
		)
		(fp_poly
			(pts
				(xy 1.255601 0.6564) (xy -1.255601 0.6564) (xy -1.255601 -0.656399) (xy 1.255601 -0.656399)
			)
			(stroke
				(width 0)
				(type default)
			)
			(fill no)
			(layer "F.CrtYd")
		)
		(fp_line
			(start -0.800001 0.399999)
			(end 0.800001 0.399999)
			(stroke
				(width 0.1)
				(type default)
			)
			(layer "F.Fab")
		)
		(fp_line
			(start 0.800001 0.399999)
			(end 0.800001 -0.399999)
			(stroke
				(width 0.1)
				(type default)
			)
			(layer "F.Fab")
		)
		(fp_line
			(start -0.800001 -0.399999)
			(end -0.800001 0.399999)
			(stroke
				(width 0.1)
				(type default)
			)
			(layer "F.Fab")
		)
		(fp_line
			(start 0.800001 -0.399999)
			(end -0.800001 -0.399999)
			(stroke
				(width 0.1)
				(type default)
			)
			(layer "F.Fab")
		)
		(pad "1" smd rect
			(at -0.650001 0 270)
			(size 0.7112 0.8128)
			(layers "F.Cu" "F.Mask" "F.Paste")
			(net "UNNAMED_4_1X2HDR_I90_IO")
		)
		(pad "2" smd rect
			(at 0.650001 0 90)
			(size 0.7112 0.8128)
			(layers "F.Cu" "F.Mask" "F.Paste")
			(net "GND")
		)
	)
	(footprint ""
		(layer "F.Cu")
		(at -80.0862 1.8542)
		(property "Reference" "R43"
			(at -3.7338 -0.1651 0)
			(unlocked yes)
			(layer "F.SilkS")
			(effects
				(font
					(size 0.762 0.5334)
					(thickness 0.1016)
				)
			)
		)
		(property "Value" ""
			(at 0 0 0)
			(layer "F.Fab")
			(effects
				(font
					(size 1.27 1.27)
				)
			)
		)
		(duplicate_pad_numbers_are_jumpers no)
		(fp_line
			(start 0 -0.381)
			(end 0 0.381)
			(stroke
				(width 0.127)
				(type default)
			)
			(layer "F.SilkS")
		)
		(fp_poly
			(pts
				(xy 1.255601 0.6564) (xy -1.255601 0.6564) (xy -1.255601 -0.656399) (xy 1.255601 -0.656399)
			)
			(stroke
				(width 0)
				(type default)
			)
			(fill no)
			(layer "F.CrtYd")
		)
		(fp_line
			(start -0.800001 -0.399999)
			(end -0.800001 0.399999)
			(stroke
				(width 0.1)
				(type default)
			)
			(layer "F.Fab")
		)
		(fp_line
			(start -0.800001 0.399999)
			(end 0.800001 0.399999)
			(stroke
				(width 0.1)
				(type default)
			)
			(layer "F.Fab")
		)
		(fp_line
			(start 0.800001 -0.399999)
			(end -0.800001 -0.399999)
			(stroke
				(width 0.1)
				(type default)
			)
			(layer "F.Fab")
		)
		(fp_line
			(start 0.800001 0.399999)
			(end 0.800001 -0.399999)
			(stroke
				(width 0.1)
				(type default)
			)
			(layer "F.Fab")
		)
		(pad "1" smd rect
			(at -0.650001 0)
			(size 0.7112 0.8128)
			(layers "F.Cu" "F.Mask" "F.Paste")
			(net "ETH10G_B2_PRES_N")
		)
		(pad "2" smd rect
			(at 0.650001 0 180)
			(size 0.7112 0.8128)
			(layers "F.Cu" "F.Mask" "F.Paste")
			(net "ETH10G_B2_MOD_ABS")
		)
	)
	(footprint ""
		(layer "F.Cu")
		(at -199.4408 21.1074 -90)
		(property "Reference" "J27"
			(at -1.2573 -5.3848 0)
			(unlocked yes)
			(layer "F.SilkS")
			(effects
				(font
					(size 0.762 0.5334)
					(thickness 0.1016)
				)
			)
		)
		(property "Value" ""
			(at 0 0 270)
			(layer "F.Fab")
			(effects
				(font
					(size 1.27 1.27)
				)
			)
		)
		(duplicate_pad_numbers_are_jumpers no)
		(fp_line
			(start 0.499999 8.75)
			(end 0.499999 7.350001)
			(stroke
				(width 0.127)
				(type default)
			)
			(layer "F.SilkS")
		)
		(fp_line
			(start 3.7 8.75)
			(end 0.499999 8.75)
			(stroke
				(width 0.127)
				(type default)
			)
			(layer "F.SilkS")
		)
		(fp_line
			(start -2.7 7.350001)
			(end -0.700001 7.350001)
			(stroke
				(width 0.127)
				(type default)
			)
			(layer "F.SilkS")
		)
		(fp_line
			(start 3.7 7.350001)
			(end 3.7 8.75)
			(stroke
				(width 0.127)
				(type default)
			)
			(layer "F.SilkS")
		)
		(fp_line
			(start 4.9 7.350001)
			(end 6.899999 7.350001)
			(stroke
				(width 0.127)
				(type default)
			)
			(layer "F.SilkS")
		)
		(fp_line
			(start 6.899999 7.350001)
			(end 6.899999 5.349999)
			(stroke
				(width 0.127)
				(type default)
			)
			(layer "F.SilkS")
		)
		(fp_line
			(start -2.7 5.349999)
			(end -2.7 7.350001)
			(stroke
				(width 0.127)
				(type default)
			)
			(layer "F.SilkS")
		)
		(fp_line
			(start 6.899999 -0.249999)
			(end 6.899999 -2.250001)
			(stroke
				(width 0.127)
				(type default)
			)
			(layer "F.SilkS")
		)
		(fp_line
			(start -2.7 -2.250001)
			(end -2.7 -0.249999)
			(stroke
				(width 0.127)
				(type default)
			)
			(layer "F.SilkS")
		)
		(fp_line
			(start -0.700001 -2.250001)
			(end -2.7 -2.250001)
			(stroke
				(width 0.127)
				(type default)
			)
			(layer "F.SilkS")
		)
		(fp_line
			(start 6.899999 -2.250001)
			(end 4.9 -2.250001)
			(stroke
				(width 0.127)
				(type default)
			)
			(layer "F.SilkS")
		)
		(fp_poly
			(pts
				(arc
					(start 9.728799 5.1962)
					(mid 8.255565 9.269839)
					(end 4.3002 11.036201)
				)
				(arc
					(start 4.099499 11.036201)
					(mid 4.005521 11.033698)
					(end 3.9116 11.029599)
				)
				(xy 0.289999 11.029599) (xy 0.282001 11.030001) (xy 0.280101 11.030001)
				(arc
					(start 0.279999 11.0301)
					(mid 0.20252 11.033493)
					(end 0.125001 11.0358)
				)
				(arc
					(start -0.125199 11.0358)
					(mid -3.994922 9.33426)
					(end -5.536301 5.398)
				)
				(arc
					(start -5.536301 0.099799)
					(mid -3.939989 -3.890625)
					(end 0.03 -5.537101)
				)
				(xy 4.1029 -5.537101)
				(arc
					(start 4.1037 -5.536301)
					(mid 8.186368 -3.843008)
					(end 9.729099 0.2989)
				)
				(xy 9.729099 5.1959)
			)
			(stroke
				(width 0)
				(type default)
			)
			(fill no)
			(layer "B.CrtYd")
		)
		(fp_poly
			(pts
				(xy -3.200001 -2.75) (xy 7.4 -2.75) (xy 7.4 7.85) (xy -3.200001 7.85)
			)
			(stroke
				(width 0)
				(type default)
			)
			(fill no)
			(layer "F.CrtYd")
		)
		(fp_line
			(start -2.7 7.350001)
			(end -2.7 -2.250001)
			(stroke
				(width 0.1)
				(type default)
			)
			(layer "F.Fab")
		)
		(fp_line
			(start 6.899999 7.350001)
			(end -2.7 7.350001)
			(stroke
				(width 0.1)
				(type default)
			)
			(layer "F.Fab")
		)
		(fp_line
			(start -2.7 -2.250001)
			(end 6.899999 -2.250001)
			(stroke
				(width 0.1)
				(type default)
			)
			(layer "F.Fab")
		)
		(fp_line
			(start 6.899999 -2.250001)
			(end 6.899999 7.350001)
			(stroke
				(width 0.1)
				(type default)
			)
			(layer "F.Fab")
		)
		(fp_text user "3"
			(at -0.21336 8.11784 0)
			(unlocked yes)
			(layer "F.SilkS")
			(effects
				(font
					(size 0.762 0.5334)
					(thickness 0.1016)
				)
			)
		)
		(fp_text user "4"
			(at 4.42468 7.9883 0)
			(unlocked yes)
			(layer "F.SilkS")
			(effects
				(font
					(size 0.762 0.5334)
					(thickness 0.1016)
				)
			)
		)
		(fp_text user "2"
			(at 4.23164 -2.96164 0)
			(unlocked yes)
			(layer "F.SilkS")
			(effects
				(font
					(size 0.762 0.5334)
					(thickness 0.1016)
				)
			)
		)
		(fp_text user "*"
			(at 0.2286 -4.54025 270)
			(unlocked yes)
			(layer "F.SilkS")
			(effects
				(font
					(size 0.381 0.381)
					(thickness 0.381)
				)
			)
		)
		(fp_text user "3"
			(at 0 7.4071 270)
			(unlocked yes)
			(layer "B.SilkS")
			(effects
				(font
					(size 0.762 0.5334)
					(thickness 0.1016)
				)
				(justify mirror)
			)
		)
		(fp_text user "4"
			(at 4.249999 7.4071 270)
			(unlocked yes)
			(layer "B.SilkS")
			(effects
				(font
					(size 0.762 0.5334)
					(thickness 0.1016)
				)
				(justify mirror)
			)
		)
		(fp_text user "2"
			(at 4.199999 -1.867901 270)
			(unlocked yes)
			(layer "B.SilkS")
			(effects
				(font
					(size 0.762 0.5334)
					(thickness 0.1016)
				)
				(justify mirror)
			)
		)
		(fp_text user "*"
			(at 0 -1.94645 270)
			(unlocked yes)
			(layer "B.SilkS")
			(effects
				(font
					(size 0.381 0.381)
					(thickness 0.381)
				)
			)
		)
		(pad "1" thru_hole rect
			(at 0 0 270)
			(size 2.0066 2.0066)
			(drill 1.397)
			(layers "*.Cu" "*.Mask")
			(remove_unused_layers no)
			(net "P12V")
			(padstack
				(mode front_inner_back)
				(layer "Inner"
					(shape circle)
					(size 2.0066 2.0066)
				)
				(layer "B.Cu"
					(shape rect)
					(size 2.0066 2.0066)
				)
			)
		)
		(pad "2" thru_hole circle
			(at 4.199999 0 270)
			(size 2.0066 2.0066)
			(drill 1.397)
			(layers "*.Cu" "*.Mask")
			(remove_unused_layers no)
			(net "GND")
		)
		(pad "3" thru_hole circle
			(at 0 5.499999 270)
			(size 2.0066 2.0066)
			(drill 1.397)
			(layers "*.Cu" "*.Mask")
			(remove_unused_layers no)
			(net "P12V")
		)
		(pad "4" thru_hole circle
			(at 4.199999 5.499999 270)
			(size 2.0066 2.0066)
			(drill 1.397)
			(layers "*.Cu" "*.Mask")
			(remove_unused_layers no)
			(net "GND")
		)
	)
	(footprint ""
		(layer "F.Cu")
		(at -339.3694 2.794 -90)
		(property "Reference" "J26"
			(at -0.69596 3.93954 90)
			(unlocked yes)
			(layer "F.SilkS")
			(effects
				(font
					(size 0.762 0.5334)
					(thickness 0.1016)
				)
			)
		)
		(property "Value" ""
			(at 0 0 270)
			(layer "F.Fab")
			(effects
				(font
					(size 1.27 1.27)
				)
			)
		)
		(duplicate_pad_numbers_are_jumpers no)
		(fp_line
			(start -2.54 1.27)
			(end 0.127 1.27)
			(stroke
				(width 0.127)
				(type default)
			)
			(layer "F.SilkS")
		)
		(fp_line
			(start 2.443175 1.257198)
			(end 2.570175 1.257198)
			(stroke
				(width 0.127)
				(type default)
			)
			(layer "F.SilkS")
		)
		(fp_line
			(start 2.570175 1.257198)
			(end 2.570175 -1.282802)
			(stroke
				(width 0.127)
				(type default)
			)
			(layer "F.SilkS")
		)
		(fp_line
			(start -2.54 -1.27)
			(end -2.54 1.27)
			(stroke
				(width 0.127)
				(type default)
			)
			(layer "F.SilkS")
		)
		(fp_line
			(start -2.413 -1.27)
			(end -2.54 -1.27)
			(stroke
				(width 0.127)
				(type default)
			)
			(layer "F.SilkS")
		)
		(fp_line
			(start 2.570175 -1.282802)
			(end -0.096825 -1.282802)
			(stroke
				(width 0.127)
				(type default)
			)
			(layer "F.SilkS")
		)
		(fp_poly
			(pts
				(xy 0.127 3.683) (xy 0.127 1.778) (xy -3.048 1.778) (xy -3.048 -1.778) (xy -2.413 -1.778) (xy -2.413 -3.683)
				(xy -0.127 -3.683) (xy -0.127 -1.778) (xy 3.048 -1.778) (xy 3.048 1.778) (xy 2.413 1.778) (xy 2.413 3.683)
			)
			(stroke
				(width 0)
				(type default)
			)
			(fill no)
			(layer "F.CrtYd")
		)
		(fp_line
			(start -2.54 1.27)
			(end -2.54 -1.27)
			(stroke
				(width 0.1)
				(type default)
			)
			(layer "F.Fab")
		)
		(fp_line
			(start 2.54 1.27)
			(end -2.54 1.27)
			(stroke
				(width 0.1)
				(type default)
			)
			(layer "F.Fab")
		)
		(fp_line
			(start -2.54 -1.27)
			(end 2.54 -1.27)
			(stroke
				(width 0.1)
				(type default)
			)
			(layer "F.Fab")
		)
		(fp_line
			(start 2.54 -1.27)
			(end 2.54 1.27)
			(stroke
				(width 0.1)
				(type default)
			)
			(layer "F.Fab")
		)
		(fp_text user "*"
			(at -1.27 -3.89255 90)
			(unlocked yes)
			(layer "F.SilkS")
			(effects
				(font
					(size 0.381 0.381)
					(thickness 0.381)
				)
			)
		)
		(pad "1" smd rect
			(at -1.27 -1.4605 270)
			(size 1.27 3.429)
			(layers "F.Cu" "F.Mask" "F.Paste")
			(net "PSU_B1_ALERT_N")
		)
		(pad "2" smd rect
			(at 1.27 1.4605 270)
			(size 1.27 3.429)
			(layers "F.Cu" "F.Mask" "F.Paste")
			(net "UNNAMED_4_1X2HDR_I90_IO")
		)
	)
	(footprint ""
		(layer "F.Cu")
		(at -269.7226 9.0424 -90)
		(property "Reference" "C35"
			(at -0.24638 1.17856 90)
			(unlocked yes)
			(layer "F.SilkS")
			(effects
				(font
					(size 0.762 0.5334)
					(thickness 0.1016)
				)
			)
		)
		(property "Value" ""
			(at 0 0 270)
			(layer "F.Fab")
			(effects
				(font
					(size 1.27 1.27)
				)
			)
		)
		(duplicate_pad_numbers_are_jumpers no)
		(fp_line
			(start 0 -0.381)
			(end 0 0.381)
			(stroke
				(width 0.127)
				(type default)
			)
			(layer "F.SilkS")
		)
		(fp_poly
			(pts
				(xy 1.2533 0.6564) (xy -1.253299 0.6564) (xy -1.253299 -0.656399) (xy 1.2533 -0.656399)
			)
			(stroke
				(width 0)
				(type default)
			)
			(fill no)
			(layer "F.CrtYd")
		)
		(fp_line
			(start -0.762 0.381)
			(end 0.762 0.381)
			(stroke
				(width 0.1)
				(type default)
			)
			(layer "F.Fab")
		)
		(fp_line
			(start 0.762 0.381)
			(end 0.762 -0.381)
			(stroke
				(width 0.1)
				(type default)
			)
			(layer "F.Fab")
		)
		(fp_line
			(start -0.762 -0.381)
			(end -0.762 0.381)
			(stroke
				(width 0.1)
				(type default)
			)
			(layer "F.Fab")
		)
		(fp_line
			(start 0.762 -0.381)
			(end -0.762 -0.381)
			(stroke
				(width 0.1)
				(type default)
			)
			(layer "F.Fab")
		)
		(pad "1" smd rect
			(at -0.6477 0 270)
			(size 0.7112 0.8128)
			(layers "F.Cu" "F.Mask" "F.Paste")
			(net "P3V3_40G_B1_VCC_TX")
		)
		(pad "2" smd rect
			(at 0.6477 0 90)
			(size 0.7112 0.8128)
			(layers "F.Cu" "F.Mask" "F.Paste")
			(net "GND")
		)
	)
	(footprint ""
		(layer "F.Cu")
		(at -296.164 12.573 180)
		(property "Reference" "R26"
			(at -3.048 0.0889 0)
			(unlocked yes)
			(layer "F.SilkS")
			(effects
				(font
					(size 0.762 0.5334)
					(thickness 0.1016)
				)
			)
		)
		(property "Value" ""
			(at 0 0 180)
			(layer "F.Fab")
			(effects
				(font
					(size 1.27 1.27)
				)
			)
		)
		(duplicate_pad_numbers_are_jumpers no)
		(fp_line
			(start 0 -0.381)
			(end 0 0.381)
			(stroke
				(width 0.127)
				(type default)
			)
			(layer "F.SilkS")
		)
		(fp_poly
			(pts
				(xy 1.255601 0.656399) (xy -1.255601 0.656399) (xy -1.255601 -0.6564) (xy 1.255601 -0.6564)
			)
			(stroke
				(width 0)
				(type default)
			)
			(fill no)
			(layer "F.CrtYd")
		)
		(fp_line
			(start 0.800001 0.399999)
			(end 0.800001 -0.399999)
			(stroke
				(width 0.1)
				(type default)
			)
			(layer "F.Fab")
		)
		(fp_line
			(start 0.800001 -0.399999)
			(end -0.800001 -0.399999)
			(stroke
				(width 0.1)
				(type default)
			)
			(layer "F.Fab")
		)
		(fp_line
			(start -0.800001 0.399999)
			(end 0.800001 0.399999)
			(stroke
				(width 0.1)
				(type default)
			)
			(layer "F.Fab")
		)
		(fp_line
			(start -0.800001 -0.399999)
			(end -0.800001 0.399999)
			(stroke
				(width 0.1)
				(type default)
			)
			(layer "F.Fab")
		)
		(pad "1" smd rect
			(at -0.650001 0 180)
			(size 0.7112 0.8128)
			(layers "F.Cu" "F.Mask" "F.Paste")
			(net "P3V3_B1_QSFP")
		)
		(pad "2" smd rect
			(at 0.650001 0)
			(size 0.7112 0.8128)
			(layers "F.Cu" "F.Mask" "F.Paste")
			(net "ETH10G_B1_SDA")
		)
	)
	(footprint ""
		(layer "F.Cu")
		(at -46.774001 2.756002 -90)
		(property "Reference" "C20"
			(at 2.047138 0.180439 90)
			(unlocked yes)
			(layer "F.SilkS")
			(effects
				(font
					(size 0.762 0.5334)
					(thickness 0.1016)
				)
			)
		)
		(property "Value" ""
			(at 0 0 270)
			(layer "F.Fab")
			(effects
				(font
					(size 1.27 1.27)
				)
			)
		)
		(duplicate_pad_numbers_are_jumpers no)
		(fp_poly
			(pts
				(xy -0.9993 0.503999) (xy -0.9993 -0.504) (xy 0.999299 -0.504) (xy 0.999299 0.503999)
			)
			(stroke
				(width 0)
				(type default)
			)
			(fill no)
			(layer "F.CrtYd")
		)
		(fp_line
			(start -0.499999 0.249999)
			(end -0.499999 -0.25)
			(stroke
				(width 0.1)
				(type default)
			)
			(layer "F.Fab")
		)
		(fp_line
			(start 0.499999 0.249999)
			(end -0.499999 0.249999)
			(stroke
				(width 0.1)
				(type default)
			)
			(layer "F.Fab")
		)
		(fp_line
			(start -0.499999 -0.25)
			(end 0.499999 -0.25)
			(stroke
				(width 0.1)
				(type default)
			)
			(layer "F.Fab")
		)
		(fp_line
			(start 0.499999 -0.25)
			(end 0.499999 0.249999)
			(stroke
				(width 0.1)
				(type default)
			)
			(layer "F.Fab")
		)
		(pad "1" smd rect
			(at -0.4572 0)
			(size 0.508 0.5842)
			(layers "F.Cu" "F.Mask" "F.Paste")
			(net "P3V3_40G_B2_VCC_RX")
		)
		(pad "2" smd rect
			(at 0.4572 0)
			(size 0.508 0.5842)
			(layers "F.Cu" "F.Mask" "F.Paste")
			(net "GND")
		)
	)
	(footprint ""
		(layer "F.Cu")
		(at -296.164 9.779)
		(property "Reference" "R3"
			(at 2.667 -0.0889 0)
			(unlocked yes)
			(layer "F.SilkS")
			(effects
				(font
					(size 0.762 0.5334)
					(thickness 0.1016)
				)
			)
		)
		(property "Value" ""
			(at 0 0 0)
			(layer "F.Fab")
			(effects
				(font
					(size 1.27 1.27)
				)
			)
		)
		(duplicate_pad_numbers_are_jumpers no)
		(fp_line
			(start 0 -0.381)
			(end 0 0.381)
			(stroke
				(width 0.127)
				(type default)
			)
			(layer "F.SilkS")
		)
		(fp_poly
			(pts
				(xy 1.255601 0.6564) (xy -1.255601 0.6564) (xy -1.255601 -0.656399) (xy 1.255601 -0.656399)
			)
			(stroke
				(width 0)
				(type default)
			)
			(fill no)
			(layer "F.CrtYd")
		)
		(fp_line
			(start -0.800001 -0.399999)
			(end -0.800001 0.399999)
			(stroke
				(width 0.1)
				(type default)
			)
			(layer "F.Fab")
		)
		(fp_line
			(start -0.800001 0.399999)
			(end 0.800001 0.399999)
			(stroke
				(width 0.1)
				(type default)
			)
			(layer "F.Fab")
		)
		(fp_line
			(start 0.800001 -0.399999)
			(end -0.800001 -0.399999)
			(stroke
				(width 0.1)
				(type default)
			)
			(layer "F.Fab")
		)
		(fp_line
			(start 0.800001 0.399999)
			(end 0.800001 -0.399999)
			(stroke
				(width 0.1)
				(type default)
			)
			(layer "F.Fab")
		)
		(pad "1" smd rect
			(at -0.650001 0)
			(size 0.7112 0.8128)
			(layers "F.Cu" "F.Mask" "F.Paste")
			(net "SKU_B1_ID0")
		)
		(pad "2" smd rect
			(at 0.650001 0 180)
			(size 0.7112 0.8128)
			(layers "F.Cu" "F.Mask" "F.Paste")
			(net "GND")
		)
	)
	(footprint ""
		(layer "F.Cu")
		(at -281.388401 44.869202 -90)
		(property "Reference" "R17"
			(at -4.102202 -0.248501 90)
			(unlocked yes)
			(layer "F.SilkS")
			(effects
				(font
					(size 0.762 0.5334)
					(thickness 0.1016)
				)
			)
		)
		(property "Value" ""
			(at 0 0 270)
			(layer "F.Fab")
			(effects
				(font
					(size 1.27 1.27)
				)
			)
		)
		(duplicate_pad_numbers_are_jumpers no)
		(fp_line
			(start 0 -0.381)
			(end 0 0.381)
			(stroke
				(width 0.127)
				(type default)
			)
			(layer "F.SilkS")
		)
		(fp_poly
			(pts
				(xy 1.2556 0.656399) (xy -1.255601 0.656399) (xy -1.255601 -0.6564) (xy 1.2556 -0.6564)
			)
			(stroke
				(width 0)
				(type default)
			)
			(fill no)
			(layer "F.CrtYd")
		)
		(fp_line
			(start -0.800001 0.399999)
			(end 0.800001 0.399999)
			(stroke
				(width 0.1)
				(type default)
			)
			(layer "F.Fab")
		)
		(fp_line
			(start 0.800001 0.399999)
			(end 0.800001 -0.399999)
			(stroke
				(width 0.1)
				(type default)
			)
			(layer "F.Fab")
		)
		(fp_line
			(start -0.800001 -0.399999)
			(end -0.800001 0.399999)
			(stroke
				(width 0.1)
				(type default)
			)
			(layer "F.Fab")
		)
		(fp_line
			(start 0.800001 -0.399999)
			(end -0.800001 -0.399999)
			(stroke
				(width 0.1)
				(type default)
			)
			(layer "F.Fab")
		)
		(pad "1" smd rect
			(at -0.650001 0 270)
			(size 0.7112 0.8128)
			(layers "F.Cu" "F.Mask" "F.Paste")
			(net "P3V3_10G_B1_VCCT")
		)
		(pad "2" smd rect
			(at 0.650001 0 90)
			(size 0.7112 0.8128)
			(layers "F.Cu" "F.Mask" "F.Paste")
			(net "P3V3_B1_QSFP")
		)
	)
	(footprint ""
		(layer "F.Cu")
		(at -266.446 1.3716 180)
		(property "Reference" "FB9"
			(at -1.397 0.1905 0)
			(unlocked yes)
			(layer "F.SilkS")
			(effects
				(font
					(size 0.762 0.5334)
					(thickness 0.1016)
				)
				(justify left)
			)
		)
		(property "Value" ""
			(at 0 0 180)
			(layer "F.Fab")
			(effects
				(font
					(size 1.27 1.27)
				)
			)
		)
		(duplicate_pad_numbers_are_jumpers no)
		(fp_poly
			(pts
				(xy -1.016 0.508) (xy -1.016 -0.508) (xy 1.016 -0.508) (xy 1.016 0.508)
			)
			(stroke
				(width 0)
				(type default)
			)
			(fill no)
			(layer "F.CrtYd")
		)
		(fp_line
			(start 0.508 0.254)
			(end -0.508 0.254)
			(stroke
				(width 0.1)
				(type default)
			)
			(layer "F.Fab")
		)
		(fp_line
			(start 0.508 -0.254)
			(end 0.508 0.254)
			(stroke
				(width 0.1)
				(type default)
			)
			(layer "F.Fab")
		)
		(fp_line
			(start -0.508 0.254)
			(end -0.508 -0.254)
			(stroke
				(width 0.1)
				(type default)
			)
			(layer "F.Fab")
		)
		(fp_line
			(start -0.508 -0.254)
			(end 0.508 -0.254)
			(stroke
				(width 0.1)
				(type default)
			)
			(layer "F.Fab")
		)
		(pad "1" smd rect
			(at -0.4572 0 270)
			(size 0.508 0.5842)
			(layers "F.Cu" "F.Mask" "F.Paste")
			(net "UNNAMED_16_FERRITE_I40_A")
		)
		(pad "2" smd rect
			(at 0.4572 0 270)
			(size 0.508 0.5842)
			(layers "F.Cu" "F.Mask" "F.Paste")
			(net "P3V3_40G_B1_VCC_RX")
		)
	)
	(footprint ""
		(layer "F.Cu")
		(at -45.2628 6.223)
		(property "Reference" "FS5"
			(at 3.4798 0.0381 0)
			(unlocked yes)
			(layer "F.SilkS")
			(effects
				(font
					(size 0.762 0.5334)
					(thickness 0.1016)
				)
			)
		)
		(property "Value" ""
			(at 0 0 0)
			(layer "F.Fab")
			(effects
				(font
					(size 1.27 1.27)
				)
			)
		)
		(duplicate_pad_numbers_are_jumpers no)
		(fp_poly
			(pts
				(xy -1.002101 0.504) (xy -1.002101 -0.503999) (xy 1.002101 -0.503999) (xy 1.002101 0.504)
			)
			(stroke
				(width 0)
				(type default)
			)
			(fill no)
			(layer "F.CrtYd")
		)
		(fp_line
			(start -0.499999 -0.249999)
			(end -0.499999 0.25)
			(stroke
				(width 0.1)
				(type default)
			)
			(layer "F.Fab")
		)
		(fp_line
			(start -0.499999 0.25)
			(end 0.499999 0.25)
			(stroke
				(width 0.1)
				(type default)
			)
			(layer "F.Fab")
		)
		(fp_line
			(start 0.499999 -0.249999)
			(end -0.499999 -0.249999)
			(stroke
				(width 0.1)
				(type default)
			)
			(layer "F.Fab")
		)
		(fp_line
			(start 0.499999 0.25)
			(end 0.499999 -0.249999)
			(stroke
				(width 0.1)
				(type default)
			)
			(layer "F.Fab")
		)
		(pad "1" smd rect
			(at -0.459999 0 90)
			(size 0.508 0.5842)
			(layers "F.Cu" "F.Mask" "F.Paste")
			(net "P3V3_B2_QSFP")
		)
		(pad "2" smd rect
			(at 0.459999 0 90)
			(size 0.508 0.5842)
			(layers "F.Cu" "F.Mask" "F.Paste")
			(net "UNNAMED_8_FERRITE_I51_A")
		)
	)
	(footprint ""
		(layer "F.Cu")
		(at -331.47 18.8468)
		(property "Reference" "R6"
			(at 1.94564 -0.0381 0)
			(unlocked yes)
			(layer "F.SilkS")
			(effects
				(font
					(size 0.762 0.5334)
					(thickness 0.1016)
				)
			)
		)
		(property "Value" ""
			(at 0 0 0)
			(layer "F.Fab")
			(effects
				(font
					(size 1.27 1.27)
				)
			)
		)
		(duplicate_pad_numbers_are_jumpers no)
		(fp_line
			(start 0 -0.381)
			(end 0 0.381)
			(stroke
				(width 0.127)
				(type default)
			)
			(layer "F.SilkS")
		)
		(fp_poly
			(pts
				(xy 1.255601 0.6564) (xy -1.255601 0.6564) (xy -1.255601 -0.656399) (xy 1.255601 -0.656399)
			)
			(stroke
				(width 0)
				(type default)
			)
			(fill no)
			(layer "F.CrtYd")
		)
		(fp_line
			(start -0.800001 -0.399999)
			(end -0.800001 0.399999)
			(stroke
				(width 0.1)
				(type default)
			)
			(layer "F.Fab")
		)
		(fp_line
			(start -0.800001 0.399999)
			(end 0.800001 0.399999)
			(stroke
				(width 0.1)
				(type default)
			)
			(layer "F.Fab")
		)
		(fp_line
			(start 0.800001 -0.399999)
			(end -0.800001 -0.399999)
			(stroke
				(width 0.1)
				(type default)
			)
			(layer "F.Fab")
		)
		(fp_line
			(start 0.800001 0.399999)
			(end 0.800001 -0.399999)
			(stroke
				(width 0.1)
				(type default)
			)
			(layer "F.Fab")
		)
		(pad "1" smd rect
			(at -0.650001 0)
			(size 0.7112 0.8128)
			(layers "F.Cu" "F.Mask" "F.Paste")
			(net "P3V3_B1_QSFP")
		)
		(pad "2" smd rect
			(at 0.650001 0 180)
			(size 0.7112 0.8128)
			(layers "F.Cu" "F.Mask" "F.Paste")
			(net "SKU_B1_ID2")
		)
	)
	(footprint ""
		(layer "F.Cu")
		(at -171.46 45.260001 180)
		(property "Reference" "J13"
			(at 9.007 25.028901 0)
			(unlocked yes)
			(layer "F.SilkS")
			(effects
				(font
					(size 0.762 0.5334)
					(thickness 0.1016)
				)
			)
		)
		(property "Value" ""
			(at 0 0 180)
			(layer "F.Fab")
			(effects
				(font
					(size 1.27 1.27)
				)
			)
		)
		(duplicate_pad_numbers_are_jumpers no)
		(fp_line
			(start 18.95 23.700001)
			(end -0.950001 23.700001)
			(stroke
				(width 0.127)
				(type default)
			)
			(layer "F.SilkS")
		)
		(fp_line
			(start 18.95 -12.100001)
			(end 18.95 23.700001)
			(stroke
				(width 0.127)
				(type default)
			)
			(layer "F.SilkS")
		)
		(fp_line
			(start -0.950001 23.700001)
			(end -0.950001 -12.100001)
			(stroke
				(width 0.127)
				(type default)
			)
			(layer "F.SilkS")
		)
		(fp_line
			(start -0.950001 -12.100001)
			(end 18.95 -12.100001)
			(stroke
				(width 0.127)
				(type default)
			)
			(layer "F.SilkS")
		)
		(fp_poly
			(pts
				(arc
					(start 0 25.4)
					(mid -3.592102 23.912102)
					(end -5.08 20.32)
				)
				(arc
					(start -5.08 -0.1)
					(mid -3.592102 -3.692102)
					(end 0 -5.18)
				)
				(arc
					(start 18 -5.18)
					(mid 21.592102 -3.692102)
					(end 23.08 -0.1)
				)
				(arc
					(start 23.08 20.32)
					(mid 21.592102 23.912102)
					(end 18 25.4)
				)
			)
			(stroke
				(width 0)
				(type default)
			)
			(fill no)
			(layer "B.CrtYd")
		)
		(fp_rect
			(start -1.950001 24.699999)
			(end 19.950001 -13.099999)
			(stroke
				(width 0)
				(type default)
			)
			(fill no)
			(layer "F.CrtYd")
		)
		(fp_line
			(start 18.95 23.700001)
			(end -0.950001 23.700001)
			(stroke
				(width 0.1)
				(type default)
			)
			(layer "F.Fab")
		)
		(fp_line
			(start 18.95 -12.100001)
			(end 18.95 23.700001)
			(stroke
				(width 0.1)
				(type default)
			)
			(layer "F.Fab")
		)
		(fp_line
			(start -0.950001 23.700001)
			(end -0.950001 -12.100001)
			(stroke
				(width 0.1)
				(type default)
			)
			(layer "F.Fab")
		)
		(fp_line
			(start -0.950001 -12.100001)
			(end 18.95 -12.100001)
			(stroke
				(width 0.1)
				(type default)
			)
			(layer "F.Fab")
		)
		(fp_text user "P10"
			(at 20.427 20.780901 0)
			(unlocked yes)
			(layer "F.SilkS")
			(effects
				(font
					(size 0.762 0.5334)
					(thickness 0.1016)
				)
			)
		)
		(fp_text user "J10"
			(at 20.377 12.4809 0)
			(unlocked yes)
			(layer "F.SilkS")
			(effects
				(font
					(size 0.762 0.5334)
					(thickness 0.1016)
				)
			)
		)
		(fp_text user "E10"
			(at 20.377 5.480901 0)
			(unlocked yes)
			(layer "F.SilkS")
			(effects
				(font
					(size 0.762 0.5334)
					(thickness 0.1016)
				)
			)
		)
		(fp_text user "A10"
			(at 20.377 -0.119101 0)
			(unlocked yes)
			(layer "F.SilkS")
			(effects
				(font
					(size 0.762 0.5334)
					(thickness 0.1016)
				)
			)
		)
		(fp_text user "*"
			(at -1.5 -1.328549 0)
			(unlocked yes)
			(layer "F.SilkS")
			(effects
				(font
					(size 0.381 0.381)
					(thickness 0.381)
				)
			)
		)
		(fp_text user "O1"
			(at -1.788 19.694901 0)
			(unlocked yes)
			(layer "F.SilkS")
			(effects
				(font
					(size 0.762 0.5334)
					(thickness 0.1016)
				)
			)
		)
		(fp_text user "A1"
			(at -1.915 0.136901 0)
			(unlocked yes)
			(layer "F.SilkS")
			(effects
				(font
					(size 0.762 0.5334)
					(thickness 0.1016)
				)
			)
		)
		(fp_text user "J1"
			(at -2.042 12.582901 0)
			(unlocked yes)
			(layer "F.SilkS")
			(effects
				(font
					(size 0.762 0.5334)
					(thickness 0.1016)
				)
			)
		)
		(pad "A1" thru_hole rect
			(at 0 0 180)
			(size 0.8128 0.8128)
			(drill 0.508)
			(layers "*.Cu" "*.Mask")
			(remove_unused_layers no)
			(net "PCIE_T2B_B2_RX_DP<7>")
			(padstack
				(mode front_inner_back)
				(layer "Inner"
					(shape circle)
					(size 0.8128 0.8128)
				)
				(layer "B.Cu"
					(shape rect)
					(size 0.8128 0.8128)
				)
			)
		)
		(pad "A2" thru_hole circle
			(at 2.000001 -0.1 180)
			(size 0.8128 0.8128)
			(drill 0.508)
			(layers "*.Cu" "*.Mask")
			(remove_unused_layers no)
			(net "GND")
		)
		(pad "A3" thru_hole circle
			(at 4 0 180)
			(size 0.8128 0.8128)
			(drill 0.508)
			(layers "*.Cu" "*.Mask")
			(remove_unused_layers no)
			(net "PCIE_T2B_B2_RX_DP<5>")
		)
		(pad "A4" thru_hole circle
			(at 6.000001 -0.1 180)
			(size 0.8128 0.8128)
			(drill 0.508)
			(layers "*.Cu" "*.Mask")
			(remove_unused_layers no)
			(net "GND")
		)
		(pad "A5" thru_hole circle
			(at 7.999999 0 180)
			(size 0.8128 0.8128)
			(drill 0.508)
			(layers "*.Cu" "*.Mask")
			(remove_unused_layers no)
			(net "PCIE_T2B_B2_RX_DP<3>")
		)
		(pad "A6" thru_hole circle
			(at 10 -0.1 180)
			(size 0.8128 0.8128)
			(drill 0.508)
			(layers "*.Cu" "*.Mask")
			(remove_unused_layers no)
			(net "GND")
		)
		(pad "A7" thru_hole circle
			(at 11.999999 0 180)
			(size 0.8128 0.8128)
			(drill 0.508)
			(layers "*.Cu" "*.Mask")
			(remove_unused_layers no)
			(net "PCIE_T2B_B2_RX_DP<1>")
		)
		(pad "A8" thru_hole circle
			(at 14 -0.1 180)
			(size 0.8128 0.8128)
			(drill 0.508)
			(layers "*.Cu" "*.Mask")
			(remove_unused_layers no)
			(net "GND")
		)
		(pad "A9" thru_hole circle
			(at 16.000001 0 180)
			(size 0.8128 0.8128)
			(drill 0.508)
			(layers "*.Cu" "*.Mask")
			(remove_unused_layers no)
			(net "CLK_100M_B2_P<0>")
		)
		(pad "A10" thru_hole circle
			(at 18 -0.1 180)
			(size 0.8128 0.8128)
			(drill 0.508)
			(layers "*.Cu" "*.Mask")
			(remove_unused_layers no)
			(net "GND")
		)
		(pad "B1" thru_hole circle
			(at 0 1.4 180)
			(size 0.8128 0.8128)
			(drill 0.508)
			(layers "*.Cu" "*.Mask")
			(remove_unused_layers no)
			(net "PCIE_T2B_B2_RX_DN<7>")
		)
		(pad "B2" thru_hole circle
			(at 2.000001 1.3 180)
			(size 0.8128 0.8128)
			(drill 0.508)
			(layers "*.Cu" "*.Mask")
			(remove_unused_layers no)
			(net "PCIE_T2B_B2_RX_DP<6>")
		)
		(pad "B3" thru_hole circle
			(at 4 1.4 180)
			(size 0.8128 0.8128)
			(drill 0.508)
			(layers "*.Cu" "*.Mask")
			(remove_unused_layers no)
			(net "PCIE_T2B_B2_RX_DN<5>")
		)
		(pad "B4" thru_hole circle
			(at 6.000001 1.3 180)
			(size 0.8128 0.8128)
			(drill 0.508)
			(layers "*.Cu" "*.Mask")
			(remove_unused_layers no)
			(net "PCIE_T2B_B2_RX_DP<4>")
		)
		(pad "B5" thru_hole circle
			(at 7.999999 1.4 180)
			(size 0.8128 0.8128)
			(drill 0.508)
			(layers "*.Cu" "*.Mask")
			(remove_unused_layers no)
			(net "PCIE_T2B_B2_RX_DN<3>")
		)
		(pad "B6" thru_hole circle
			(at 10 1.3 180)
			(size 0.8128 0.8128)
			(drill 0.508)
			(layers "*.Cu" "*.Mask")
			(remove_unused_layers no)
			(net "PCIE_T2B_B2_RX_DP<2>")
		)
		(pad "B7" thru_hole circle
			(at 11.999999 1.4 180)
			(size 0.8128 0.8128)
			(drill 0.508)
			(layers "*.Cu" "*.Mask")
			(remove_unused_layers no)
			(net "PCIE_T2B_B2_RX_DN<1>")
		)
		(pad "B8" thru_hole circle
			(at 14 1.3 180)
			(size 0.8128 0.8128)
			(drill 0.508)
			(layers "*.Cu" "*.Mask")
			(remove_unused_layers no)
			(net "PCIE_T2B_B2_RX_DP<0>")
		)
		(pad "B9" thru_hole circle
			(at 16.000001 1.4 180)
			(size 0.8128 0.8128)
			(drill 0.508)
			(layers "*.Cu" "*.Mask")
			(remove_unused_layers no)
			(net "CLK_100M_B2_N<0>")
		)
		(pad "B10" thru_hole circle
			(at 18 1.3 180)
			(size 0.8128 0.8128)
			(drill 0.508)
			(layers "*.Cu" "*.Mask")
			(remove_unused_layers no)
			(net "USB_B2_P")
		)
		(pad "C1" thru_hole circle
			(at 0 2.799999 180)
			(size 0.8128 0.8128)
			(drill 0.508)
			(layers "*.Cu" "*.Mask")
			(remove_unused_layers no)
			(net "GND")
		)
		(pad "C2" thru_hole circle
			(at 2.000001 2.7 180)
			(size 0.8128 0.8128)
			(drill 0.508)
			(layers "*.Cu" "*.Mask")
			(remove_unused_layers no)
			(net "PCIE_T2B_B2_RX_DN<6>")
		)
		(pad "C3" thru_hole circle
			(at 4 2.799999 180)
			(size 0.8128 0.8128)
			(drill 0.508)
			(layers "*.Cu" "*.Mask")
			(remove_unused_layers no)
			(net "GND")
		)
		(pad "C4" thru_hole circle
			(at 6.000001 2.7 180)
			(size 0.8128 0.8128)
			(drill 0.508)
			(layers "*.Cu" "*.Mask")
			(remove_unused_layers no)
			(net "PCIE_T2B_B2_RX_DN<4>")
		)
		(pad "C5" thru_hole circle
			(at 7.999999 2.799999 180)
			(size 0.8128 0.8128)
			(drill 0.508)
			(layers "*.Cu" "*.Mask")
			(remove_unused_layers no)
			(net "GND")
		)
		(pad "C6" thru_hole circle
			(at 10 2.7 180)
			(size 0.8128 0.8128)
			(drill 0.508)
			(layers "*.Cu" "*.Mask")
			(remove_unused_layers no)
			(net "PCIE_T2B_B2_RX_DN<2>")
		)
		(pad "C7" thru_hole circle
			(at 11.999999 2.799999 180)
			(size 0.8128 0.8128)
			(drill 0.508)
			(layers "*.Cu" "*.Mask")
			(remove_unused_layers no)
			(net "GND")
		)
		(pad "C8" thru_hole circle
			(at 14 2.7 180)
			(size 0.8128 0.8128)
			(drill 0.508)
			(layers "*.Cu" "*.Mask")
			(remove_unused_layers no)
			(net "PCIE_T2B_B2_RX_DN<0>")
		)
		(pad "C9" thru_hole circle
			(at 16.000001 2.799999 180)
			(size 0.8128 0.8128)
			(drill 0.508)
			(layers "*.Cu" "*.Mask")
			(remove_unused_layers no)
			(net "GND")
		)
		(pad "C10" thru_hole circle
			(at 18 2.7 180)
			(size 0.8128 0.8128)
			(drill 0.508)
			(layers "*.Cu" "*.Mask")
			(remove_unused_layers no)
			(net "USB_B2_N")
		)
		(pad "D1" thru_hole circle
			(at 0 4.199999 180)
			(size 0.8128 0.8128)
			(drill 0.508)
			(layers "*.Cu" "*.Mask")
			(remove_unused_layers no)
			(net "PCIE_T2B_B2_RX_DP<15>")
		)
		(pad "D2" thru_hole circle
			(at 2.000001 4.099999 180)
			(size 0.8128 0.8128)
			(drill 0.508)
			(layers "*.Cu" "*.Mask")
			(remove_unused_layers no)
			(net "GND")
		)
		(pad "D3" thru_hole circle
			(at 4 4.199999 180)
			(size 0.8128 0.8128)
			(drill 0.508)
			(layers "*.Cu" "*.Mask")
			(remove_unused_layers no)
			(net "PCIE_T2B_B2_RX_DP<13>")
		)
		(pad "D4" thru_hole circle
			(at 6.000001 4.099999 180)
			(size 0.8128 0.8128)
			(drill 0.508)
			(layers "*.Cu" "*.Mask")
			(remove_unused_layers no)
			(net "GND")
		)
		(pad "D5" thru_hole circle
			(at 7.999999 4.199999 180)
			(size 0.8128 0.8128)
			(drill 0.508)
			(layers "*.Cu" "*.Mask")
			(remove_unused_layers no)
			(net "PCIE_T2B_B2_RX_DP<11>")
		)
		(pad "D6" thru_hole circle
			(at 10 4.099999 180)
			(size 0.8128 0.8128)
			(drill 0.508)
			(layers "*.Cu" "*.Mask")
			(remove_unused_layers no)
			(net "GND")
		)
		(pad "D7" thru_hole circle
			(at 11.999999 4.199999 180)
			(size 0.8128 0.8128)
			(drill 0.508)
			(layers "*.Cu" "*.Mask")
			(remove_unused_layers no)
			(net "PCIE_T2B_B2_RX_DP<9>")
		)
		(pad "D8" thru_hole circle
			(at 14 4.099999 180)
			(size 0.8128 0.8128)
			(drill 0.508)
			(layers "*.Cu" "*.Mask")
			(remove_unused_layers no)
			(net "GND")
		)
		(pad "D9" thru_hole circle
			(at 16.000001 4.199999 180)
			(size 0.8128 0.8128)
			(drill 0.508)
			(layers "*.Cu" "*.Mask")
			(remove_unused_layers no)
			(net "CLK_100M_B2_P<1>")
		)
		(pad "D10" thru_hole circle
			(at 18 4.099999 180)
			(size 0.8128 0.8128)
			(drill 0.508)
			(layers "*.Cu" "*.Mask")
			(remove_unused_layers no)
			(net "GND")
		)
		(pad "E1" thru_hole circle
			(at 0 5.599999 180)
			(size 0.8128 0.8128)
			(drill 0.508)
			(layers "*.Cu" "*.Mask")
			(remove_unused_layers no)
			(net "PCIE_T2B_B2_RX_DN<15>")
		)
		(pad "E2" thru_hole circle
			(at 2.000001 5.499999 180)
			(size 0.8128 0.8128)
			(drill 0.508)
			(layers "*.Cu" "*.Mask")
			(remove_unused_layers no)
			(net "PCIE_T2B_B2_RX_DP<14>")
		)
		(pad "E3" thru_hole circle
			(at 4 5.599999 180)
			(size 0.8128 0.8128)
			(drill 0.508)
			(layers "*.Cu" "*.Mask")
			(remove_unused_layers no)
			(net "PCIE_T2B_B2_RX_DN<13>")
		)
		(pad "E4" thru_hole circle
			(at 6.000001 5.499999 180)
			(size 0.8128 0.8128)
			(drill 0.508)
			(layers "*.Cu" "*.Mask")
			(remove_unused_layers no)
			(net "PCIE_T2B_B2_RX_DP<12>")
		)
		(pad "E5" thru_hole circle
			(at 7.999999 5.599999 180)
			(size 0.8128 0.8128)
			(drill 0.508)
			(layers "*.Cu" "*.Mask")
			(remove_unused_layers no)
			(net "PCIE_T2B_B2_RX_DN<11>")
		)
		(pad "E6" thru_hole circle
			(at 10 5.499999 180)
			(size 0.8128 0.8128)
			(drill 0.508)
			(layers "*.Cu" "*.Mask")
			(remove_unused_layers no)
			(net "PCIE_T2B_B2_RX_DP<10>")
		)
		(pad "E7" thru_hole circle
			(at 11.999999 5.599999 180)
			(size 0.8128 0.8128)
			(drill 0.508)
			(layers "*.Cu" "*.Mask")
			(remove_unused_layers no)
			(net "PCIE_T2B_B2_RX_DN<9>")
		)
		(pad "E8" thru_hole circle
			(at 14 5.499999 180)
			(size 0.8128 0.8128)
			(drill 0.508)
			(layers "*.Cu" "*.Mask")
			(remove_unused_layers no)
			(net "PCIE_T2B_B2_RX_DP<8>")
		)
		(pad "E9" thru_hole circle
			(at 16.000001 5.599999 180)
			(size 0.8128 0.8128)
			(drill 0.508)
			(layers "*.Cu" "*.Mask")
			(remove_unused_layers no)
			(net "CLK_100M_B2_N<1>")
		)
		(pad "E10" thru_hole circle
			(at 18 5.499999 180)
			(size 0.8128 0.8128)
			(drill 0.508)
			(layers "*.Cu" "*.Mask")
			(remove_unused_layers no)
			(net "P5V_USB_B2")
		)
		(pad "F1" thru_hole circle
			(at 0 7.000001 180)
			(size 0.8128 0.8128)
			(drill 0.508)
			(layers "*.Cu" "*.Mask")
			(remove_unused_layers no)
			(net "GND")
		)
		(pad "F2" thru_hole circle
			(at 2.000001 6.899999 180)
			(size 0.8128 0.8128)
			(drill 0.508)
			(layers "*.Cu" "*.Mask")
			(remove_unused_layers no)
			(net "PCIE_T2B_B2_RX_DN<14>")
		)
		(pad "F3" thru_hole circle
			(at 4 7.000001 180)
			(size 0.8128 0.8128)
			(drill 0.508)
			(layers "*.Cu" "*.Mask")
			(remove_unused_layers no)
			(net "GND")
		)
		(pad "F4" thru_hole circle
			(at 6.000001 6.899999 180)
			(size 0.8128 0.8128)
			(drill 0.508)
			(layers "*.Cu" "*.Mask")
			(remove_unused_layers no)
			(net "PCIE_T2B_B2_RX_DN<12>")
		)
		(pad "F5" thru_hole circle
			(at 7.999999 7.000001 180)
			(size 0.8128 0.8128)
			(drill 0.508)
			(layers "*.Cu" "*.Mask")
			(remove_unused_layers no)
			(net "GND")
		)
		(pad "F6" thru_hole circle
			(at 10 6.899999 180)
			(size 0.8128 0.8128)
			(drill 0.508)
			(layers "*.Cu" "*.Mask")
			(remove_unused_layers no)
			(net "PCIE_T2B_B2_RX_DN<10>")
		)
		(pad "F7" thru_hole circle
			(at 11.999999 7.000001 180)
			(size 0.8128 0.8128)
			(drill 0.508)
			(layers "*.Cu" "*.Mask")
			(remove_unused_layers no)
			(net "GND")
		)
		(pad "F8" thru_hole circle
			(at 14 6.899999 180)
			(size 0.8128 0.8128)
			(drill 0.508)
			(layers "*.Cu" "*.Mask")
			(remove_unused_layers no)
			(net "PCIE_T2B_B2_RX_DN<8>")
		)
		(pad "F9" thru_hole circle
			(at 16.000001 7.000001 180)
			(size 0.8128 0.8128)
			(drill 0.508)
			(layers "*.Cu" "*.Mask")
			(remove_unused_layers no)
			(net "GND")
		)
		(pad "F10" thru_hole circle
			(at 18 6.899999 180)
			(size 0.8128 0.8128)
			(drill 0.508)
			(layers "*.Cu" "*.Mask")
			(remove_unused_layers no)
			(net "GND")
		)
		(pad "G1" thru_hole circle
			(at 0 8.400001 180)
			(size 0.8128 0.8128)
			(drill 0.508)
			(layers "*.Cu" "*.Mask")
			(remove_unused_layers no)
			(net "PCIE_RESET_B2_N<3>")
		)
		(pad "G2" thru_hole circle
			(at 2.000001 8.300001 180)
			(size 0.8128 0.8128)
			(drill 0.508)
			(layers "*.Cu" "*.Mask")
			(remove_unused_layers no)
			(net "GND")
		)
		(pad "G3" thru_hole circle
			(at 4 8.400001 180)
			(size 0.8128 0.8128)
			(drill 0.508)
			(layers "*.Cu" "*.Mask")
			(remove_unused_layers no)
			(net "PCIE_CFG_B2_ID0")
		)
		(pad "G4" thru_hole circle
			(at 6.000001 8.300001 180)
			(size 0.8128 0.8128)
			(drill 0.508)
			(layers "*.Cu" "*.Mask")
			(remove_unused_layers no)
			(net "GND")
		)
		(pad "G5" thru_hole circle
			(at 7.999999 8.400001 180)
			(size 0.8128 0.8128)
			(drill 0.508)
			(layers "*.Cu" "*.Mask")
			(remove_unused_layers no)
			(net "MEZZ_B2_SCL")
		)
		(pad "G6" thru_hole circle
			(at 10 8.300001 180)
			(size 0.8128 0.8128)
			(drill 0.508)
			(layers "*.Cu" "*.Mask")
			(remove_unused_layers no)
			(net "GND")
		)
		(pad "G7" thru_hole circle
			(at 11.999999 8.400001 180)
			(size 0.8128 0.8128)
			(drill 0.508)
			(layers "*.Cu" "*.Mask")
			(remove_unused_layers no)
			(net "Net_2")
		)
		(pad "G8" thru_hole circle
			(at 14 8.300001 180)
			(size 0.8128 0.8128)
			(drill 0.508)
			(layers "*.Cu" "*.Mask")
			(remove_unused_layers no)
			(net "GND")
		)
		(pad "G9" thru_hole circle
			(at 16.000001 8.400001 180)
			(size 0.8128 0.8128)
			(drill 0.508)
			(layers "*.Cu" "*.Mask")
			(remove_unused_layers no)
			(net "CLK_100M_B2_P<2>")
		)
		(pad "G10" thru_hole circle
			(at 18 8.300001 180)
			(size 0.8128 0.8128)
			(drill 0.508)
			(layers "*.Cu" "*.Mask")
			(remove_unused_layers no)
			(net "GND")
		)
		(pad "H1" thru_hole circle
			(at 0 9.800001 180)
			(size 0.8128 0.8128)
			(drill 0.508)
			(layers "*.Cu" "*.Mask")
			(remove_unused_layers no)
			(net "PCIE_RESET_B2_N<2>")
		)
		(pad "H2" thru_hole circle
			(at 2.000001 9.700001 180)
			(size 0.8128 0.8128)
			(drill 0.508)
			(layers "*.Cu" "*.Mask")
			(remove_unused_layers no)
			(net "PCIE_RESET_B2_N<1>")
		)
		(pad "H3" thru_hole circle
			(at 4 9.800001 180)
			(size 0.8128 0.8128)
			(drill 0.508)
			(layers "*.Cu" "*.Mask")
			(remove_unused_layers no)
			(net "PCIE_CFG_B2_ID1")
		)
		(pad "H4" thru_hole circle
			(at 6.000001 9.700001 180)
			(size 0.8128 0.8128)
			(drill 0.508)
			(layers "*.Cu" "*.Mask")
			(remove_unused_layers no)
			(net "PCIE_WAKE_B2_N")
		)
		(pad "H5" thru_hole circle
			(at 7.999999 9.800001 180)
			(size 0.8128 0.8128)
			(drill 0.508)
			(layers "*.Cu" "*.Mask")
			(remove_unused_layers no)
			(net "MEZZ_B2_EN")
		)
		(pad "H6" thru_hole circle
			(at 10 9.700001 180)
			(size 0.8128 0.8128)
			(drill 0.508)
			(layers "*.Cu" "*.Mask")
			(remove_unused_layers no)
			(net "MEZZ_PRESENT_B2_N")
		)
		(pad "H7" thru_hole circle
			(at 11.999999 9.800001 180)
			(size 0.8128 0.8128)
			(drill 0.508)
			(layers "*.Cu" "*.Mask")
			(remove_unused_layers no)
			(net "PSU_B2_ALERT_N")
		)
		(pad "H8" thru_hole circle
			(at 14 9.700001 180)
			(size 0.8128 0.8128)
			(drill 0.508)
			(layers "*.Cu" "*.Mask")
			(remove_unused_layers no)
			(net "SERIAL_B2_TX2")
		)
		(pad "H9" thru_hole circle
			(at 16.000001 9.800001 180)
			(size 0.8128 0.8128)
			(drill 0.508)
			(layers "*.Cu" "*.Mask")
			(remove_unused_layers no)
			(net "CLK_100M_B2_N<2>")
		)
		(pad "H10" thru_hole circle
			(at 18 9.700001 180)
			(size 0.8128 0.8128)
			(drill 0.508)
			(layers "*.Cu" "*.Mask")
			(remove_unused_layers no)
			(net "GND")
		)
		(pad "I1" thru_hole circle
			(at 0 11.2 180)
			(size 0.8128 0.8128)
			(drill 0.508)
			(layers "*.Cu" "*.Mask")
			(remove_unused_layers no)
			(net "GND")
		)
		(pad "I2" thru_hole circle
			(at 2.000001 11.100001 180)
			(size 0.8128 0.8128)
			(drill 0.508)
			(layers "*.Cu" "*.Mask")
			(remove_unused_layers no)
			(net "PCIE_RESET_B2_N<0>")
		)
		(pad "I3" thru_hole circle
			(at 4 11.2 180)
			(size 0.8128 0.8128)
			(drill 0.508)
			(layers "*.Cu" "*.Mask")
			(remove_unused_layers no)
			(net "GND")
		)
		(pad "I4" thru_hole circle
			(at 6.000001 11.100001 180)
			(size 0.8128 0.8128)
			(drill 0.508)
			(layers "*.Cu" "*.Mask")
			(remove_unused_layers no)
			(net "MEZZ_B2_SDA")
		)
		(pad "I5" thru_hole circle
			(at 7.999999 11.2 180)
			(size 0.8128 0.8128)
			(drill 0.508)
			(layers "*.Cu" "*.Mask")
			(remove_unused_layers no)
			(net "GND")
		)
		(pad "I6" thru_hole circle
			(at 10 11.100001 180)
			(size 0.8128 0.8128)
			(drill 0.508)
			(layers "*.Cu" "*.Mask")
			(remove_unused_layers no)
			(net "BLADE_MATED_B2_N<0>")
		)
		(pad "I7" thru_hole circle
			(at 11.999999 11.2 180)
			(size 0.8128 0.8128)
			(drill 0.508)
			(layers "*.Cu" "*.Mask")
			(remove_unused_layers no)
			(net "GND")
		)
		(pad "I8" thru_hole circle
			(at 14 11.100001 180)
			(size 0.8128 0.8128)
			(drill 0.508)
			(layers "*.Cu" "*.Mask")
			(remove_unused_layers no)
			(net "SERIAL_B2_RX2")
		)
		(pad "I9" thru_hole circle
			(at 16.000001 11.2 180)
			(size 0.8128 0.8128)
			(drill 0.508)
			(layers "*.Cu" "*.Mask")
			(remove_unused_layers no)
			(net "GND")
		)
		(pad "I10" thru_hole circle
			(at 18 11.100001 180)
			(size 0.8128 0.8128)
			(drill 0.508)
			(layers "*.Cu" "*.Mask")
			(remove_unused_layers no)
			(net "P12V_MEZZ_B2")
		)
		(pad "J1" thru_hole circle
			(at 0 12.6 180)
			(size 0.8128 0.8128)
			(drill 0.508)
			(layers "*.Cu" "*.Mask")
			(remove_unused_layers no)
			(net "PCIE_B2T_B2_TX_DP<7>")
		)
		(pad "J2" thru_hole circle
			(at 2.000001 12.5 180)
			(size 0.8128 0.8128)
			(drill 0.508)
			(layers "*.Cu" "*.Mask")
			(remove_unused_layers no)
			(net "GND")
		)
		(pad "J3" thru_hole circle
			(at 4 12.6 180)
			(size 0.8128 0.8128)
			(drill 0.508)
			(layers "*.Cu" "*.Mask")
			(remove_unused_layers no)
			(net "PCIE_B2T_B2_TX_DP<5>")
		)
		(pad "J4" thru_hole circle
			(at 6.000001 12.5 180)
			(size 0.8128 0.8128)
			(drill 0.508)
			(layers "*.Cu" "*.Mask")
			(remove_unused_layers no)
			(net "GND")
		)
		(pad "J5" thru_hole circle
			(at 7.999999 12.6 180)
			(size 0.8128 0.8128)
			(drill 0.508)
			(layers "*.Cu" "*.Mask")
			(remove_unused_layers no)
			(net "PCIE_B2T_B2_TX_DP<3>")
		)
		(pad "J6" thru_hole circle
			(at 10 12.5 180)
			(size 0.8128 0.8128)
			(drill 0.508)
			(layers "*.Cu" "*.Mask")
			(remove_unused_layers no)
			(net "GND")
		)
		(pad "J7" thru_hole circle
			(at 11.999999 12.6 180)
			(size 0.8128 0.8128)
			(drill 0.508)
			(layers "*.Cu" "*.Mask")
			(remove_unused_layers no)
			(net "PCIE_B2T_B2_TX_DP<1>")
		)
		(pad "J8" thru_hole circle
			(at 14 12.5 180)
			(size 0.8128 0.8128)
			(drill 0.508)
			(layers "*.Cu" "*.Mask")
			(remove_unused_layers no)
			(net "GND")
		)
		(pad "J9" thru_hole circle
			(at 16.000001 12.6 180)
			(size 0.8128 0.8128)
			(drill 0.508)
			(layers "*.Cu" "*.Mask")
			(remove_unused_layers no)
			(net "CLK_100M_B2_P<3>")
		)
		(pad "J10" thru_hole circle
			(at 18 12.5 180)
			(size 0.8128 0.8128)
			(drill 0.508)
			(layers "*.Cu" "*.Mask")
			(remove_unused_layers no)
			(net "P12V_MEZZ_B2")
		)
		(pad "K1" thru_hole circle
			(at 0 14 180)
			(size 0.8128 0.8128)
			(drill 0.508)
			(layers "*.Cu" "*.Mask")
			(remove_unused_layers no)
			(net "PCIE_B2T_B2_TX_DN<7>")
		)
		(pad "K2" thru_hole circle
			(at 2.000001 13.9 180)
			(size 0.8128 0.8128)
			(drill 0.508)
			(layers "*.Cu" "*.Mask")
			(remove_unused_layers no)
			(net "PCIE_B2T_B2_TX_DP<6>")
		)
		(pad "K3" thru_hole circle
			(at 4 14 180)
			(size 0.8128 0.8128)
			(drill 0.508)
			(layers "*.Cu" "*.Mask")
			(remove_unused_layers no)
			(net "PCIE_B2T_B2_TX_DN<5>")
		)
		(pad "K4" thru_hole circle
			(at 6.000001 13.9 180)
			(size 0.8128 0.8128)
			(drill 0.508)
			(layers "*.Cu" "*.Mask")
			(remove_unused_layers no)
			(net "PCIE_B2T_B2_TX_DP<4>")
		)
		(pad "K5" thru_hole circle
			(at 7.999999 14 180)
			(size 0.8128 0.8128)
			(drill 0.508)
			(layers "*.Cu" "*.Mask")
			(remove_unused_layers no)
			(net "PCIE_B2T_B2_TX_DN<3>")
		)
		(pad "K6" thru_hole circle
			(at 10 13.9 180)
			(size 0.8128 0.8128)
			(drill 0.508)
			(layers "*.Cu" "*.Mask")
			(remove_unused_layers no)
			(net "PCIE_B2T_B2_TX_DP<2>")
		)
		(pad "K7" thru_hole circle
			(at 11.999999 14 180)
			(size 0.8128 0.8128)
			(drill 0.508)
			(layers "*.Cu" "*.Mask")
			(remove_unused_layers no)
			(net "PCIE_B2T_B2_TX_DN<1>")
		)
		(pad "K8" thru_hole circle
			(at 14 13.9 180)
			(size 0.8128 0.8128)
			(drill 0.508)
			(layers "*.Cu" "*.Mask")
			(remove_unused_layers no)
			(net "PCIE_B2T_B2_TX_DP<0>")
		)
		(pad "K9" thru_hole circle
			(at 16.000001 14 180)
			(size 0.8128 0.8128)
			(drill 0.508)
			(layers "*.Cu" "*.Mask")
			(remove_unused_layers no)
			(net "CLK_100M_B2_N<3>")
		)
		(pad "K10" thru_hole circle
			(at 18 13.9 180)
			(size 0.8128 0.8128)
			(drill 0.508)
			(layers "*.Cu" "*.Mask")
			(remove_unused_layers no)
			(net "P12V_MEZZ_B2")
		)
		(pad "L1" thru_hole circle
			(at 0 15.4 180)
			(size 0.8128 0.8128)
			(drill 0.508)
			(layers "*.Cu" "*.Mask")
			(remove_unused_layers no)
			(net "GND")
		)
		(pad "L2" thru_hole circle
			(at 2.000001 15.3 180)
			(size 0.8128 0.8128)
			(drill 0.508)
			(layers "*.Cu" "*.Mask")
			(remove_unused_layers no)
			(net "PCIE_B2T_B2_TX_DN<6>")
		)
		(pad "L3" thru_hole circle
			(at 4 15.4 180)
			(size 0.8128 0.8128)
			(drill 0.508)
			(layers "*.Cu" "*.Mask")
			(remove_unused_layers no)
			(net "GND")
		)
		(pad "L4" thru_hole circle
			(at 6.000001 15.3 180)
			(size 0.8128 0.8128)
			(drill 0.508)
			(layers "*.Cu" "*.Mask")
			(remove_unused_layers no)
			(net "PCIE_B2T_B2_TX_DN<4>")
		)
		(pad "L5" thru_hole circle
			(at 7.999999 15.4 180)
			(size 0.8128 0.8128)
			(drill 0.508)
			(layers "*.Cu" "*.Mask")
			(remove_unused_layers no)
			(net "GND")
		)
		(pad "L6" thru_hole circle
			(at 10 15.3 180)
			(size 0.8128 0.8128)
			(drill 0.508)
			(layers "*.Cu" "*.Mask")
			(remove_unused_layers no)
			(net "PCIE_B2T_B2_TX_DN<2>")
		)
		(pad "L7" thru_hole circle
			(at 11.999999 15.4 180)
			(size 0.8128 0.8128)
			(drill 0.508)
			(layers "*.Cu" "*.Mask")
			(remove_unused_layers no)
			(net "GND")
		)
		(pad "L8" thru_hole circle
			(at 14 15.3 180)
			(size 0.8128 0.8128)
			(drill 0.508)
			(layers "*.Cu" "*.Mask")
			(remove_unused_layers no)
			(net "PCIE_B2T_B2_TX_DN<0>")
		)
		(pad "L9" thru_hole circle
			(at 16.000001 15.4 180)
			(size 0.8128 0.8128)
			(drill 0.508)
			(layers "*.Cu" "*.Mask")
			(remove_unused_layers no)
			(net "GND")
		)
		(pad "L10" thru_hole circle
			(at 18 15.3 180)
			(size 0.8128 0.8128)
			(drill 0.508)
			(layers "*.Cu" "*.Mask")
			(remove_unused_layers no)
			(net "P12V_MEZZ_B2")
		)
		(pad "M1" thru_hole circle
			(at 0 16.799999 180)
			(size 0.8128 0.8128)
			(drill 0.508)
			(layers "*.Cu" "*.Mask")
			(remove_unused_layers no)
			(net "PCIE_B2T_B2_TX_DP<15>")
		)
		(pad "M2" thru_hole circle
			(at 2.000001 16.7 180)
			(size 0.8128 0.8128)
			(drill 0.508)
			(layers "*.Cu" "*.Mask")
			(remove_unused_layers no)
			(net "GND")
		)
		(pad "M3" thru_hole circle
			(at 4 16.799999 180)
			(size 0.8128 0.8128)
			(drill 0.508)
			(layers "*.Cu" "*.Mask")
			(remove_unused_layers no)
			(net "PCIE_B2T_B2_TX_DP<13>")
		)
		(pad "M4" thru_hole circle
			(at 6.000001 16.7 180)
			(size 0.8128 0.8128)
			(drill 0.508)
			(layers "*.Cu" "*.Mask")
			(remove_unused_layers no)
			(net "GND")
		)
		(pad "M5" thru_hole circle
			(at 7.999999 16.799999 180)
			(size 0.8128 0.8128)
			(drill 0.508)
			(layers "*.Cu" "*.Mask")
			(remove_unused_layers no)
			(net "PCIE_B2T_B2_TX_DP<11>")
		)
		(pad "M6" thru_hole circle
			(at 10 16.7 180)
			(size 0.8128 0.8128)
			(drill 0.508)
			(layers "*.Cu" "*.Mask")
			(remove_unused_layers no)
			(net "GND")
		)
		(pad "M7" thru_hole circle
			(at 11.999999 16.799999 180)
			(size 0.8128 0.8128)
			(drill 0.508)
			(layers "*.Cu" "*.Mask")
			(remove_unused_layers no)
			(net "PCIE_B2T_B2_TX_DP<9>")
		)
		(pad "M8" thru_hole circle
			(at 14 16.7 180)
			(size 0.8128 0.8128)
			(drill 0.508)
			(layers "*.Cu" "*.Mask")
			(remove_unused_layers no)
			(net "GND")
		)
		(pad "M9" thru_hole circle
			(at 16.000001 16.799999 180)
			(size 0.8128 0.8128)
			(drill 0.508)
			(layers "*.Cu" "*.Mask")
			(remove_unused_layers no)
			(net "GND")
		)
		(pad "M10" thru_hole circle
			(at 18 16.7 180)
			(size 0.8128 0.8128)
			(drill 0.508)
			(layers "*.Cu" "*.Mask")
			(remove_unused_layers no)
			(net "GND")
		)
		(pad "N1" thru_hole circle
			(at 0 18.199999 180)
			(size 0.8128 0.8128)
			(drill 0.508)
			(layers "*.Cu" "*.Mask")
			(remove_unused_layers no)
			(net "PCIE_B2T_B2_TX_DN<15>")
		)
		(pad "N2" thru_hole circle
			(at 2.000001 18.099999 180)
			(size 0.8128 0.8128)
			(drill 0.508)
			(layers "*.Cu" "*.Mask")
			(remove_unused_layers no)
			(net "PCIE_B2T_B2_TX_DP<14>")
		)
		(pad "N3" thru_hole circle
			(at 4 18.199999 180)
			(size 0.8128 0.8128)
			(drill 0.508)
			(layers "*.Cu" "*.Mask")
			(remove_unused_layers no)
			(net "PCIE_B2T_B2_TX_DN<13>")
		)
		(pad "N4" thru_hole circle
			(at 6.000001 18.099999 180)
			(size 0.8128 0.8128)
			(drill 0.508)
			(layers "*.Cu" "*.Mask")
			(remove_unused_layers no)
			(net "PCIE_B2T_B2_TX_DP<12>")
		)
		(pad "N5" thru_hole circle
			(at 7.999999 18.199999 180)
			(size 0.8128 0.8128)
			(drill 0.508)
			(layers "*.Cu" "*.Mask")
			(remove_unused_layers no)
			(net "PCIE_B2T_B2_TX_DN<11>")
		)
		(pad "N6" thru_hole circle
			(at 10 18.099999 180)
			(size 0.8128 0.8128)
			(drill 0.508)
			(layers "*.Cu" "*.Mask")
			(remove_unused_layers no)
			(net "PCIE_B2T_B2_TX_DP<10>")
		)
		(pad "N7" thru_hole circle
			(at 11.999999 18.199999 180)
			(size 0.8128 0.8128)
			(drill 0.508)
			(layers "*.Cu" "*.Mask")
			(remove_unused_layers no)
			(net "PCIE_B2T_B2_TX_DN<9>")
		)
		(pad "N8" thru_hole circle
			(at 14 18.099999 180)
			(size 0.8128 0.8128)
			(drill 0.508)
			(layers "*.Cu" "*.Mask")
			(remove_unused_layers no)
			(net "PCIE_B2T_B2_TX_DP<8>")
		)
		(pad "N9" thru_hole circle
			(at 16.000001 18.199999 180)
			(size 0.8128 0.8128)
			(drill 0.508)
			(layers "*.Cu" "*.Mask")
			(remove_unused_layers no)
			(net "GND")
		)
		(pad "N10" thru_hole circle
			(at 18 18.099999 180)
			(size 0.8128 0.8128)
			(drill 0.508)
			(layers "*.Cu" "*.Mask")
			(remove_unused_layers no)
			(net "P12V_MEZZ_B2")
		)
		(pad "O1" thru_hole circle
			(at 0 19.599999 180)
			(size 0.8128 0.8128)
			(drill 0.508)
			(layers "*.Cu" "*.Mask")
			(remove_unused_layers no)
			(net "GND")
		)
		(pad "O2" thru_hole circle
			(at 2.000001 19.499999 180)
			(size 0.8128 0.8128)
			(drill 0.508)
			(layers "*.Cu" "*.Mask")
			(remove_unused_layers no)
			(net "PCIE_B2T_B2_TX_DN<14>")
		)
		(pad "O3" thru_hole circle
			(at 4 19.599999 180)
			(size 0.8128 0.8128)
			(drill 0.508)
			(layers "*.Cu" "*.Mask")
			(remove_unused_layers no)
			(net "GND")
		)
		(pad "O4" thru_hole circle
			(at 6.000001 19.499999 180)
			(size 0.8128 0.8128)
			(drill 0.508)
			(layers "*.Cu" "*.Mask")
			(remove_unused_layers no)
			(net "PCIE_B2T_B2_TX_DN<12>")
		)
		(pad "O5" thru_hole circle
			(at 7.999999 19.599999 180)
			(size 0.8128 0.8128)
			(drill 0.508)
			(layers "*.Cu" "*.Mask")
			(remove_unused_layers no)
			(net "GND")
		)
		(pad "O6" thru_hole circle
			(at 10 19.499999 180)
			(size 0.8128 0.8128)
			(drill 0.508)
			(layers "*.Cu" "*.Mask")
			(remove_unused_layers no)
			(net "PCIE_B2T_B2_TX_DN<10>")
		)
		(pad "O7" thru_hole circle
			(at 11.999999 19.599999 180)
			(size 0.8128 0.8128)
			(drill 0.508)
			(layers "*.Cu" "*.Mask")
			(remove_unused_layers no)
			(net "GND")
		)
		(pad "O8" thru_hole circle
			(at 14 19.499999 180)
			(size 0.8128 0.8128)
			(drill 0.508)
			(layers "*.Cu" "*.Mask")
			(remove_unused_layers no)
			(net "PCIE_B2T_B2_TX_DN<8>")
		)
		(pad "O9" thru_hole circle
			(at 16.000001 19.599999 180)
			(size 0.8128 0.8128)
			(drill 0.508)
			(layers "*.Cu" "*.Mask")
			(remove_unused_layers no)
			(net "GND")
		)
		(pad "O10" thru_hole circle
			(at 18 19.499999 180)
			(size 0.8128 0.8128)
			(drill 0.508)
			(layers "*.Cu" "*.Mask")
			(remove_unused_layers no)
			(net "P12V_MEZZ_B2")
		)
		(pad "P2" thru_hole circle
			(at 2.000001 20.899999 180)
			(size 0.8128 0.8128)
			(drill 0.508)
			(layers "*.Cu" "*.Mask")
			(remove_unused_layers no)
			(net "GND")
		)
		(pad "P4" thru_hole circle
			(at 6.000001 20.899999 180)
			(size 0.8128 0.8128)
			(drill 0.508)
			(layers "*.Cu" "*.Mask")
			(remove_unused_layers no)
			(net "GND")
		)
		(pad "P6" thru_hole circle
			(at 10 20.899999 180)
			(size 0.8128 0.8128)
			(drill 0.508)
			(layers "*.Cu" "*.Mask")
			(remove_unused_layers no)
			(net "GND")
		)
		(pad "P8" thru_hole circle
			(at 14 20.899999 180)
			(size 0.8128 0.8128)
			(drill 0.508)
			(layers "*.Cu" "*.Mask")
			(remove_unused_layers no)
			(net "GND")
		)
		(pad "P10" thru_hole circle
			(at 18 20.899999 180)
			(size 0.8128 0.8128)
			(drill 0.508)
			(layers "*.Cu" "*.Mask")
			(remove_unused_layers no)
			(net "GND")
		)
	)
	(footprint ""
		(layer "F.Cu")
		(at -331.5462 3.0226 -90)
		(property "Reference" "J25"
			(at 0.49022 -4.06146 90)
			(unlocked yes)
			(layer "F.SilkS")
			(effects
				(font
					(size 0.762 0.5334)
					(thickness 0.1016)
				)
			)
		)
		(property "Value" ""
			(at 0 0 270)
			(layer "F.Fab")
			(effects
				(font
					(size 1.27 1.27)
				)
			)
		)
		(duplicate_pad_numbers_are_jumpers no)
		(fp_line
			(start -2.54 1.27)
			(end 0.127 1.27)
			(stroke
				(width 0.127)
				(type default)
			)
			(layer "F.SilkS")
		)
		(fp_line
			(start 2.443175 1.257198)
			(end 2.570175 1.257198)
			(stroke
				(width 0.127)
				(type default)
			)
			(layer "F.SilkS")
		)
		(fp_line
			(start 2.570175 1.257198)
			(end 2.570175 -1.282802)
			(stroke
				(width 0.127)
				(type default)
			)
			(layer "F.SilkS")
		)
		(fp_line
			(start -2.54 -1.27)
			(end -2.54 1.27)
			(stroke
				(width 0.127)
				(type default)
			)
			(layer "F.SilkS")
		)
		(fp_line
			(start -2.413 -1.27)
			(end -2.54 -1.27)
			(stroke
				(width 0.127)
				(type default)
			)
			(layer "F.SilkS")
		)
		(fp_line
			(start 2.570175 -1.282802)
			(end -0.096825 -1.282802)
			(stroke
				(width 0.127)
				(type default)
			)
			(layer "F.SilkS")
		)
		(fp_poly
			(pts
				(xy 0.127 3.683) (xy 0.127 1.778) (xy -3.048 1.778) (xy -3.048 -1.778) (xy -2.413 -1.778) (xy -2.413 -3.683)
				(xy -0.127 -3.683) (xy -0.127 -1.778) (xy 3.048 -1.778) (xy 3.048 1.778) (xy 2.413 1.778) (xy 2.413 3.683)
			)
			(stroke
				(width 0)
				(type default)
			)
			(fill no)
			(layer "F.CrtYd")
		)
		(fp_line
			(start -2.54 1.27)
			(end -2.54 -1.27)
			(stroke
				(width 0.1)
				(type default)
			)
			(layer "F.Fab")
		)
		(fp_line
			(start 2.54 1.27)
			(end -2.54 1.27)
			(stroke
				(width 0.1)
				(type default)
			)
			(layer "F.Fab")
		)
		(fp_line
			(start -2.54 -1.27)
			(end 2.54 -1.27)
			(stroke
				(width 0.1)
				(type default)
			)
			(layer "F.Fab")
		)
		(fp_line
			(start 2.54 -1.27)
			(end 2.54 1.27)
			(stroke
				(width 0.1)
				(type default)
			)
			(layer "F.Fab")
		)
		(fp_text user "*"
			(at -1.27 -3.89255 90)
			(unlocked yes)
			(layer "F.SilkS")
			(effects
				(font
					(size 0.381 0.381)
					(thickness 0.381)
				)
			)
		)
		(pad "1" smd rect
			(at -1.27 -1.4605 270)
			(size 1.27 3.429)
			(layers "F.Cu" "F.Mask" "F.Paste")
			(net "BLADE_B1_EN1")
		)
		(pad "2" smd rect
			(at 1.27 1.4605 270)
			(size 1.27 3.429)
			(layers "F.Cu" "F.Mask" "F.Paste")
			(net "UNNAMED_4_1X2HDR_I81_IO")
		)
	)
	(footprint ""
		(layer "F.Cu")
		(at -279.610401 45.631202)
		(property "Reference" "FB2"
			(at -0.932599 1.142898 0)
			(unlocked yes)
			(layer "F.SilkS")
			(effects
				(font
					(size 0.762 0.5334)
					(thickness 0.1016)
				)
				(justify left)
			)
		)
		(property "Value" ""
			(at 0 0 0)
			(layer "F.Fab")
			(effects
				(font
					(size 1.27 1.27)
				)
			)
		)
		(duplicate_pad_numbers_are_jumpers no)
		(fp_poly
			(pts
				(xy -1.016 0.508) (xy -1.016 -0.508) (xy 1.016 -0.508) (xy 1.016 0.508)
			)
			(stroke
				(width 0)
				(type default)
			)
			(fill no)
			(layer "F.CrtYd")
		)
		(fp_line
			(start -0.508 -0.254)
			(end 0.508 -0.254)
			(stroke
				(width 0.1)
				(type default)
			)
			(layer "F.Fab")
		)
		(fp_line
			(start -0.508 0.254)
			(end -0.508 -0.254)
			(stroke
				(width 0.1)
				(type default)
			)
			(layer "F.Fab")
		)
		(fp_line
			(start 0.508 -0.254)
			(end 0.508 0.254)
			(stroke
				(width 0.1)
				(type default)
			)
			(layer "F.Fab")
		)
		(fp_line
			(start 0.508 0.254)
			(end -0.508 0.254)
			(stroke
				(width 0.1)
				(type default)
			)
			(layer "F.Fab")
		)
		(pad "1" smd rect
			(at -0.4572 0 90)
			(size 0.508 0.5842)
			(layers "F.Cu" "F.Mask" "F.Paste")
			(net "P3V3_10G_B1_VCCT")
		)
		(pad "2" smd rect
			(at 0.4572 0 90)
			(size 0.508 0.5842)
			(layers "F.Cu" "F.Mask" "F.Paste")
			(net "UNNAMED_4_FERRITE_I151_B")
		)
	)
	(footprint ""
		(layer "F.Cu")
		(at -279.610401 43.345202)
		(property "Reference" "C5"
			(at 2.242401 -0.000102 0)
			(unlocked yes)
			(layer "F.SilkS")
			(effects
				(font
					(size 0.762 0.5334)
					(thickness 0.1016)
				)
			)
		)
		(property "Value" ""
			(at 0 0 0)
			(layer "F.Fab")
			(effects
				(font
					(size 1.27 1.27)
				)
			)
		)
		(duplicate_pad_numbers_are_jumpers no)
		(fp_poly
			(pts
				(xy -0.999299 0.503999) (xy -0.999299 -0.504) (xy 0.9993 -0.504) (xy 0.9993 0.503999)
			)
			(stroke
				(width 0)
				(type default)
			)
			(fill no)
			(layer "F.CrtYd")
		)
		(fp_line
			(start -0.499999 -0.25)
			(end 0.499999 -0.25)
			(stroke
				(width 0.1)
				(type default)
			)
			(layer "F.Fab")
		)
		(fp_line
			(start -0.499999 0.249999)
			(end -0.499999 -0.25)
			(stroke
				(width 0.1)
				(type default)
			)
			(layer "F.Fab")
		)
		(fp_line
			(start 0.499999 -0.25)
			(end 0.499999 0.249999)
			(stroke
				(width 0.1)
				(type default)
			)
			(layer "F.Fab")
		)
		(fp_line
			(start 0.499999 0.249999)
			(end -0.499999 0.249999)
			(stroke
				(width 0.1)
				(type default)
			)
			(layer "F.Fab")
		)
		(pad "1" smd rect
			(at -0.4572 0 90)
			(size 0.508 0.5842)
			(layers "F.Cu" "F.Mask" "F.Paste")
			(net "P3V3_10G_B1_VCCT")
		)
		(pad "2" smd rect
			(at 0.4572 0 90)
			(size 0.508 0.5842)
			(layers "F.Cu" "F.Mask" "F.Paste")
			(net "GND")
		)
	)
	(footprint ""
		(layer "F.Cu")
		(at -80.137 10.668)
		(property "Reference" "R40"
			(at -3.048 0.1651 0)
			(unlocked yes)
			(layer "F.SilkS")
			(effects
				(font
					(size 0.762 0.5334)
					(thickness 0.1016)
				)
			)
		)
		(property "Value" ""
			(at 0 0 0)
			(layer "F.Fab")
			(effects
				(font
					(size 1.27 1.27)
				)
			)
		)
		(duplicate_pad_numbers_are_jumpers no)
		(fp_line
			(start 0 -0.381)
			(end 0 0.381)
			(stroke
				(width 0.127)
				(type default)
			)
			(layer "F.SilkS")
		)
		(fp_poly
			(pts
				(xy 1.255601 0.6564) (xy -1.255601 0.6564) (xy -1.255601 -0.656399) (xy 1.255601 -0.656399)
			)
			(stroke
				(width 0)
				(type default)
			)
			(fill no)
			(layer "F.CrtYd")
		)
		(fp_line
			(start -0.800001 -0.399999)
			(end -0.800001 0.399999)
			(stroke
				(width 0.1)
				(type default)
			)
			(layer "F.Fab")
		)
		(fp_line
			(start -0.800001 0.399999)
			(end 0.800001 0.399999)
			(stroke
				(width 0.1)
				(type default)
			)
			(layer "F.Fab")
		)
		(fp_line
			(start 0.800001 -0.399999)
			(end -0.800001 -0.399999)
			(stroke
				(width 0.1)
				(type default)
			)
			(layer "F.Fab")
		)
		(fp_line
			(start 0.800001 0.399999)
			(end 0.800001 -0.399999)
			(stroke
				(width 0.1)
				(type default)
			)
			(layer "F.Fab")
		)
		(pad "1" smd rect
			(at -0.650001 0)
			(size 0.7112 0.8128)
			(layers "F.Cu" "F.Mask" "F.Paste")
			(net "BLADE_B2_MATED_N")
		)
		(pad "2" smd rect
			(at 0.650001 0 180)
			(size 0.7112 0.8128)
			(layers "F.Cu" "F.Mask" "F.Paste")
			(net "GND")
		)
	)
	(footprint ""
		(layer "F.Cu")
		(at -48.2854 9.1186 -90)
		(property "Reference" "C23"
			(at 0.03556 1.28016 90)
			(unlocked yes)
			(layer "F.SilkS")
			(effects
				(font
					(size 0.762 0.5334)
					(thickness 0.1016)
				)
			)
		)
		(property "Value" ""
			(at 0 0 270)
			(layer "F.Fab")
			(effects
				(font
					(size 1.27 1.27)
				)
			)
		)
		(duplicate_pad_numbers_are_jumpers no)
		(fp_line
			(start 0 -0.381)
			(end 0 0.381)
			(stroke
				(width 0.127)
				(type default)
			)
			(layer "F.SilkS")
		)
		(fp_poly
			(pts
				(xy 1.2533 0.6564) (xy -1.253299 0.6564) (xy -1.253299 -0.656399) (xy 1.2533 -0.656399)
			)
			(stroke
				(width 0)
				(type default)
			)
			(fill no)
			(layer "F.CrtYd")
		)
		(fp_line
			(start -0.762 0.381)
			(end 0.762 0.381)
			(stroke
				(width 0.1)
				(type default)
			)
			(layer "F.Fab")
		)
		(fp_line
			(start 0.762 0.381)
			(end 0.762 -0.381)
			(stroke
				(width 0.1)
				(type default)
			)
			(layer "F.Fab")
		)
		(fp_line
			(start -0.762 -0.381)
			(end -0.762 0.381)
			(stroke
				(width 0.1)
				(type default)
			)
			(layer "F.Fab")
		)
		(fp_line
			(start 0.762 -0.381)
			(end -0.762 -0.381)
			(stroke
				(width 0.1)
				(type default)
			)
			(layer "F.Fab")
		)
		(pad "1" smd rect
			(at -0.6477 0 270)
			(size 0.7112 0.8128)
			(layers "F.Cu" "F.Mask" "F.Paste")
			(net "P3V3_40G_B2_VCC_TX")
		)
		(pad "2" smd rect
			(at 0.6477 0 90)
			(size 0.7112 0.8128)
			(layers "F.Cu" "F.Mask" "F.Paste")
			(net "GND")
		)
	)
	(footprint ""
		(layer "F.Cu")
		(at -80.118801 5.016602 180)
		(property "Reference" "R31"
			(at 2.939199 0.025502 0)
			(unlocked yes)
			(layer "F.SilkS")
			(effects
				(font
					(size 0.762 0.5334)
					(thickness 0.1016)
				)
			)
		)
		(property "Value" ""
			(at 0 0 180)
			(layer "F.Fab")
			(effects
				(font
					(size 1.27 1.27)
				)
			)
		)
		(duplicate_pad_numbers_are_jumpers no)
		(fp_line
			(start 0 -0.381)
			(end 0 0.381)
			(stroke
				(width 0.127)
				(type default)
			)
			(layer "F.SilkS")
		)
		(fp_poly
			(pts
				(xy 1.255601 0.6564) (xy -1.255601 0.6564) (xy -1.255601 -0.656399) (xy 1.255601 -0.656399)
			)
			(stroke
				(width 0)
				(type default)
			)
			(fill no)
			(layer "F.CrtYd")
		)
		(fp_line
			(start 0.800001 0.4)
			(end 0.800001 -0.399999)
			(stroke
				(width 0.1)
				(type default)
			)
			(layer "F.Fab")
		)
		(fp_line
			(start 0.800001 -0.399999)
			(end -0.800001 -0.399999)
			(stroke
				(width 0.1)
				(type default)
			)
			(layer "F.Fab")
		)
		(fp_line
			(start -0.800001 0.4)
			(end 0.800001 0.4)
			(stroke
				(width 0.1)
				(type default)
			)
			(layer "F.Fab")
		)
		(fp_line
			(start -0.800001 -0.399999)
			(end -0.800001 0.4)
			(stroke
				(width 0.1)
				(type default)
			)
			(layer "F.Fab")
		)
		(pad "1" smd rect
			(at -0.650001 0 180)
			(size 0.7112 0.8128)
			(layers "F.Cu" "F.Mask" "F.Paste")
			(net "SKU_B2_ID0")
		)
		(pad "2" smd rect
			(at 0.650001 0)
			(size 0.7112 0.8128)
			(layers "F.Cu" "F.Mask" "F.Paste")
			(net "GND")
		)
	)
	(footprint ""
		(layer "F.Cu")
		(at -95.25 39.010001 180)
		(property "Reference" "J20"
			(at 8.73506 -8.843599 0)
			(unlocked yes)
			(layer "F.SilkS")
			(effects
				(font
					(size 0.762 0.5334)
					(thickness 0.1016)
				)
			)
		)
		(property "Value" ""
			(at 0 0 180)
			(layer "F.Fab")
			(effects
				(font
					(size 1.27 1.27)
				)
			)
		)
		(duplicate_pad_numbers_are_jumpers no)
		(fp_line
			(start 9.1 5.750001)
			(end 9.1 4.093401)
			(stroke
				(width 0.127)
				(type default)
			)
			(layer "F.SilkS")
		)
		(fp_line
			(start 9.1 -5.750001)
			(end 9.1 1.507599)
			(stroke
				(width 0.127)
				(type default)
			)
			(layer "F.SilkS")
		)
		(fp_line
			(start 7.5211 -5.750001)
			(end 9.1 -5.750001)
			(stroke
				(width 0.127)
				(type default)
			)
			(layer "F.SilkS")
		)
		(fp_line
			(start -8.029301 -5.750001)
			(end -9.1 -5.750001)
			(stroke
				(width 0.127)
				(type default)
			)
			(layer "F.SilkS")
		)
		(fp_line
			(start -9.1 5.750001)
			(end 9.1 5.750001)
			(stroke
				(width 0.127)
				(type default)
			)
			(layer "F.SilkS")
		)
		(fp_line
			(start -9.1 4.0408)
			(end -9.1 5.750001)
			(stroke
				(width 0.127)
				(type default)
			)
			(layer "F.SilkS")
		)
		(fp_line
			(start -9.1 -5.750001)
			(end -9.1 1.446101)
			(stroke
				(width 0.127)
				(type default)
			)
			(layer "F.SilkS")
		)
		(fp_rect
			(start -9.608 6.258001)
			(end 9.607999 -6.258002)
			(stroke
				(width 0)
				(type default)
			)
			(fill no)
			(layer "F.CrtYd")
		)
		(fp_line
			(start 9.1 5.750001)
			(end 9.1 -5.750001)
			(stroke
				(width 0.1)
				(type default)
			)
			(layer "F.Fab")
		)
		(fp_line
			(start 9.1 -5.750001)
			(end -9.1 -5.750001)
			(stroke
				(width 0.1)
				(type default)
			)
			(layer "F.Fab")
		)
		(fp_line
			(start -9.1 5.750001)
			(end 9.1 5.750001)
			(stroke
				(width 0.1)
				(type default)
			)
			(layer "F.Fab")
		)
		(fp_line
			(start -9.1 -5.750001)
			(end -9.1 5.750001)
			(stroke
				(width 0.1)
				(type default)
			)
			(layer "F.Fab")
		)
		(fp_text user "19"
			(at 8.3566 -0.131399 0)
			(unlocked yes)
			(layer "F.SilkS")
			(effects
				(font
					(size 0.762 0.5334)
					(thickness 0.1016)
				)
			)
		)
		(fp_text user "20"
			(at 8.03656 -3.992199 0)
			(unlocked yes)
			(layer "F.SilkS")
			(effects
				(font
					(size 0.762 0.5334)
					(thickness 0.1016)
				)
			)
		)
		(fp_text user "*"
			(at -8.08228 -0.650829 0)
			(unlocked yes)
			(layer "F.SilkS")
			(effects
				(font
					(size 0.381 0.381)
					(thickness 0.381)
				)
			)
		)
		(pad "" np_thru_hole circle
			(at -8.400001 2.849999 270)
			(size 1.27 1.27)
			(drill 1.5494)
			(layers "*.Cu" "*.Mask")
		)
		(pad "" np_thru_hole circle
			(at 8.400001 2.849999 270)
			(size 1.27 1.27)
			(drill 1.5494)
			(layers "*.Cu" "*.Mask")
		)
		(pad "1" smd oval
			(at -7.000001 -2.33 180)
			(size 0.3556 1.8034)
			(layers "F.Cu" "F.Mask" "F.Paste")
			(net "GND")
		)
		(pad "2" smd oval
			(at -6.2 -2.33 180)
			(size 0.3556 1.8034)
			(layers "F.Cu" "F.Mask" "F.Paste")
			(net "ETH40G_B2_TX1N")
		)
		(pad "3" smd oval
			(at -5.399999 -2.33 180)
			(size 0.3556 1.8034)
			(layers "F.Cu" "F.Mask" "F.Paste")
			(net "ETH40G_B2_TX1P")
		)
		(pad "4" smd oval
			(at -4.600001 -2.33 180)
			(size 0.3556 1.8034)
			(layers "F.Cu" "F.Mask" "F.Paste")
			(net "GND")
		)
		(pad "5" smd oval
			(at -3.8 -2.33 180)
			(size 0.3556 1.8034)
			(layers "F.Cu" "F.Mask" "F.Paste")
			(net "ETH40G_B2_TX3N")
		)
		(pad "6" smd oval
			(at -2.999999 -2.33 180)
			(size 0.3556 1.8034)
			(layers "F.Cu" "F.Mask" "F.Paste")
			(net "ETH40G_B2_TX3P")
		)
		(pad "7" smd oval
			(at -2.200001 -2.33 180)
			(size 0.3556 1.8034)
			(layers "F.Cu" "F.Mask" "F.Paste")
			(net "GND")
		)
		(pad "8" smd oval
			(at -1.4 -2.33 180)
			(size 0.3556 1.8034)
			(layers "F.Cu" "F.Mask" "F.Paste")
			(net "ETH40G_B2_MODSEL_N")
		)
		(pad "9" smd oval
			(at -0.599999 -2.33 180)
			(size 0.3556 1.8034)
			(layers "F.Cu" "F.Mask" "F.Paste")
			(net "ETH40G_B2_RESET_N")
		)
		(pad "10" smd oval
			(at 0.2 -2.33 180)
			(size 0.3556 1.8034)
			(layers "F.Cu" "F.Mask" "F.Paste")
			(net "P3V3_40G_B2_VCC_RX")
		)
		(pad "11" smd oval
			(at 1.000001 -2.33 180)
			(size 0.3556 1.8034)
			(layers "F.Cu" "F.Mask" "F.Paste")
			(net "ETH40G_B2_SCL")
		)
		(pad "12" smd oval
			(at 1.799999 -2.33 180)
			(size 0.3556 1.8034)
			(layers "F.Cu" "F.Mask" "F.Paste")
			(net "ETH40G_B2_SDA")
		)
		(pad "13" smd oval
			(at 2.6 -2.33 180)
			(size 0.3556 1.8034)
			(layers "F.Cu" "F.Mask" "F.Paste")
			(net "GND")
		)
		(pad "14" smd oval
			(at 3.400001 -2.33 180)
			(size 0.3556 1.8034)
			(layers "F.Cu" "F.Mask" "F.Paste")
			(net "ETH40G_B2_RX2P")
		)
		(pad "15" smd oval
			(at 4.199999 -2.33 180)
			(size 0.3556 1.8034)
			(layers "F.Cu" "F.Mask" "F.Paste")
			(net "ETH40G_B2_RX2N")
		)
		(pad "16" smd oval
			(at 5 -2.33 180)
			(size 0.3556 1.8034)
			(layers "F.Cu" "F.Mask" "F.Paste")
			(net "GND")
		)
		(pad "17" smd oval
			(at 5.800001 -2.33 180)
			(size 0.3556 1.8034)
			(layers "F.Cu" "F.Mask" "F.Paste")
			(net "ETH40G_B2_RX0P")
		)
		(pad "18" smd oval
			(at 6.6 -2.33 180)
			(size 0.3556 1.8034)
			(layers "F.Cu" "F.Mask" "F.Paste")
			(net "ETH40G_B2_RX0N")
		)
		(pad "19" smd oval
			(at 7.4 -2.33 180)
			(size 0.3556 1.8034)
			(layers "F.Cu" "F.Mask" "F.Paste")
			(net "GND")
		)
		(pad "20" smd oval
			(at 7.000001 -4.830001 180)
			(size 0.3556 1.8034)
			(layers "F.Cu" "F.Mask" "F.Paste")
			(net "GND")
		)
		(pad "21" smd oval
			(at 6.2 -4.830001 180)
			(size 0.3556 1.8034)
			(layers "F.Cu" "F.Mask" "F.Paste")
			(net "ETH40G_B2_RX1N")
		)
		(pad "22" smd oval
			(at 5.399999 -4.830001 180)
			(size 0.3556 1.8034)
			(layers "F.Cu" "F.Mask" "F.Paste")
			(net "ETH40G_B2_RX1P")
		)
		(pad "23" smd oval
			(at 4.600001 -4.830001 180)
			(size 0.3556 1.8034)
			(layers "F.Cu" "F.Mask" "F.Paste")
			(net "GND")
		)
		(pad "24" smd oval
			(at 3.8 -4.830001 180)
			(size 0.3556 1.8034)
			(layers "F.Cu" "F.Mask" "F.Paste")
			(net "ETH40G_B2_RX3N")
		)
		(pad "25" smd oval
			(at 2.999999 -4.830001 180)
			(size 0.3556 1.8034)
			(layers "F.Cu" "F.Mask" "F.Paste")
			(net "ETH40G_B2_RX3P")
		)
		(pad "26" smd oval
			(at 2.200001 -4.830001 180)
			(size 0.3556 1.8034)
			(layers "F.Cu" "F.Mask" "F.Paste")
			(net "GND")
		)
		(pad "27" smd oval
			(at 1.4 -4.830001 180)
			(size 0.3556 1.8034)
			(layers "F.Cu" "F.Mask" "F.Paste")
			(net "ETH40G_B2_MODPRS_N")
		)
		(pad "28" smd oval
			(at 0.599999 -4.830001 180)
			(size 0.3556 1.8034)
			(layers "F.Cu" "F.Mask" "F.Paste")
			(net "ETH40G_B2_INT_N")
		)
		(pad "29" smd oval
			(at -0.2 -4.830001 180)
			(size 0.3556 1.8034)
			(layers "F.Cu" "F.Mask" "F.Paste")
			(net "P3V3_40G_B2_VCC_TX")
		)
		(pad "30" smd oval
			(at -1.000001 -4.830001 180)
			(size 0.3556 1.8034)
			(layers "F.Cu" "F.Mask" "F.Paste")
			(net "P3V3_40G_B2_VCC1")
		)
		(pad "31" smd oval
			(at -1.799999 -4.830001 180)
			(size 0.3556 1.8034)
			(layers "F.Cu" "F.Mask" "F.Paste")
			(net "ETH40G_B2_LPMODE")
		)
		(pad "32" smd oval
			(at -2.6 -4.830001 180)
			(size 0.3556 1.8034)
			(layers "F.Cu" "F.Mask" "F.Paste")
			(net "GND")
		)
		(pad "33" smd oval
			(at -3.400001 -4.830001 180)
			(size 0.3556 1.8034)
			(layers "F.Cu" "F.Mask" "F.Paste")
			(net "ETH40G_B2_TX2P")
		)
		(pad "34" smd oval
			(at -4.199999 -4.830001 180)
			(size 0.3556 1.8034)
			(layers "F.Cu" "F.Mask" "F.Paste")
			(net "ETH40G_B2_TX2N")
		)
		(pad "35" smd oval
			(at -5 -4.830001 180)
			(size 0.3556 1.8034)
			(layers "F.Cu" "F.Mask" "F.Paste")
			(net "GND")
		)
		(pad "36" smd oval
			(at -5.800001 -4.830001 180)
			(size 0.3556 1.8034)
			(layers "F.Cu" "F.Mask" "F.Paste")
			(net "ETH40G_B2_TX0P")
		)
		(pad "37" smd oval
			(at -6.6 -4.830001 180)
			(size 0.3556 1.8034)
			(layers "F.Cu" "F.Mask" "F.Paste")
			(net "ETH40G_B2_TX0N")
		)
		(pad "38" smd oval
			(at -7.4 -4.830001 180)
			(size 0.3556 1.8034)
			(layers "F.Cu" "F.Mask" "F.Paste")
			(net "GND")
		)
		(zone
			(layers "F.Cu" "B.Cu" "In1.Cu" "In2.Cu" "In3.Cu" "In4.Cu" "In5.Cu" "In6.Cu")
			(hatch none 0.5)
			(connect_pads
				(clearance 0)
			)
			(min_thickness 0.25)
			(keepout
				(tracks not_allowed)
				(vias allowed)
				(pads allowed)
				(copperpour not_allowed)
				(footprints allowed)
			)
			(placement
				(enabled no)
				(sheetname "")
			)
			(fill
				(thermal_gap 0.5)
				(thermal_bridge_width 0.5)
				(island_removal_mode 0)
			)
			(polygon
				(pts
					(arc
						(start -104.805701 36.160001)
						(mid -102.494301 36.160001)
						(end -104.805701 36.160001)
					)
				)
			)
		)
		(zone
			(layers "F.Cu" "B.Cu" "In1.Cu" "In2.Cu" "In3.Cu" "In4.Cu" "In5.Cu" "In6.Cu")
			(hatch none 0.5)
			(connect_pads
				(clearance 0)
			)
			(min_thickness 0.25)
			(keepout
				(tracks not_allowed)
				(vias allowed)
				(pads allowed)
				(copperpour not_allowed)
				(footprints allowed)
			)
			(placement
				(enabled no)
				(sheetname "")
			)
			(fill
				(thermal_gap 0.5)
				(thermal_bridge_width 0.5)
				(island_removal_mode 0)
			)
			(polygon
				(pts
					(arc
						(start -88.005699 36.160001)
						(mid -85.694299 36.160001)
						(end -88.005699 36.160001)
					)
				)
			)
		)
	)
	(footprint ""
		(layer "F.Cu")
		(at -110.8456 7.493 180)
		(property "Reference" "R63"
			(at -2.79146 -0.18542 0)
			(unlocked yes)
			(layer "F.SilkS")
			(effects
				(font
					(size 0.762 0.5334)
					(thickness 0.1016)
				)
			)
		)
		(property "Value" ""
			(at 0 0 180)
			(layer "F.Fab")
			(effects
				(font
					(size 1.27 1.27)
				)
			)
		)
		(duplicate_pad_numbers_are_jumpers no)
		(fp_line
			(start 0 -0.381)
			(end 0 0.381)
			(stroke
				(width 0.127)
				(type default)
			)
			(layer "F.SilkS")
		)
		(fp_poly
			(pts
				(xy 1.255601 0.656399) (xy -1.255601 0.656399) (xy -1.255601 -0.6564) (xy 1.255601 -0.6564)
			)
			(stroke
				(width 0)
				(type default)
			)
			(fill no)
			(layer "F.CrtYd")
		)
		(fp_line
			(start 0.800001 0.399999)
			(end 0.800001 -0.399999)
			(stroke
				(width 0.1)
				(type default)
			)
			(layer "F.Fab")
		)
		(fp_line
			(start 0.800001 -0.399999)
			(end -0.800001 -0.399999)
			(stroke
				(width 0.1)
				(type default)
			)
			(layer "F.Fab")
		)
		(fp_line
			(start -0.800001 0.399999)
			(end 0.800001 0.399999)
			(stroke
				(width 0.1)
				(type default)
			)
			(layer "F.Fab")
		)
		(fp_line
			(start -0.800001 -0.399999)
			(end -0.800001 0.399999)
			(stroke
				(width 0.1)
				(type default)
			)
			(layer "F.Fab")
		)
		(pad "1" smd rect
			(at -0.650001 0 180)
			(size 0.7112 0.8128)
			(layers "F.Cu" "F.Mask" "F.Paste")
			(net "ETH40G_B2_MODSEL_N")
		)
		(pad "2" smd rect
			(at 0.650001 0)
			(size 0.7112 0.8128)
			(layers "F.Cu" "F.Mask" "F.Paste")
			(net "GND")
		)
	)
	(footprint ""
		(layer "F.Cu")
		(at -296.145801 2.730602 180)
		(property "Reference" "R21"
			(at -3.029801 -0.101498 0)
			(unlocked yes)
			(layer "F.SilkS")
			(effects
				(font
					(size 0.762 0.5334)
					(thickness 0.1016)
				)
			)
		)
		(property "Value" ""
			(at 0 0 180)
			(layer "F.Fab")
			(effects
				(font
					(size 1.27 1.27)
				)
			)
		)
		(duplicate_pad_numbers_are_jumpers no)
		(fp_line
			(start 0 -0.381)
			(end 0 0.381)
			(stroke
				(width 0.127)
				(type default)
			)
			(layer "F.SilkS")
		)
		(fp_poly
			(pts
				(xy 1.255601 0.6564) (xy -1.255601 0.6564) (xy -1.255601 -0.656399) (xy 1.255601 -0.656399)
			)
			(stroke
				(width 0)
				(type default)
			)
			(fill no)
			(layer "F.CrtYd")
		)
		(fp_line
			(start 0.800001 0.4)
			(end 0.800001 -0.399999)
			(stroke
				(width 0.1)
				(type default)
			)
			(layer "F.Fab")
		)
		(fp_line
			(start 0.800001 -0.399999)
			(end -0.800001 -0.399999)
			(stroke
				(width 0.1)
				(type default)
			)
			(layer "F.Fab")
		)
		(fp_line
			(start -0.800001 0.4)
			(end 0.800001 0.4)
			(stroke
				(width 0.1)
				(type default)
			)
			(layer "F.Fab")
		)
		(fp_line
			(start -0.800001 -0.399999)
			(end -0.800001 0.4)
			(stroke
				(width 0.1)
				(type default)
			)
			(layer "F.Fab")
		)
		(pad "1" smd rect
			(at -0.650001 0 180)
			(size 0.7112 0.8128)
			(layers "F.Cu" "F.Mask" "F.Paste")
			(net "ETH10G_B1_TX_DIS")
		)
		(pad "2" smd rect
			(at 0.650001 0)
			(size 0.7112 0.8128)
			(layers "F.Cu" "F.Mask" "F.Paste")
			(net "GND")
		)
	)
	(footprint ""
		(layer "F.Cu")
		(at -63.563401 43.345202 180)
		(property "Reference" "C11"
			(at 2.603599 0.000102 0)
			(unlocked yes)
			(layer "F.SilkS")
			(effects
				(font
					(size 0.762 0.5334)
					(thickness 0.1016)
				)
			)
		)
		(property "Value" ""
			(at 0 0 180)
			(layer "F.Fab")
			(effects
				(font
					(size 1.27 1.27)
				)
			)
		)
		(duplicate_pad_numbers_are_jumpers no)
		(fp_poly
			(pts
				(xy -0.9993 0.504) (xy -0.9993 -0.503999) (xy 0.999299 -0.503999) (xy 0.999299 0.504)
			)
			(stroke
				(width 0)
				(type default)
			)
			(fill no)
			(layer "F.CrtYd")
		)
		(fp_line
			(start 0.499999 0.25)
			(end -0.499999 0.25)
			(stroke
				(width 0.1)
				(type default)
			)
			(layer "F.Fab")
		)
		(fp_line
			(start 0.499999 -0.249999)
			(end 0.499999 0.25)
			(stroke
				(width 0.1)
				(type default)
			)
			(layer "F.Fab")
		)
		(fp_line
			(start -0.499999 0.25)
			(end -0.499999 -0.249999)
			(stroke
				(width 0.1)
				(type default)
			)
			(layer "F.Fab")
		)
		(fp_line
			(start -0.499999 -0.249999)
			(end 0.499999 -0.249999)
			(stroke
				(width 0.1)
				(type default)
			)
			(layer "F.Fab")
		)
		(pad "1" smd rect
			(at -0.4572 0 270)
			(size 0.508 0.5842)
			(layers "F.Cu" "F.Mask" "F.Paste")
			(net "P3V3_10G_B2_VCCR")
		)
		(pad "2" smd rect
			(at 0.4572 0 270)
			(size 0.508 0.5842)
			(layers "F.Cu" "F.Mask" "F.Paste")
			(net "GND")
		)
	)
	(footprint ""
		(layer "F.Cu")
		(at -110.8456 16.0274)
		(property "Reference" "R67"
			(at 3.1496 0.0127 0)
			(unlocked yes)
			(layer "F.SilkS")
			(effects
				(font
					(size 0.762 0.5334)
					(thickness 0.1016)
				)
			)
		)
		(property "Value" ""
			(at 0 0 0)
			(layer "F.Fab")
			(effects
				(font
					(size 1.27 1.27)
				)
			)
		)
		(duplicate_pad_numbers_are_jumpers no)
		(fp_line
			(start 0 -0.381)
			(end 0 0.381)
			(stroke
				(width 0.127)
				(type default)
			)
			(layer "F.SilkS")
		)
		(fp_poly
			(pts
				(xy 1.255601 0.6564) (xy -1.255601 0.6564) (xy -1.255601 -0.656399) (xy 1.255601 -0.656399)
			)
			(stroke
				(width 0)
				(type default)
			)
			(fill no)
			(layer "F.CrtYd")
		)
		(fp_line
			(start -0.800001 -0.399999)
			(end -0.800001 0.399999)
			(stroke
				(width 0.1)
				(type default)
			)
			(layer "F.Fab")
		)
		(fp_line
			(start -0.800001 0.399999)
			(end 0.800001 0.399999)
			(stroke
				(width 0.1)
				(type default)
			)
			(layer "F.Fab")
		)
		(fp_line
			(start 0.800001 -0.399999)
			(end -0.800001 -0.399999)
			(stroke
				(width 0.1)
				(type default)
			)
			(layer "F.Fab")
		)
		(fp_line
			(start 0.800001 0.399999)
			(end 0.800001 -0.399999)
			(stroke
				(width 0.1)
				(type default)
			)
			(layer "F.Fab")
		)
		(pad "1" smd rect
			(at -0.650001 0)
			(size 0.7112 0.8128)
			(layers "F.Cu" "F.Mask" "F.Paste")
			(net "P3V3_B2_QSFP")
		)
		(pad "2" smd rect
			(at 0.650001 0 180)
			(size 0.7112 0.8128)
			(layers "F.Cu" "F.Mask" "F.Paste")
			(net "ETH40G_B2_SDA")
		)
	)
	(footprint ""
		(layer "F.Cu")
		(at -80.137 12.065)
		(property "Reference" "R66"
			(at -2.921 0.0381 0)
			(unlocked yes)
			(layer "F.SilkS")
			(effects
				(font
					(size 0.762 0.5334)
					(thickness 0.1016)
				)
			)
		)
		(property "Value" ""
			(at 0 0 0)
			(layer "F.Fab")
			(effects
				(font
					(size 1.27 1.27)
				)
			)
		)
		(duplicate_pad_numbers_are_jumpers no)
		(fp_line
			(start 0 -0.381)
			(end 0 0.381)
			(stroke
				(width 0.127)
				(type default)
			)
			(layer "F.SilkS")
		)
		(fp_poly
			(pts
				(xy 1.255601 0.6564) (xy -1.255601 0.6564) (xy -1.255601 -0.656399) (xy 1.255601 -0.656399)
			)
			(stroke
				(width 0)
				(type default)
			)
			(fill no)
			(layer "F.CrtYd")
		)
		(fp_line
			(start -0.800001 -0.399999)
			(end -0.800001 0.399999)
			(stroke
				(width 0.1)
				(type default)
			)
			(layer "F.Fab")
		)
		(fp_line
			(start -0.800001 0.399999)
			(end 0.800001 0.399999)
			(stroke
				(width 0.1)
				(type default)
			)
			(layer "F.Fab")
		)
		(fp_line
			(start 0.800001 -0.399999)
			(end -0.800001 -0.399999)
			(stroke
				(width 0.1)
				(type default)
			)
			(layer "F.Fab")
		)
		(fp_line
			(start 0.800001 0.399999)
			(end 0.800001 -0.399999)
			(stroke
				(width 0.1)
				(type default)
			)
			(layer "F.Fab")
		)
		(pad "1" smd rect
			(at -0.650001 0)
			(size 0.7112 0.8128)
			(layers "F.Cu" "F.Mask" "F.Paste")
			(net "ETH40G_B2_MODPRS_N")
		)
		(pad "2" smd rect
			(at 0.650001 0 180)
			(size 0.7112 0.8128)
			(layers "F.Cu" "F.Mask" "F.Paste")
			(net "ETH40G_B2_PRES_N")
		)
	)
	(footprint ""
		(layer "F.Cu")
		(at -19.850001 13.639371 180)
		(property "Reference" "J24"
			(at 3.009999 -15.100729 0)
			(unlocked yes)
			(layer "F.SilkS")
			(effects
				(font
					(size 0.762 0.5334)
					(thickness 0.1016)
				)
			)
		)
		(property "Value" ""
			(at 0 0 180)
			(layer "F.Fab")
			(effects
				(font
					(size 1.27 1.27)
				)
			)
		)
		(duplicate_pad_numbers_are_jumpers no)
		(fp_line
			(start 19.625 24.759999)
			(end 19.625 14.950001)
			(stroke
				(width 0.127)
				(type default)
			)
			(layer "F.SilkS")
		)
		(fp_line
			(start 19.625 1.699999)
			(end 19.625 12.95)
			(stroke
				(width 0.127)
				(type default)
			)
			(layer "F.SilkS")
		)
		(fp_line
			(start 19.625 -13.239999)
			(end 19.625 -0.299999)
			(stroke
				(width 0.127)
				(type default)
			)
			(layer "F.SilkS")
		)
		(fp_line
			(start 18 -13.239999)
			(end 19.625 -13.239999)
			(stroke
				(width 0.127)
				(type default)
			)
			(layer "F.SilkS")
		)
		(fp_line
			(start 0.499999 -13.239999)
			(end -2.625001 -13.239999)
			(stroke
				(width 0.127)
				(type default)
			)
			(layer "F.SilkS")
		)
		(fp_line
			(start -2.625001 24.759999)
			(end 19.625 24.759999)
			(stroke
				(width 0.127)
				(type default)
			)
			(layer "F.SilkS")
		)
		(fp_line
			(start -2.625001 14.950001)
			(end -2.625001 24.759999)
			(stroke
				(width 0.127)
				(type default)
			)
			(layer "F.SilkS")
		)
		(fp_line
			(start -2.625001 12.95)
			(end -2.625001 1.699999)
			(stroke
				(width 0.127)
				(type default)
			)
			(layer "F.SilkS")
		)
		(fp_line
			(start -2.625001 -13.239999)
			(end -2.625001 -0.299999)
			(stroke
				(width 0.127)
				(type default)
			)
			(layer "F.SilkS")
		)
		(fp_poly
			(pts
				(arc
					(start -2.5 19.06)
					(mid -6.070889 17.580889)
					(end -7.55 14.01)
				)
				(arc
					(start -7.55 0.700001)
					(mid -7.480978 -0.132072)
					(end -7.2758 -0.9414)
				)
				(arc
					(start -3.378599 -14.414299)
					(mid -1.57533 -17.115548)
					(end 1.499999 -18.159999)
				)
				(xy 5.9849 -18.159999) (xy 6.014999 -18.159999)
				(arc
					(start 16.984901 -18.159999)
					(mid 20.058046 -17.128812)
					(end 21.871201 -14.4418)
				)
				(xy 22.0277 -13.583699)
				(arc
					(start 24.457401 -0.262699)
					(mid 24.526799 0.216429)
					(end 24.549999 0.700001)
				)
				(arc
					(start 24.549999 14.01)
					(mid 23.070888 17.580889)
					(end 19.499999 19.06)
				)
			)
			(stroke
				(width 0)
				(type default)
			)
			(fill no)
			(layer "B.CrtYd")
		)
		(fp_poly
			(pts
				(xy -3.624999 25.76)
				(arc
					(start -3.624999 15.090699)
					(mid -4.059979 14.01)
					(end -3.624999 12.929301)
				)
				(arc
					(start -3.624999 1.7807)
					(mid -4.05998 0.7)
					(end -3.624999 -0.3807)
				)
				(xy -3.624999 -14.239999)
				(arc
					(start 0.4245 -14.239999)
					(mid 1.499999 -14.669998)
					(end 2.575499 -14.239999)
				)
				(arc
					(start 4.924501 -14.239999)
					(mid 6.000001 -14.669999)
					(end 7.0755 -14.239999)
				)
				(arc
					(start 11.424501 -14.239999)
					(mid 12.5 -14.669998)
					(end 13.5755 -14.239999)
				)
				(arc
					(start 15.924499 -14.239999)
					(mid 17.000001 -14.670001)
					(end 18.075501 -14.239999)
				)
				(xy 20.625001 -14.239999)
				(arc
					(start 20.625001 -0.3807)
					(mid 21.05998 0.7)
					(end 20.625001 1.7807)
				)
				(arc
					(start 20.625001 12.929301)
					(mid 21.05998 14.01)
					(end 20.625001 15.090699)
				)
				(xy 20.625001 25.76)
			)
			(stroke
				(width 0)
				(type default)
			)
			(fill no)
			(layer "F.CrtYd")
		)
		(fp_line
			(start 19.625 24.759999)
			(end -2.625001 24.759999)
			(stroke
				(width 0.1)
				(type default)
			)
			(layer "F.Fab")
		)
		(fp_line
			(start 19.625 -13.239999)
			(end 19.625 24.759999)
			(stroke
				(width 0.1)
				(type default)
			)
			(layer "F.Fab")
		)
		(fp_line
			(start -2.625001 24.759999)
			(end -2.625001 -13.239999)
			(stroke
				(width 0.1)
				(type default)
			)
			(layer "F.Fab")
		)
		(fp_line
			(start -2.625001 -13.239999)
			(end 19.625 -13.239999)
			(stroke
				(width 0.1)
				(type default)
			)
			(layer "F.Fab")
		)
		(fp_text user "2A"
			(at 20.627 1.707901 0)
			(unlocked yes)
			(layer "F.SilkS")
			(effects
				(font
					(size 0.762 0.5334)
					(thickness 0.1016)
				)
			)
		)
		(fp_text user "2B"
			(at 20.627 -3.042099 0)
			(unlocked yes)
			(layer "F.SilkS")
			(effects
				(font
					(size 0.762 0.5334)
					(thickness 0.1016)
				)
			)
		)
		(fp_text user "2D"
			(at 20.627 -10.5421 0)
			(unlocked yes)
			(layer "F.SilkS")
			(effects
				(font
					(size 0.762 0.5334)
					(thickness 0.1016)
				)
			)
		)
		(fp_text user "2C"
			(at 20.31458 -6.931799 0)
			(unlocked yes)
			(layer "F.SilkS")
			(effects
				(font
					(size 0.762 0.5334)
					(thickness 0.1016)
				)
			)
		)
		(fp_text user "*"
			(at -3.594001 -0.756079 180)
			(unlocked yes)
			(layer "F.SilkS")
			(effects
				(font
					(size 0.381 0.381)
					(thickness 0.381)
				)
			)
		)
		(fp_text user "1B"
			(at -3.627001 -3.931099 0)
			(unlocked yes)
			(layer "F.SilkS")
			(effects
				(font
					(size 0.762 0.5334)
					(thickness 0.1016)
				)
			)
		)
		(fp_text user "1C"
			(at -3.627001 -7.681099 0)
			(unlocked yes)
			(layer "F.SilkS")
			(effects
				(font
					(size 0.762 0.5334)
					(thickness 0.1016)
				)
			)
		)
		(fp_text user "1D"
			(at -3.627001 -11.4311 0)
			(unlocked yes)
			(layer "F.SilkS")
			(effects
				(font
					(size 0.762 0.5334)
					(thickness 0.1016)
				)
			)
		)
		(fp_text user "1A"
			(at -4.356001 0.393271 0)
			(unlocked yes)
			(layer "F.SilkS")
			(effects
				(font
					(size 0.762 0.5334)
					(thickness 0.1016)
				)
			)
		)
		(pad "" thru_hole circle
			(at 2.999999 4.399999 180)
			(size 3.81 3.81)
			(drill 2.2098)
			(layers "*.Cu" "*.Mask")
			(remove_unused_layers no)
		)
		(pad "" thru_hole circle
			(at 14 4.399999 180)
			(size 3.81 3.81)
			(drill 2.2098)
			(layers "*.Cu" "*.Mask")
			(remove_unused_layers no)
		)
		(pad "1" thru_hole circle
			(at 1.5 -13.109999 180)
			(size 1.1176 1.1176)
			(drill 0.6096)
			(layers "*.Cu" "*.Mask")
			(remove_unused_layers no)
			(net "GND")
		)
		(pad "1A1" thru_hole circle
			(at 0 0 180)
			(size 0.6858 0.6858)
			(drill 0.381)
			(layers "*.Cu" "*.Mask")
			(remove_unused_layers no)
			(net "Net_393")
		)
		(pad "1A2" thru_hole circle
			(at 0.750001 1.4 180)
			(size 0.6858 0.6858)
			(drill 0.381)
			(layers "*.Cu" "*.Mask")
			(remove_unused_layers no)
			(net "Net_392")
		)
		(pad "1A3" thru_hole circle
			(at 1.5 0.700001 180)
			(size 0.6858 0.6858)
			(drill 0.381)
			(layers "*.Cu" "*.Mask")
			(remove_unused_layers no)
			(net "GND")
		)
		(pad "1A4" thru_hole circle
			(at 2.250001 0 180)
			(size 0.6858 0.6858)
			(drill 0.381)
			(layers "*.Cu" "*.Mask")
			(remove_unused_layers no)
			(net "SAS_B2_RX2P")
		)
		(pad "1A5" thru_hole circle
			(at 2.999999 1.4 180)
			(size 0.6858 0.6858)
			(drill 0.381)
			(layers "*.Cu" "*.Mask")
			(remove_unused_layers no)
			(net "SAS_B2_RX2N")
		)
		(pad "1A6" thru_hole circle
			(at 3.75 0.700001 180)
			(size 0.6858 0.6858)
			(drill 0.381)
			(layers "*.Cu" "*.Mask")
			(remove_unused_layers no)
			(net "GND")
		)
		(pad "1A7" thru_hole circle
			(at 4.500001 0 180)
			(size 0.6858 0.6858)
			(drill 0.381)
			(layers "*.Cu" "*.Mask")
			(remove_unused_layers no)
			(net "SAS_B2_RX4P")
		)
		(pad "1A8" thru_hole circle
			(at 5.25 1.4 180)
			(size 0.6858 0.6858)
			(drill 0.381)
			(layers "*.Cu" "*.Mask")
			(remove_unused_layers no)
			(net "SAS_B2_RX4N")
		)
		(pad "1A9" thru_hole circle
			(at 6.000001 0.700001 180)
			(size 0.6858 0.6858)
			(drill 0.381)
			(layers "*.Cu" "*.Mask")
			(remove_unused_layers no)
			(net "GND")
		)
		(pad "1B1" thru_hole circle
			(at 0 -3.8 180)
			(size 0.6858 0.6858)
			(drill 0.381)
			(layers "*.Cu" "*.Mask")
			(remove_unused_layers no)
			(net "Net_391")
		)
		(pad "1B2" thru_hole circle
			(at 0.750001 -2.4 180)
			(size 0.6858 0.6858)
			(drill 0.381)
			(layers "*.Cu" "*.Mask")
			(remove_unused_layers no)
			(net "Net_390")
		)
		(pad "1B3" thru_hole circle
			(at 1.5 -3.099999 180)
			(size 0.6858 0.6858)
			(drill 0.381)
			(layers "*.Cu" "*.Mask")
			(remove_unused_layers no)
			(net "GND")
		)
		(pad "1B4" thru_hole circle
			(at 2.250001 -3.8 180)
			(size 0.6858 0.6858)
			(drill 0.381)
			(layers "*.Cu" "*.Mask")
			(remove_unused_layers no)
			(net "SAS_B2_RX1P")
		)
		(pad "1B5" thru_hole circle
			(at 2.999999 -2.4 180)
			(size 0.6858 0.6858)
			(drill 0.381)
			(layers "*.Cu" "*.Mask")
			(remove_unused_layers no)
			(net "SAS_B2_RX1N")
		)
		(pad "1B6" thru_hole circle
			(at 3.75 -3.099999 180)
			(size 0.6858 0.6858)
			(drill 0.381)
			(layers "*.Cu" "*.Mask")
			(remove_unused_layers no)
			(net "GND")
		)
		(pad "1B7" thru_hole circle
			(at 4.500001 -3.8 180)
			(size 0.6858 0.6858)
			(drill 0.381)
			(layers "*.Cu" "*.Mask")
			(remove_unused_layers no)
			(net "SAS_B2_RX3P")
		)
		(pad "1B8" thru_hole circle
			(at 5.25 -2.4 180)
			(size 0.6858 0.6858)
			(drill 0.381)
			(layers "*.Cu" "*.Mask")
			(remove_unused_layers no)
			(net "SAS_B2_RX3N")
		)
		(pad "1B9" thru_hole circle
			(at 6.000001 -3.099999 180)
			(size 0.6858 0.6858)
			(drill 0.381)
			(layers "*.Cu" "*.Mask")
			(remove_unused_layers no)
			(net "GND")
		)
		(pad "1C1" thru_hole circle
			(at 0 -7.6 180)
			(size 0.6858 0.6858)
			(drill 0.381)
			(layers "*.Cu" "*.Mask")
			(remove_unused_layers no)
			(net "Net_389")
		)
		(pad "1C2" thru_hole circle
			(at 0.750001 -6.2 180)
			(size 0.6858 0.6858)
			(drill 0.381)
			(layers "*.Cu" "*.Mask")
			(remove_unused_layers no)
			(net "Net_388")
		)
		(pad "1C3" thru_hole circle
			(at 1.5 -6.899999 180)
			(size 0.6858 0.6858)
			(drill 0.381)
			(layers "*.Cu" "*.Mask")
			(remove_unused_layers no)
			(net "GND")
		)
		(pad "1C4" thru_hole circle
			(at 2.250001 -7.6 180)
			(size 0.6858 0.6858)
			(drill 0.381)
			(layers "*.Cu" "*.Mask")
			(remove_unused_layers no)
			(net "SAS_B2_TX2P")
		)
		(pad "1C5" thru_hole circle
			(at 2.999999 -6.2 180)
			(size 0.6858 0.6858)
			(drill 0.381)
			(layers "*.Cu" "*.Mask")
			(remove_unused_layers no)
			(net "SAS_B2_TX2N")
		)
		(pad "1C6" thru_hole circle
			(at 3.75 -6.899999 180)
			(size 0.6858 0.6858)
			(drill 0.381)
			(layers "*.Cu" "*.Mask")
			(remove_unused_layers no)
			(net "GND")
		)
		(pad "1C7" thru_hole circle
			(at 4.500001 -7.6 180)
			(size 0.6858 0.6858)
			(drill 0.381)
			(layers "*.Cu" "*.Mask")
			(remove_unused_layers no)
			(net "SAS_B2_TX4P")
		)
		(pad "1C8" thru_hole circle
			(at 5.25 -6.2 180)
			(size 0.6858 0.6858)
			(drill 0.381)
			(layers "*.Cu" "*.Mask")
			(remove_unused_layers no)
			(net "SAS_B2_TX4N")
		)
		(pad "1C9" thru_hole circle
			(at 6.000001 -6.899999 180)
			(size 0.6858 0.6858)
			(drill 0.381)
			(layers "*.Cu" "*.Mask")
			(remove_unused_layers no)
			(net "GND")
		)
		(pad "1D1" thru_hole circle
			(at 0 -11.4 180)
			(size 0.6858 0.6858)
			(drill 0.381)
			(layers "*.Cu" "*.Mask")
			(remove_unused_layers no)
			(net "Net_387")
		)
		(pad "1D2" thru_hole circle
			(at 0.750001 -10 180)
			(size 0.6858 0.6858)
			(drill 0.381)
			(layers "*.Cu" "*.Mask")
			(remove_unused_layers no)
			(net "Net_386")
		)
		(pad "1D3" thru_hole circle
			(at 1.5 -10.699999 180)
			(size 0.6858 0.6858)
			(drill 0.381)
			(layers "*.Cu" "*.Mask")
			(remove_unused_layers no)
			(net "GND")
		)
		(pad "1D4" thru_hole circle
			(at 2.250001 -11.4 180)
			(size 0.6858 0.6858)
			(drill 0.381)
			(layers "*.Cu" "*.Mask")
			(remove_unused_layers no)
			(net "SAS_B2_TX1P")
		)
		(pad "1D5" thru_hole circle
			(at 2.999999 -10 180)
			(size 0.6858 0.6858)
			(drill 0.381)
			(layers "*.Cu" "*.Mask")
			(remove_unused_layers no)
			(net "SAS_B2_TX1N")
		)
		(pad "1D6" thru_hole circle
			(at 3.75 -10.699999 180)
			(size 0.6858 0.6858)
			(drill 0.381)
			(layers "*.Cu" "*.Mask")
			(remove_unused_layers no)
			(net "GND")
		)
		(pad "1D7" thru_hole circle
			(at 4.500001 -11.4 180)
			(size 0.6858 0.6858)
			(drill 0.381)
			(layers "*.Cu" "*.Mask")
			(remove_unused_layers no)
			(net "SAS_B2_TX3P")
		)
		(pad "1D8" thru_hole circle
			(at 5.25 -10 180)
			(size 0.6858 0.6858)
			(drill 0.381)
			(layers "*.Cu" "*.Mask")
			(remove_unused_layers no)
			(net "SAS_B2_TX3N")
		)
		(pad "1D9" thru_hole circle
			(at 6.000001 -10.699999 180)
			(size 0.6858 0.6858)
			(drill 0.381)
			(layers "*.Cu" "*.Mask")
			(remove_unused_layers no)
			(net "GND")
		)
		(pad "2" thru_hole circle
			(at 6.000001 -13.109999 180)
			(size 1.1176 1.1176)
			(drill 0.6096)
			(layers "*.Cu" "*.Mask")
			(remove_unused_layers no)
			(net "GND")
		)
		(pad "2A1" thru_hole circle
			(at 11.000001 0 180)
			(size 0.6858 0.6858)
			(drill 0.381)
			(layers "*.Cu" "*.Mask")
			(remove_unused_layers no)
			(net "Net_385")
		)
		(pad "2A2" thru_hole circle
			(at 11.749999 1.4 180)
			(size 0.6858 0.6858)
			(drill 0.381)
			(layers "*.Cu" "*.Mask")
			(remove_unused_layers no)
			(net "Net_384")
		)
		(pad "2A3" thru_hole circle
			(at 12.5 0.700001 180)
			(size 0.6858 0.6858)
			(drill 0.381)
			(layers "*.Cu" "*.Mask")
			(remove_unused_layers no)
			(net "GND")
		)
		(pad "2A4" thru_hole circle
			(at 13.249999 0 180)
			(size 0.6858 0.6858)
			(drill 0.381)
			(layers "*.Cu" "*.Mask")
			(remove_unused_layers no)
			(net "SAS_B2_RX6P")
		)
		(pad "2A5" thru_hole circle
			(at 14 1.4 180)
			(size 0.6858 0.6858)
			(drill 0.381)
			(layers "*.Cu" "*.Mask")
			(remove_unused_layers no)
			(net "SAS_B2_RX6N")
		)
		(pad "2A6" thru_hole circle
			(at 14.750001 0.700001 180)
			(size 0.6858 0.6858)
			(drill 0.381)
			(layers "*.Cu" "*.Mask")
			(remove_unused_layers no)
			(net "GND")
		)
		(pad "2A7" thru_hole circle
			(at 15.499999 0 180)
			(size 0.6858 0.6858)
			(drill 0.381)
			(layers "*.Cu" "*.Mask")
			(remove_unused_layers no)
			(net "SAS_B2_RX8P")
		)
		(pad "2A8" thru_hole circle
			(at 16.250001 1.4 180)
			(size 0.6858 0.6858)
			(drill 0.381)
			(layers "*.Cu" "*.Mask")
			(remove_unused_layers no)
			(net "SAS_B2_RX8N")
		)
		(pad "2A9" thru_hole circle
			(at 16.999999 0.700001 180)
			(size 0.6858 0.6858)
			(drill 0.381)
			(layers "*.Cu" "*.Mask")
			(remove_unused_layers no)
			(net "GND")
		)
		(pad "2B1" thru_hole circle
			(at 11.000001 -3.8 180)
			(size 0.6858 0.6858)
			(drill 0.381)
			(layers "*.Cu" "*.Mask")
			(remove_unused_layers no)
			(net "Net_383")
		)
		(pad "2B2" thru_hole circle
			(at 11.749999 -2.4 180)
			(size 0.6858 0.6858)
			(drill 0.381)
			(layers "*.Cu" "*.Mask")
			(remove_unused_layers no)
			(net "Net_382")
		)
		(pad "2B3" thru_hole circle
			(at 12.5 -3.099999 180)
			(size 0.6858 0.6858)
			(drill 0.381)
			(layers "*.Cu" "*.Mask")
			(remove_unused_layers no)
			(net "GND")
		)
		(pad "2B4" thru_hole circle
			(at 13.249999 -3.8 180)
			(size 0.6858 0.6858)
			(drill 0.381)
			(layers "*.Cu" "*.Mask")
			(remove_unused_layers no)
			(net "SAS_B2_RX5P")
		)
		(pad "2B5" thru_hole circle
			(at 14 -2.4 180)
			(size 0.6858 0.6858)
			(drill 0.381)
			(layers "*.Cu" "*.Mask")
			(remove_unused_layers no)
			(net "SAS_B2_RX5N")
		)
		(pad "2B6" thru_hole circle
			(at 14.750001 -3.099999 180)
			(size 0.6858 0.6858)
			(drill 0.381)
			(layers "*.Cu" "*.Mask")
			(remove_unused_layers no)
			(net "GND")
		)
		(pad "2B7" thru_hole circle
			(at 15.499999 -3.8 180)
			(size 0.6858 0.6858)
			(drill 0.381)
			(layers "*.Cu" "*.Mask")
			(remove_unused_layers no)
			(net "SAS_B2_RX7P")
		)
		(pad "2B8" thru_hole circle
			(at 16.250001 -2.4 180)
			(size 0.6858 0.6858)
			(drill 0.381)
			(layers "*.Cu" "*.Mask")
			(remove_unused_layers no)
			(net "SAS_B2_RX7N")
		)
		(pad "2B9" thru_hole circle
			(at 16.999999 -3.099999 180)
			(size 0.6858 0.6858)
			(drill 0.381)
			(layers "*.Cu" "*.Mask")
			(remove_unused_layers no)
			(net "GND")
		)
		(pad "2C1" thru_hole circle
			(at 11.000001 -7.6 180)
			(size 0.6858 0.6858)
			(drill 0.381)
			(layers "*.Cu" "*.Mask")
			(remove_unused_layers no)
			(net "Net_381")
		)
		(pad "2C2" thru_hole circle
			(at 11.749999 -6.2 180)
			(size 0.6858 0.6858)
			(drill 0.381)
			(layers "*.Cu" "*.Mask")
			(remove_unused_layers no)
			(net "Net_380")
		)
		(pad "2C3" thru_hole circle
			(at 12.5 -6.899999 180)
			(size 0.6858 0.6858)
			(drill 0.381)
			(layers "*.Cu" "*.Mask")
			(remove_unused_layers no)
			(net "GND")
		)
		(pad "2C4" thru_hole circle
			(at 13.249999 -7.6 180)
			(size 0.6858 0.6858)
			(drill 0.381)
			(layers "*.Cu" "*.Mask")
			(remove_unused_layers no)
			(net "SAS_B2_TX6P")
		)
		(pad "2C5" thru_hole circle
			(at 14 -6.2 180)
			(size 0.6858 0.6858)
			(drill 0.381)
			(layers "*.Cu" "*.Mask")
			(remove_unused_layers no)
			(net "SAS_B2_TX6N")
		)
		(pad "2C6" thru_hole circle
			(at 14.750001 -6.899999 180)
			(size 0.6858 0.6858)
			(drill 0.381)
			(layers "*.Cu" "*.Mask")
			(remove_unused_layers no)
			(net "GND")
		)
		(pad "2C7" thru_hole circle
			(at 15.499999 -7.6 180)
			(size 0.6858 0.6858)
			(drill 0.381)
			(layers "*.Cu" "*.Mask")
			(remove_unused_layers no)
			(net "SAS_B2_TX8P")
		)
		(pad "2C8" thru_hole circle
			(at 16.250001 -6.2 180)
			(size 0.6858 0.6858)
			(drill 0.381)
			(layers "*.Cu" "*.Mask")
			(remove_unused_layers no)
			(net "SAS_B2_TX8N")
		)
		(pad "2C9" thru_hole circle
			(at 16.999999 -6.899999 180)
			(size 0.6858 0.6858)
			(drill 0.381)
			(layers "*.Cu" "*.Mask")
			(remove_unused_layers no)
			(net "GND")
		)
		(pad "2D1" thru_hole circle
			(at 11.000001 -11.4 180)
			(size 0.6858 0.6858)
			(drill 0.381)
			(layers "*.Cu" "*.Mask")
			(remove_unused_layers no)
			(net "Net_379")
		)
		(pad "2D2" thru_hole circle
			(at 11.749999 -10 180)
			(size 0.6858 0.6858)
			(drill 0.381)
			(layers "*.Cu" "*.Mask")
			(remove_unused_layers no)
			(net "Net_378")
		)
		(pad "2D3" thru_hole circle
			(at 12.5 -10.699999 180)
			(size 0.6858 0.6858)
			(drill 0.381)
			(layers "*.Cu" "*.Mask")
			(remove_unused_layers no)
			(net "GND")
		)
		(pad "2D4" thru_hole circle
			(at 13.249999 -11.4 180)
			(size 0.6858 0.6858)
			(drill 0.381)
			(layers "*.Cu" "*.Mask")
			(remove_unused_layers no)
			(net "SAS_B2_TX5P")
		)
		(pad "2D5" thru_hole circle
			(at 14 -10 180)
			(size 0.6858 0.6858)
			(drill 0.381)
			(layers "*.Cu" "*.Mask")
			(remove_unused_layers no)
			(net "SAS_B2_TX5N")
		)
		(pad "2D6" thru_hole circle
			(at 14.750001 -10.699999 180)
			(size 0.6858 0.6858)
			(drill 0.381)
			(layers "*.Cu" "*.Mask")
			(remove_unused_layers no)
			(net "GND")
		)
		(pad "2D7" thru_hole circle
			(at 15.499999 -11.4 180)
			(size 0.6858 0.6858)
			(drill 0.381)
			(layers "*.Cu" "*.Mask")
			(remove_unused_layers no)
			(net "SAS_B2_TX7P")
		)
		(pad "2D8" thru_hole circle
			(at 16.250001 -10 180)
			(size 0.6858 0.6858)
			(drill 0.381)
			(layers "*.Cu" "*.Mask")
			(remove_unused_layers no)
			(net "SAS_B2_TX7N")
		)
		(pad "2D9" thru_hole circle
			(at 16.999999 -10.699999 180)
			(size 0.6858 0.6858)
			(drill 0.381)
			(layers "*.Cu" "*.Mask")
			(remove_unused_layers no)
			(net "GND")
		)
		(pad "3" thru_hole circle
			(at 12.5 -13.109999 180)
			(size 1.1176 1.1176)
			(drill 0.6096)
			(layers "*.Cu" "*.Mask")
			(remove_unused_layers no)
			(net "GND")
		)
		(pad "4" thru_hole circle
			(at 16.999999 -13.109999 180)
			(size 1.1176 1.1176)
			(drill 0.6096)
			(layers "*.Cu" "*.Mask")
			(remove_unused_layers no)
			(net "GND")
		)
		(pad "5" thru_hole circle
			(at -2.5 0.700001 180)
			(size 1.1176 1.1176)
			(drill 0.6096)
			(layers "*.Cu" "*.Mask")
			(remove_unused_layers no)
			(net "GND")
		)
		(pad "6" thru_hole circle
			(at 8.500001 0.700001 180)
			(size 1.1176 1.1176)
			(drill 0.6096)
			(layers "*.Cu" "*.Mask")
			(remove_unused_layers no)
			(net "GND")
		)
		(pad "7" thru_hole circle
			(at 19.499999 0.700001 180)
			(size 1.1176 1.1176)
			(drill 0.6096)
			(layers "*.Cu" "*.Mask")
			(remove_unused_layers no)
			(net "GND")
		)
		(pad "8" thru_hole circle
			(at -2.5 14.01 180)
			(size 1.1176 1.1176)
			(drill 0.6096)
			(layers "*.Cu" "*.Mask")
			(remove_unused_layers no)
			(net "GND")
		)
		(pad "9" thru_hole circle
			(at 8.500001 14.01 180)
			(size 1.1176 1.1176)
			(drill 0.6096)
			(layers "*.Cu" "*.Mask")
			(remove_unused_layers no)
			(net "GND")
		)
		(pad "10" thru_hole circle
			(at 19.499999 14.01 180)
			(size 1.1176 1.1176)
			(drill 0.6096)
			(layers "*.Cu" "*.Mask")
			(remove_unused_layers no)
			(net "GND")
		)
	)
	(footprint ""
		(layer "F.Cu")
		(at -331.47 7.6708)
		(property "Reference" "R79"
			(at 3.175 -0.1397 0)
			(unlocked yes)
			(layer "F.SilkS")
			(effects
				(font
					(size 0.762 0.5334)
					(thickness 0.1016)
				)
			)
		)
		(property "Value" ""
			(at 0 0 0)
			(layer "F.Fab")
			(effects
				(font
					(size 1.27 1.27)
				)
			)
		)
		(duplicate_pad_numbers_are_jumpers no)
		(fp_line
			(start 0 -0.381)
			(end 0 0.381)
			(stroke
				(width 0.127)
				(type default)
			)
			(layer "F.SilkS")
		)
		(fp_poly
			(pts
				(xy 1.255601 0.6564) (xy -1.255601 0.6564) (xy -1.255601 -0.656399) (xy 1.255601 -0.656399)
			)
			(stroke
				(width 0)
				(type default)
			)
			(fill no)
			(layer "F.CrtYd")
		)
		(fp_line
			(start -0.800001 -0.399999)
			(end -0.800001 0.399999)
			(stroke
				(width 0.1)
				(type default)
			)
			(layer "F.Fab")
		)
		(fp_line
			(start -0.800001 0.399999)
			(end 0.800001 0.399999)
			(stroke
				(width 0.1)
				(type default)
			)
			(layer "F.Fab")
		)
		(fp_line
			(start 0.800001 -0.399999)
			(end -0.800001 -0.399999)
			(stroke
				(width 0.1)
				(type default)
			)
			(layer "F.Fab")
		)
		(fp_line
			(start 0.800001 0.399999)
			(end 0.800001 -0.399999)
			(stroke
				(width 0.1)
				(type default)
			)
			(layer "F.Fab")
		)
		(pad "1" smd rect
			(at -0.650001 0)
			(size 0.7112 0.8128)
			(layers "F.Cu" "F.Mask" "F.Paste")
			(net "ETH40G_B1_LPMODE")
		)
		(pad "2" smd rect
			(at 0.650001 0 180)
			(size 0.7112 0.8128)
			(layers "F.Cu" "F.Mask" "F.Paste")
			(net "GND")
		)
	)
	(footprint ""
		(layer "F.Cu")
		(at -331.47 17.4498 180)
		(property "Reference" "R75"
			(at -3.2004 0.0889 0)
			(unlocked yes)
			(layer "F.SilkS")
			(effects
				(font
					(size 0.762 0.5334)
					(thickness 0.1016)
				)
			)
		)
		(property "Value" ""
			(at 0 0 180)
			(layer "F.Fab")
			(effects
				(font
					(size 1.27 1.27)
				)
			)
		)
		(duplicate_pad_numbers_are_jumpers no)
		(fp_line
			(start 0 -0.381)
			(end 0 0.381)
			(stroke
				(width 0.127)
				(type default)
			)
			(layer "F.SilkS")
		)
		(fp_poly
			(pts
				(xy 1.255601 0.656399) (xy -1.255601 0.656399) (xy -1.255601 -0.6564) (xy 1.255601 -0.6564)
			)
			(stroke
				(width 0)
				(type default)
			)
			(fill no)
			(layer "F.CrtYd")
		)
		(fp_line
			(start 0.800001 0.399999)
			(end 0.800001 -0.399999)
			(stroke
				(width 0.1)
				(type default)
			)
			(layer "F.Fab")
		)
		(fp_line
			(start 0.800001 -0.399999)
			(end -0.800001 -0.399999)
			(stroke
				(width 0.1)
				(type default)
			)
			(layer "F.Fab")
		)
		(fp_line
			(start -0.800001 0.399999)
			(end 0.800001 0.399999)
			(stroke
				(width 0.1)
				(type default)
			)
			(layer "F.Fab")
		)
		(fp_line
			(start -0.800001 -0.399999)
			(end -0.800001 0.399999)
			(stroke
				(width 0.1)
				(type default)
			)
			(layer "F.Fab")
		)
		(pad "1" smd rect
			(at -0.650001 0 180)
			(size 0.7112 0.8128)
			(layers "F.Cu" "F.Mask" "F.Paste")
			(net "SKU_B1_ID2")
		)
		(pad "2" smd rect
			(at 0.650001 0)
			(size 0.7112 0.8128)
			(layers "F.Cu" "F.Mask" "F.Paste")
			(net "ETH40G_B1_RESET_N")
		)
	)
	(footprint ""
		(layer "F.Cu")
		(at -385.826 31.1912 90)
		(property "Reference" "R85"
			(at -0.0508 1.5621 90)
			(unlocked yes)
			(layer "F.SilkS")
			(effects
				(font
					(size 0.762 0.5334)
					(thickness 0.1016)
				)
			)
		)
		(property "Value" ""
			(at 0 0 90)
			(layer "F.Fab")
			(effects
				(font
					(size 1.27 1.27)
				)
			)
		)
		(duplicate_pad_numbers_are_jumpers no)
		(fp_line
			(start 0 -0.381)
			(end 0 0.381)
			(stroke
				(width 0.127)
				(type default)
			)
			(layer "F.SilkS")
		)
		(fp_poly
			(pts
				(xy 1.255601 0.656399) (xy -1.255601 0.656399) (xy -1.255601 -0.6564) (xy 1.255601 -0.6564)
			)
			(stroke
				(width 0)
				(type default)
			)
			(fill no)
			(layer "F.CrtYd")
		)
		(fp_line
			(start 0.800001 -0.399999)
			(end -0.800001 -0.399999)
			(stroke
				(width 0.1)
				(type default)
			)
			(layer "F.Fab")
		)
		(fp_line
			(start -0.800001 -0.399999)
			(end -0.800001 0.399999)
			(stroke
				(width 0.1)
				(type default)
			)
			(layer "F.Fab")
		)
		(fp_line
			(start 0.800001 0.399999)
			(end 0.800001 -0.399999)
			(stroke
				(width 0.1)
				(type default)
			)
			(layer "F.Fab")
		)
		(fp_line
			(start -0.800001 0.399999)
			(end 0.800001 0.399999)
			(stroke
				(width 0.1)
				(type default)
			)
			(layer "F.Fab")
		)
		(pad "1" smd rect
			(at -0.650001 0 90)
			(size 0.7112 0.8128)
			(layers "F.Cu" "F.Mask" "F.Paste")
			(net "GND")
		)
		(pad "2" smd rect
			(at 0.650001 0 270)
			(size 0.7112 0.8128)
			(layers "F.Cu" "F.Mask" "F.Paste")
			(net "BLADE_MATED_B1_N<0>")
		)
	)
	(footprint ""
		(layer "F.Cu")
		(at -266.446 0)
		(property "Reference" "FS9"
			(at 2.413 0.0381 0)
			(unlocked yes)
			(layer "F.SilkS")
			(effects
				(font
					(size 0.762 0.5334)
					(thickness 0.1016)
				)
			)
		)
		(property "Value" ""
			(at 0 0 0)
			(layer "F.Fab")
			(effects
				(font
					(size 1.27 1.27)
				)
			)
		)
		(duplicate_pad_numbers_are_jumpers no)
		(fp_poly
			(pts
				(xy -1.002101 0.504) (xy -1.002101 -0.504) (xy 1.002101 -0.504) (xy 1.002101 0.504)
			)
			(stroke
				(width 0)
				(type default)
			)
			(fill no)
			(layer "F.CrtYd")
		)
		(fp_line
			(start -0.499999 -0.25)
			(end -0.499999 0.25)
			(stroke
				(width 0.1)
				(type default)
			)
			(layer "F.Fab")
		)
		(fp_line
			(start -0.499999 0.25)
			(end 0.499999 0.25)
			(stroke
				(width 0.1)
				(type default)
			)
			(layer "F.Fab")
		)
		(fp_line
			(start 0.499999 -0.25)
			(end -0.499999 -0.25)
			(stroke
				(width 0.1)
				(type default)
			)
			(layer "F.Fab")
		)
		(fp_line
			(start 0.499999 0.25)
			(end 0.499999 -0.25)
			(stroke
				(width 0.1)
				(type default)
			)
			(layer "F.Fab")
		)
		(pad "1" smd rect
			(at -0.459999 0 90)
			(size 0.508 0.5842)
			(layers "F.Cu" "F.Mask" "F.Paste")
			(net "P3V3_B1_QSFP")
		)
		(pad "2" smd rect
			(at 0.459999 0 90)
			(size 0.508 0.5842)
			(layers "F.Cu" "F.Mask" "F.Paste")
			(net "UNNAMED_16_FERRITE_I40_A")
		)
	)
	(footprint ""
		(layer "F.Cu")
		(at -266.192 11.6332 -90)
		(property "Reference" "FS10"
			(at -0.26924 -1.9177 90)
			(unlocked yes)
			(layer "F.SilkS")
			(effects
				(font
					(size 0.762 0.5334)
					(thickness 0.1016)
				)
			)
		)
		(property "Value" ""
			(at 0 0 270)
			(layer "F.Fab")
			(effects
				(font
					(size 1.27 1.27)
				)
			)
		)
		(duplicate_pad_numbers_are_jumpers no)
		(fp_poly
			(pts
				(xy -1.002101 0.504) (xy -1.002101 -0.503999) (xy 1.002101 -0.503999) (xy 1.002101 0.504)
			)
			(stroke
				(width 0)
				(type default)
			)
			(fill no)
			(layer "F.CrtYd")
		)
		(fp_line
			(start -0.499999 0.25)
			(end 0.499999 0.25)
			(stroke
				(width 0.1)
				(type default)
			)
			(layer "F.Fab")
		)
		(fp_line
			(start 0.499999 0.25)
			(end 0.499999 -0.249999)
			(stroke
				(width 0.1)
				(type default)
			)
			(layer "F.Fab")
		)
		(fp_line
			(start -0.499999 -0.249999)
			(end -0.499999 0.25)
			(stroke
				(width 0.1)
				(type default)
			)
			(layer "F.Fab")
		)
		(fp_line
			(start 0.499999 -0.249999)
			(end -0.499999 -0.249999)
			(stroke
				(width 0.1)
				(type default)
			)
			(layer "F.Fab")
		)
		(pad "1" smd rect
			(at -0.459999 0)
			(size 0.508 0.5842)
			(layers "F.Cu" "F.Mask" "F.Paste")
			(net "UNNAMED_16_FERRITE_I46_B")
		)
		(pad "2" smd rect
			(at 0.459999 0)
			(size 0.508 0.5842)
			(layers "F.Cu" "F.Mask" "F.Paste")
			(net "P3V3_B1_QSFP")
		)
	)
	(footprint ""
		(layer "F.Cu")
		(at -269.748 3.048 -90)
		(property "Reference" "C36"
			(at -0.02286 1.15316 90)
			(unlocked yes)
			(layer "F.SilkS")
			(effects
				(font
					(size 0.762 0.5334)
					(thickness 0.1016)
				)
			)
		)
		(property "Value" ""
			(at 0 0 270)
			(layer "F.Fab")
			(effects
				(font
					(size 1.27 1.27)
				)
			)
		)
		(duplicate_pad_numbers_are_jumpers no)
		(fp_line
			(start 0 -0.381)
			(end 0 0.381)
			(stroke
				(width 0.127)
				(type default)
			)
			(layer "F.SilkS")
		)
		(fp_poly
			(pts
				(xy 1.2533 0.6564) (xy -1.253299 0.6564) (xy -1.253299 -0.656399) (xy 1.2533 -0.656399)
			)
			(stroke
				(width 0)
				(type default)
			)
			(fill no)
			(layer "F.CrtYd")
		)
		(fp_line
			(start -0.762 0.381)
			(end 0.762 0.381)
			(stroke
				(width 0.1)
				(type default)
			)
			(layer "F.Fab")
		)
		(fp_line
			(start 0.762 0.381)
			(end 0.762 -0.381)
			(stroke
				(width 0.1)
				(type default)
			)
			(layer "F.Fab")
		)
		(fp_line
			(start -0.762 -0.381)
			(end -0.762 0.381)
			(stroke
				(width 0.1)
				(type default)
			)
			(layer "F.Fab")
		)
		(fp_line
			(start 0.762 -0.381)
			(end -0.762 -0.381)
			(stroke
				(width 0.1)
				(type default)
			)
			(layer "F.Fab")
		)
		(pad "1" smd rect
			(at -0.6477 0 270)
			(size 0.7112 0.8128)
			(layers "F.Cu" "F.Mask" "F.Paste")
			(net "P3V3_40G_B1_VCC_RX")
		)
		(pad "2" smd rect
			(at 0.6477 0 90)
			(size 0.7112 0.8128)
			(layers "F.Cu" "F.Mask" "F.Paste")
			(net "GND")
		)
	)
	(footprint ""
		(layer "F.Cu")
		(at -331.47 10.4648)
		(property "Reference" "R83"
			(at 3.175 0.1143 0)
			(unlocked yes)
			(layer "F.SilkS")
			(effects
				(font
					(size 0.762 0.5334)
					(thickness 0.1016)
				)
			)
		)
		(property "Value" ""
			(at 0 0 0)
			(layer "F.Fab")
			(effects
				(font
					(size 1.27 1.27)
				)
			)
		)
		(duplicate_pad_numbers_are_jumpers no)
		(fp_line
			(start 0 -0.381)
			(end 0 0.381)
			(stroke
				(width 0.127)
				(type default)
			)
			(layer "F.SilkS")
		)
		(fp_poly
			(pts
				(xy 1.255601 0.6564) (xy -1.255601 0.6564) (xy -1.255601 -0.656399) (xy 1.255601 -0.656399)
			)
			(stroke
				(width 0)
				(type default)
			)
			(fill no)
			(layer "F.CrtYd")
		)
		(fp_line
			(start -0.800001 -0.399999)
			(end -0.800001 0.399999)
			(stroke
				(width 0.1)
				(type default)
			)
			(layer "F.Fab")
		)
		(fp_line
			(start -0.800001 0.399999)
			(end 0.800001 0.399999)
			(stroke
				(width 0.1)
				(type default)
			)
			(layer "F.Fab")
		)
		(fp_line
			(start 0.800001 -0.399999)
			(end -0.800001 -0.399999)
			(stroke
				(width 0.1)
				(type default)
			)
			(layer "F.Fab")
		)
		(fp_line
			(start 0.800001 0.399999)
			(end 0.800001 -0.399999)
			(stroke
				(width 0.1)
				(type default)
			)
			(layer "F.Fab")
		)
		(pad "1" smd rect
			(at -0.650001 0)
			(size 0.7112 0.8128)
			(layers "F.Cu" "F.Mask" "F.Paste")
			(net "P3V3_B1_QSFP")
		)
		(pad "2" smd rect
			(at 0.650001 0 180)
			(size 0.7112 0.8128)
			(layers "F.Cu" "F.Mask" "F.Paste")
			(net "ETH40G_B1_RESET_N")
		)
	)
	(footprint ""
		(layer "F.Cu")
		(at -267.109689 36.82998 180)
		(property "Reference" "J10"
			(at 0 11.834899 0)
			(unlocked yes)
			(layer "F.SilkS")
			(effects
				(font
					(size 0.762 0.5334)
					(thickness 0.1016)
				)
			)
		)
		(property "Value" ""
			(at 0 0 180)
			(layer "F.Fab")
			(effects
				(font
					(size 1.27 1.27)
				)
			)
		)
		(duplicate_pad_numbers_are_jumpers no)
		(fp_line
			(start 5.325001 10.870001)
			(end -5.325 10.870001)
			(stroke
				(width 0.127)
				(type default)
			)
			(layer "F.SilkS")
		)
		(fp_line
			(start 5.325001 9.27098)
			(end 5.325001 10.870001)
			(stroke
				(width 0.127)
				(type default)
			)
			(layer "F.SilkS")
		)
		(fp_line
			(start 5.325001 -1.58498)
			(end 5.325001 7.36598)
			(stroke
				(width 0.127)
				(type default)
			)
			(layer "F.SilkS")
		)
		(fp_line
			(start 5.325001 -12.76)
			(end 5.325001 -3.269)
			(stroke
				(width 0.127)
				(type default)
			)
			(layer "F.SilkS")
		)
		(fp_line
			(start 2.775001 -12.76)
			(end 5.325001 -12.76)
			(stroke
				(width 0.127)
				(type default)
			)
			(layer "F.SilkS")
		)
		(fp_line
			(start 2.775001 -42.660001)
			(end 2.775001 -12.76)
			(stroke
				(width 0.127)
				(type default)
			)
			(layer "F.SilkS")
		)
		(fp_line
			(start -2.775 -12.76)
			(end -2.775 -42.660001)
			(stroke
				(width 0.127)
				(type default)
			)
			(layer "F.SilkS")
		)
		(fp_line
			(start -2.775 -42.660001)
			(end 2.775001 -42.660001)
			(stroke
				(width 0.127)
				(type default)
			)
			(layer "F.SilkS")
		)
		(fp_line
			(start -5.325 10.870001)
			(end -5.325 -12.76)
			(stroke
				(width 0.127)
				(type default)
			)
			(layer "F.SilkS")
		)
		(fp_line
			(start -5.325 -12.76)
			(end -2.775 -12.76)
			(stroke
				(width 0.127)
				(type default)
			)
			(layer "F.SilkS")
		)
		(fp_poly
			(pts
				(arc
					(start 7.3152 0)
					(mid -7.3152 0)
					(end 7.3152 0)
				)
			)
			(stroke
				(width 0)
				(type default)
			)
			(fill no)
			(layer "B.CrtYd")
		)
		(fp_poly
			(pts
				(xy 6.324999 11.869999) (xy -6.324998 11.869999) (xy -6.324998 -13.76) (xy -3.774998 -13.76) (xy -3.774998 -43.659999)
				(xy 3.774999 -43.659999) (xy 3.774999 -13.76) (xy 6.324999 -13.76)
			)
			(stroke
				(width 0)
				(type default)
			)
			(fill no)
			(layer "F.CrtYd")
		)
		(fp_line
			(start 5.325001 10.870001)
			(end -5.325 10.870001)
			(stroke
				(width 0.1)
				(type default)
			)
			(layer "F.Fab")
		)
		(fp_line
			(start 5.325001 -12.76)
			(end 5.325001 10.870001)
			(stroke
				(width 0.1)
				(type default)
			)
			(layer "F.Fab")
		)
		(fp_line
			(start 2.775001 -12.76)
			(end 5.325001 -12.76)
			(stroke
				(width 0.1)
				(type default)
			)
			(layer "F.Fab")
		)
		(fp_line
			(start 2.775001 -42.660001)
			(end 2.775001 -12.76)
			(stroke
				(width 0.1)
				(type default)
			)
			(layer "F.Fab")
		)
		(fp_line
			(start -2.775 -12.76)
			(end -2.775 -42.660001)
			(stroke
				(width 0.1)
				(type default)
			)
			(layer "F.Fab")
		)
		(fp_line
			(start -2.775 -42.660001)
			(end 2.775001 -42.660001)
			(stroke
				(width 0.1)
				(type default)
			)
			(layer "F.Fab")
		)
		(fp_line
			(start -5.325 10.870001)
			(end -5.325 -12.76)
			(stroke
				(width 0.1)
				(type default)
			)
			(layer "F.Fab")
		)
		(fp_line
			(start -5.325 -12.76)
			(end -2.775 -12.76)
			(stroke
				(width 0.1)
				(type default)
			)
			(layer "F.Fab")
		)
		(pad "" np_thru_hole circle
			(at 0 -5.629999 180)
			(size 1.27 1.27)
			(drill 3.9624)
			(layers "*.Cu" "*.Mask")
		)
		(pad "" np_thru_hole circle
			(at 0 6.619999 180)
			(size 1.27 1.27)
			(drill 3.9624)
			(layers "*.Cu" "*.Mask")
		)
		(pad "1" thru_hole circle
			(at 0 0 180)
			(size 5.588 5.588)
			(drill 3.9624)
			(layers "*.Cu" "*.Mask")
			(remove_unused_layers no)
			(net "GND")
		)
		(zone
			(layers "F.Cu" "B.Cu" "In1.Cu" "In2.Cu" "In3.Cu" "In4.Cu" "In5.Cu" "In6.Cu")
			(hatch none 0.5)
			(connect_pads
				(clearance 0)
			)
			(min_thickness 0.25)
			(keepout
				(tracks not_allowed)
				(vias allowed)
				(pads allowed)
				(copperpour not_allowed)
				(footprints allowed)
			)
			(placement
				(enabled no)
				(sheetname "")
			)
			(fill
				(thermal_gap 0.5)
				(thermal_bridge_width 0.5)
				(island_removal_mode 0)
			)
			(polygon
				(pts
					(arc
						(start -269.471889 30.20998)
						(mid -264.747489 30.20998)
						(end -269.471889 30.20998)
					)
				)
			)
		)
		(zone
			(layers "F.Cu" "B.Cu" "In1.Cu" "In2.Cu" "In3.Cu" "In4.Cu" "In5.Cu" "In6.Cu")
			(hatch none 0.5)
			(connect_pads
				(clearance 0)
			)
			(min_thickness 0.25)
			(keepout
				(tracks not_allowed)
				(vias allowed)
				(pads allowed)
				(copperpour not_allowed)
				(footprints allowed)
			)
			(placement
				(enabled no)
				(sheetname "")
			)
			(fill
				(thermal_gap 0.5)
				(thermal_bridge_width 0.5)
				(island_removal_mode 0)
			)
			(polygon
				(pts
					(arc
						(start -269.471889 42.459979)
						(mid -264.747489 42.459979)
						(end -269.471889 42.459979)
					)
				)
			)
		)
	)
	(footprint ""
		(layer "F.Cu")
		(at -44.958 -0.254)
		(property "Reference" "FS6"
			(at 3.048 0.0381 0)
			(unlocked yes)
			(layer "F.SilkS")
			(effects
				(font
					(size 0.762 0.5334)
					(thickness 0.1016)
				)
			)
		)
		(property "Value" ""
			(at 0 0 0)
			(layer "F.Fab")
			(effects
				(font
					(size 1.27 1.27)
				)
			)
		)
		(duplicate_pad_numbers_are_jumpers no)
		(fp_poly
			(pts
				(xy -1.002101 0.504) (xy -1.002101 -0.504) (xy 1.002101 -0.504) (xy 1.002101 0.504)
			)
			(stroke
				(width 0)
				(type default)
			)
			(fill no)
			(layer "F.CrtYd")
		)
		(fp_line
			(start -0.499999 -0.25)
			(end -0.499999 0.249999)
			(stroke
				(width 0.1)
				(type default)
			)
			(layer "F.Fab")
		)
		(fp_line
			(start -0.499999 0.249999)
			(end 0.499999 0.249999)
			(stroke
				(width 0.1)
				(type default)
			)
			(layer "F.Fab")
		)
		(fp_line
			(start 0.499999 -0.25)
			(end -0.499999 -0.25)
			(stroke
				(width 0.1)
				(type default)
			)
			(layer "F.Fab")
		)
		(fp_line
			(start 0.499999 0.249999)
			(end 0.499999 -0.25)
			(stroke
				(width 0.1)
				(type default)
			)
			(layer "F.Fab")
		)
		(pad "1" smd rect
			(at -0.459999 0 90)
			(size 0.508 0.5842)
			(layers "F.Cu" "F.Mask" "F.Paste")
			(net "P3V3_B2_QSFP")
		)
		(pad "2" smd rect
			(at 0.459999 0 90)
			(size 0.508 0.5842)
			(layers "F.Cu" "F.Mask" "F.Paste")
			(net "UNNAMED_8_FERRITE_I54_A")
		)
	)
	(footprint ""
		(layer "F.Cu")
		(at -344.649689 36.82998 180)
		(property "Reference" "J3"
			(at 0 11.834899 0)
			(unlocked yes)
			(layer "F.SilkS")
			(effects
				(font
					(size 0.762 0.5334)
					(thickness 0.1016)
				)
			)
		)
		(property "Value" ""
			(at 0 0 180)
			(layer "F.Fab")
			(effects
				(font
					(size 1.27 1.27)
				)
			)
		)
		(duplicate_pad_numbers_are_jumpers no)
		(fp_line
			(start 5.325001 10.870001)
			(end -5.325001 10.870001)
			(stroke
				(width 0.127)
				(type default)
			)
			(layer "F.SilkS")
		)
		(fp_line
			(start 5.325001 -12.76)
			(end 5.325001 10.870001)
			(stroke
				(width 0.127)
				(type default)
			)
			(layer "F.SilkS")
		)
		(fp_line
			(start 2.775001 -12.76)
			(end 5.325001 -12.76)
			(stroke
				(width 0.127)
				(type default)
			)
			(layer "F.SilkS")
		)
		(fp_line
			(start 2.775001 -42.660001)
			(end 2.775001 -12.76)
			(stroke
				(width 0.127)
				(type default)
			)
			(layer "F.SilkS")
		)
		(fp_line
			(start -2.775001 -12.76)
			(end -2.775001 -42.660001)
			(stroke
				(width 0.127)
				(type default)
			)
			(layer "F.SilkS")
		)
		(fp_line
			(start -2.775001 -42.660001)
			(end 2.775001 -42.660001)
			(stroke
				(width 0.127)
				(type default)
			)
			(layer "F.SilkS")
		)
		(fp_line
			(start -5.325001 10.870001)
			(end -5.325001 -12.76)
			(stroke
				(width 0.127)
				(type default)
			)
			(layer "F.SilkS")
		)
		(fp_line
			(start -5.325001 -12.76)
			(end -2.775001 -12.76)
			(stroke
				(width 0.127)
				(type default)
			)
			(layer "F.SilkS")
		)
		(fp_poly
			(pts
				(arc
					(start 7.3152 0)
					(mid -7.3152 0)
					(end 7.3152 0)
				)
			)
			(stroke
				(width 0)
				(type default)
			)
			(fill no)
			(layer "B.CrtYd")
		)
		(fp_poly
			(pts
				(xy 6.324999 11.869999) (xy -6.324999 11.869999) (xy -6.324999 -13.76) (xy -3.774999 -13.76) (xy -3.774999 -43.659999)
				(xy 3.774999 -43.659999) (xy 3.774999 -13.76) (xy 6.324999 -13.76)
			)
			(stroke
				(width 0)
				(type default)
			)
			(fill no)
			(layer "F.CrtYd")
		)
		(fp_line
			(start 5.325001 10.870001)
			(end -5.325001 10.870001)
			(stroke
				(width 0.1)
				(type default)
			)
			(layer "F.Fab")
		)
		(fp_line
			(start 5.325001 -12.76)
			(end 5.325001 10.870001)
			(stroke
				(width 0.1)
				(type default)
			)
			(layer "F.Fab")
		)
		(fp_line
			(start 2.775001 -12.76)
			(end 5.325001 -12.76)
			(stroke
				(width 0.1)
				(type default)
			)
			(layer "F.Fab")
		)
		(fp_line
			(start 2.775001 -42.660001)
			(end 2.775001 -12.76)
			(stroke
				(width 0.1)
				(type default)
			)
			(layer "F.Fab")
		)
		(fp_line
			(start -2.775001 -12.76)
			(end -2.775001 -42.660001)
			(stroke
				(width 0.1)
				(type default)
			)
			(layer "F.Fab")
		)
		(fp_line
			(start -2.775001 -42.660001)
			(end 2.775001 -42.660001)
			(stroke
				(width 0.1)
				(type default)
			)
			(layer "F.Fab")
		)
		(fp_line
			(start -5.325001 10.870001)
			(end -5.325001 -12.76)
			(stroke
				(width 0.1)
				(type default)
			)
			(layer "F.Fab")
		)
		(fp_line
			(start -5.325001 -12.76)
			(end -2.775001 -12.76)
			(stroke
				(width 0.1)
				(type default)
			)
			(layer "F.Fab")
		)
		(pad "" np_thru_hole circle
			(at 0 -5.629999 180)
			(size 1.27 1.27)
			(drill 3.9624)
			(layers "*.Cu" "*.Mask")
		)
		(pad "" np_thru_hole circle
			(at 0 6.619999 180)
			(size 1.27 1.27)
			(drill 3.9624)
			(layers "*.Cu" "*.Mask")
		)
		(pad "1" thru_hole circle
			(at 0 0 180)
			(size 5.588 5.588)
			(drill 3.9624)
			(layers "*.Cu" "*.Mask")
			(remove_unused_layers no)
			(net "GND")
		)
		(zone
			(layers "F.Cu" "B.Cu" "In1.Cu" "In2.Cu" "In3.Cu" "In4.Cu" "In5.Cu" "In6.Cu")
			(hatch none 0.5)
			(connect_pads
				(clearance 0)
			)
			(min_thickness 0.25)
			(keepout
				(tracks not_allowed)
				(vias allowed)
				(pads allowed)
				(copperpour not_allowed)
				(footprints allowed)
			)
			(placement
				(enabled no)
				(sheetname "")
			)
			(fill
				(thermal_gap 0.5)
				(thermal_bridge_width 0.5)
				(island_removal_mode 0)
			)
			(polygon
				(pts
					(arc
						(start -347.011889 30.20998)
						(mid -342.287489 30.20998)
						(end -347.011889 30.20998)
					)
				)
			)
		)
		(zone
			(layers "F.Cu" "B.Cu" "In1.Cu" "In2.Cu" "In3.Cu" "In4.Cu" "In5.Cu" "In6.Cu")
			(hatch none 0.5)
			(connect_pads
				(clearance 0)
			)
			(min_thickness 0.25)
			(keepout
				(tracks not_allowed)
				(vias allowed)
				(pads allowed)
				(copperpour not_allowed)
				(footprints allowed)
			)
			(placement
				(enabled no)
				(sheetname "")
			)
			(fill
				(thermal_gap 0.5)
				(thermal_bridge_width 0.5)
				(island_removal_mode 0)
			)
			(polygon
				(pts
					(arc
						(start -347.011889 42.459979)
						(mid -342.287489 42.459979)
						(end -347.011889 42.459979)
					)
				)
			)
		)
	)
	(footprint ""
		(layer "F.Cu")
		(at -58.610401 43.345202)
		(property "Reference" "C9"
			(at 2.476401 -0.127102 0)
			(unlocked yes)
			(layer "F.SilkS")
			(effects
				(font
					(size 0.762 0.5334)
					(thickness 0.1016)
				)
			)
		)
		(property "Value" ""
			(at 0 0 0)
			(layer "F.Fab")
			(effects
				(font
					(size 1.27 1.27)
				)
			)
		)
		(duplicate_pad_numbers_are_jumpers no)
		(fp_poly
			(pts
				(xy -0.999299 0.503999) (xy -0.999299 -0.504) (xy 0.9993 -0.504) (xy 0.9993 0.503999)
			)
			(stroke
				(width 0)
				(type default)
			)
			(fill no)
			(layer "F.CrtYd")
		)
		(fp_line
			(start -0.499999 -0.25)
			(end 0.499999 -0.25)
			(stroke
				(width 0.1)
				(type default)
			)
			(layer "F.Fab")
		)
		(fp_line
			(start -0.499999 0.249999)
			(end -0.499999 -0.25)
			(stroke
				(width 0.1)
				(type default)
			)
			(layer "F.Fab")
		)
		(fp_line
			(start 0.499999 -0.25)
			(end 0.499999 0.249999)
			(stroke
				(width 0.1)
				(type default)
			)
			(layer "F.Fab")
		)
		(fp_line
			(start 0.499999 0.249999)
			(end -0.499999 0.249999)
			(stroke
				(width 0.1)
				(type default)
			)
			(layer "F.Fab")
		)
		(pad "1" smd rect
			(at -0.4572 0 90)
			(size 0.508 0.5842)
			(layers "F.Cu" "F.Mask" "F.Paste")
			(net "P3V3_10G_B2_VCCT")
		)
		(pad "2" smd rect
			(at 0.4572 0 90)
			(size 0.508 0.5842)
			(layers "F.Cu" "F.Mask" "F.Paste")
			(net "GND")
		)
	)
	(footprint ""
		(layer "F.Cu")
		(at -63.4746 45.72)
		(property "Reference" "FB3"
			(at -0.9144 1.0541 0)
			(unlocked yes)
			(layer "F.SilkS")
			(effects
				(font
					(size 0.762 0.5334)
					(thickness 0.1016)
				)
				(justify left)
			)
		)
		(property "Value" ""
			(at 0 0 0)
			(layer "F.Fab")
			(effects
				(font
					(size 1.27 1.27)
				)
			)
		)
		(duplicate_pad_numbers_are_jumpers no)
		(fp_poly
			(pts
				(xy -1.016 0.508) (xy -1.016 -0.508) (xy 1.016 -0.508) (xy 1.016 0.508)
			)
			(stroke
				(width 0)
				(type default)
			)
			(fill no)
			(layer "F.CrtYd")
		)
		(fp_line
			(start -0.508 -0.254)
			(end 0.508 -0.254)
			(stroke
				(width 0.1)
				(type default)
			)
			(layer "F.Fab")
		)
		(fp_line
			(start -0.508 0.254)
			(end -0.508 -0.254)
			(stroke
				(width 0.1)
				(type default)
			)
			(layer "F.Fab")
		)
		(fp_line
			(start 0.508 -0.254)
			(end 0.508 0.254)
			(stroke
				(width 0.1)
				(type default)
			)
			(layer "F.Fab")
		)
		(fp_line
			(start 0.508 0.254)
			(end -0.508 0.254)
			(stroke
				(width 0.1)
				(type default)
			)
			(layer "F.Fab")
		)
		(pad "1" smd rect
			(at -0.4572 0 90)
			(size 0.508 0.5842)
			(layers "F.Cu" "F.Mask" "F.Paste")
			(net "UNNAMED_6_FERRITE_I24_A")
		)
		(pad "2" smd rect
			(at 0.4572 0 90)
			(size 0.508 0.5842)
			(layers "F.Cu" "F.Mask" "F.Paste")
			(net "P3V3_10G_B2_VCCR")
		)
	)
	(footprint ""
		(layer "F.Cu")
		(at -284.563401 43.345202 180)
		(property "Reference" "C7"
			(at 2.126399 -0.050698 0)
			(unlocked yes)
			(layer "F.SilkS")
			(effects
				(font
					(size 0.762 0.5334)
					(thickness 0.1016)
				)
			)
		)
		(property "Value" ""
			(at 0 0 180)
			(layer "F.Fab")
			(effects
				(font
					(size 1.27 1.27)
				)
			)
		)
		(duplicate_pad_numbers_are_jumpers no)
		(fp_poly
			(pts
				(xy -0.9993 0.504) (xy -0.9993 -0.503999) (xy 0.999299 -0.503999) (xy 0.999299 0.504)
			)
			(stroke
				(width 0)
				(type default)
			)
			(fill no)
			(layer "F.CrtYd")
		)
		(fp_line
			(start 0.499999 0.25)
			(end -0.499999 0.25)
			(stroke
				(width 0.1)
				(type default)
			)
			(layer "F.Fab")
		)
		(fp_line
			(start 0.499999 -0.249999)
			(end 0.499999 0.25)
			(stroke
				(width 0.1)
				(type default)
			)
			(layer "F.Fab")
		)
		(fp_line
			(start -0.499999 0.25)
			(end -0.499999 -0.249999)
			(stroke
				(width 0.1)
				(type default)
			)
			(layer "F.Fab")
		)
		(fp_line
			(start -0.499999 -0.249999)
			(end 0.499999 -0.249999)
			(stroke
				(width 0.1)
				(type default)
			)
			(layer "F.Fab")
		)
		(pad "1" smd rect
			(at -0.4572 0 270)
			(size 0.508 0.5842)
			(layers "F.Cu" "F.Mask" "F.Paste")
			(net "P3V3_10G_B1_VCCR")
		)
		(pad "2" smd rect
			(at 0.4572 0 270)
			(size 0.508 0.5842)
			(layers "F.Cu" "F.Mask" "F.Paste")
			(net "GND")
		)
	)
	(footprint ""
		(layer "F.Cu")
		(at -46.109689 36.82998 180)
		(property "Reference" "J22"
			(at 3.166311 12.40788 0)
			(unlocked yes)
			(layer "F.SilkS")
			(effects
				(font
					(size 0.762 0.5334)
					(thickness 0.1016)
				)
			)
		)
		(property "Value" ""
			(at 0 0 180)
			(layer "F.Fab")
			(effects
				(font
					(size 1.27 1.27)
				)
			)
		)
		(duplicate_pad_numbers_are_jumpers no)
		(fp_line
			(start 5.325001 10.870001)
			(end -5.325 10.870001)
			(stroke
				(width 0.127)
				(type default)
			)
			(layer "F.SilkS")
		)
		(fp_line
			(start 5.325001 9.27098)
			(end 5.325001 10.870001)
			(stroke
				(width 0.127)
				(type default)
			)
			(layer "F.SilkS")
		)
		(fp_line
			(start 5.325001 -1.88216)
			(end 5.325001 7.36598)
			(stroke
				(width 0.127)
				(type default)
			)
			(layer "F.SilkS")
		)
		(fp_line
			(start 5.325001 -12.76)
			(end 5.325001 -3.14708)
			(stroke
				(width 0.127)
				(type default)
			)
			(layer "F.SilkS")
		)
		(fp_line
			(start 2.775001 -12.76)
			(end 5.325001 -12.76)
			(stroke
				(width 0.127)
				(type default)
			)
			(layer "F.SilkS")
		)
		(fp_line
			(start 2.775001 -42.660001)
			(end 2.775001 -12.76)
			(stroke
				(width 0.127)
				(type default)
			)
			(layer "F.SilkS")
		)
		(fp_line
			(start -2.775 -12.76)
			(end -2.775 -42.660001)
			(stroke
				(width 0.127)
				(type default)
			)
			(layer "F.SilkS")
		)
		(fp_line
			(start -2.775 -42.660001)
			(end 2.775001 -42.660001)
			(stroke
				(width 0.127)
				(type default)
			)
			(layer "F.SilkS")
		)
		(fp_line
			(start -5.325 10.870001)
			(end -5.325 -12.76)
			(stroke
				(width 0.127)
				(type default)
			)
			(layer "F.SilkS")
		)
		(fp_line
			(start -5.325 -12.76)
			(end -2.775 -12.76)
			(stroke
				(width 0.127)
				(type default)
			)
			(layer "F.SilkS")
		)
		(fp_poly
			(pts
				(arc
					(start -7.3152 0)
					(mid 7.3152 0)
					(end -7.3152 0)
				)
			)
			(stroke
				(width 0)
				(type default)
			)
			(fill no)
			(layer "B.CrtYd")
		)
		(fp_poly
			(pts
				(xy 6.324999 11.869999) (xy -6.324998 11.869999) (xy -6.324998 -13.76) (xy -3.774998 -13.76) (xy -3.774998 -43.659999)
				(xy 3.774999 -43.659999) (xy 3.774999 -13.76) (xy 6.324999 -13.76)
			)
			(stroke
				(width 0)
				(type default)
			)
			(fill no)
			(layer "F.CrtYd")
		)
		(fp_line
			(start 5.325001 10.870001)
			(end -5.325 10.870001)
			(stroke
				(width 0.1)
				(type default)
			)
			(layer "F.Fab")
		)
		(fp_line
			(start 5.325001 -12.76)
			(end 5.325001 10.870001)
			(stroke
				(width 0.1)
				(type default)
			)
			(layer "F.Fab")
		)
		(fp_line
			(start 2.775001 -12.76)
			(end 5.325001 -12.76)
			(stroke
				(width 0.1)
				(type default)
			)
			(layer "F.Fab")
		)
		(fp_line
			(start 2.775001 -42.660001)
			(end 2.775001 -12.76)
			(stroke
				(width 0.1)
				(type default)
			)
			(layer "F.Fab")
		)
		(fp_line
			(start -2.775 -12.76)
			(end -2.775 -42.660001)
			(stroke
				(width 0.1)
				(type default)
			)
			(layer "F.Fab")
		)
		(fp_line
			(start -2.775 -42.660001)
			(end 2.775001 -42.660001)
			(stroke
				(width 0.1)
				(type default)
			)
			(layer "F.Fab")
		)
		(fp_line
			(start -5.325 10.870001)
			(end -5.325 -12.76)
			(stroke
				(width 0.1)
				(type default)
			)
			(layer "F.Fab")
		)
		(fp_line
			(start -5.325 -12.76)
			(end -2.775 -12.76)
			(stroke
				(width 0.1)
				(type default)
			)
			(layer "F.Fab")
		)
		(pad "" np_thru_hole circle
			(at 0 -5.629999 180)
			(size 1.27 1.27)
			(drill 3.9624)
			(layers "*.Cu" "*.Mask")
		)
		(pad "" np_thru_hole circle
			(at 0 6.619999 180)
			(size 1.27 1.27)
			(drill 3.9624)
			(layers "*.Cu" "*.Mask")
		)
		(pad "1" thru_hole circle
			(at 0 0 180)
			(size 5.588 5.588)
			(drill 3.9624)
			(layers "*.Cu" "*.Mask")
			(remove_unused_layers no)
			(net "GND")
		)
		(zone
			(layers "F.Cu" "B.Cu" "In1.Cu" "In2.Cu" "In3.Cu" "In4.Cu" "In5.Cu" "In6.Cu")
			(hatch none 0.5)
			(connect_pads
				(clearance 0)
			)
			(min_thickness 0.25)
			(keepout
				(tracks not_allowed)
				(vias allowed)
				(pads allowed)
				(copperpour not_allowed)
				(footprints allowed)
			)
			(placement
				(enabled no)
				(sheetname "")
			)
			(fill
				(thermal_gap 0.5)
				(thermal_bridge_width 0.5)
				(island_removal_mode 0)
			)
			(polygon
				(pts
					(arc
						(start -43.747489 30.20998)
						(mid -48.471889 30.20998)
						(end -43.747489 30.20998)
					)
				)
			)
		)
		(zone
			(layers "F.Cu" "B.Cu" "In1.Cu" "In2.Cu" "In3.Cu" "In4.Cu" "In5.Cu" "In6.Cu")
			(hatch none 0.5)
			(connect_pads
				(clearance 0)
			)
			(min_thickness 0.25)
			(keepout
				(tracks not_allowed)
				(vias allowed)
				(pads allowed)
				(copperpour not_allowed)
				(footprints allowed)
			)
			(placement
				(enabled no)
				(sheetname "")
			)
			(fill
				(thermal_gap 0.5)
				(thermal_bridge_width 0.5)
				(island_removal_mode 0)
			)
			(polygon
				(pts
					(arc
						(start -43.747489 42.459979)
						(mid -48.471889 42.459979)
						(end -43.747489 42.459979)
					)
				)
			)
		)
	)
	(footprint ""
		(layer "F.Cu")
		(at -296.145801 4.127602)
		(property "Reference" "R20"
			(at 3.067901 0.528218 0)
			(unlocked yes)
			(layer "F.SilkS")
			(effects
				(font
					(size 0.762 0.5334)
					(thickness 0.1016)
				)
			)
		)
		(property "Value" ""
			(at 0 0 0)
			(layer "F.Fab")
			(effects
				(font
					(size 1.27 1.27)
				)
			)
		)
		(duplicate_pad_numbers_are_jumpers no)
		(fp_line
			(start 0 -0.381)
			(end 0 0.381)
			(stroke
				(width 0.127)
				(type default)
			)
			(layer "F.SilkS")
		)
		(fp_poly
			(pts
				(xy 1.255601 0.656399) (xy -1.255601 0.656399) (xy -1.255601 -0.6564) (xy 1.255601 -0.6564)
			)
			(stroke
				(width 0)
				(type default)
			)
			(fill no)
			(layer "F.CrtYd")
		)
		(fp_line
			(start -0.800001 -0.4)
			(end -0.800001 0.399999)
			(stroke
				(width 0.1)
				(type default)
			)
			(layer "F.Fab")
		)
		(fp_line
			(start -0.800001 0.399999)
			(end 0.800001 0.399999)
			(stroke
				(width 0.1)
				(type default)
			)
			(layer "F.Fab")
		)
		(fp_line
			(start 0.800001 -0.4)
			(end -0.800001 -0.4)
			(stroke
				(width 0.1)
				(type default)
			)
			(layer "F.Fab")
		)
		(fp_line
			(start 0.800001 0.399999)
			(end 0.800001 -0.4)
			(stroke
				(width 0.1)
				(type default)
			)
			(layer "F.Fab")
		)
		(pad "1" smd rect
			(at -0.650001 0)
			(size 0.7112 0.8128)
			(layers "F.Cu" "F.Mask" "F.Paste")
			(net "P3V3_B1_QSFP")
		)
		(pad "2" smd rect
			(at 0.650001 0 180)
			(size 0.7112 0.8128)
			(layers "F.Cu" "F.Mask" "F.Paste")
			(net "ETH10G_B1_TX_DIS")
		)
	)
	(footprint ""
		(layer "F.Cu")
		(at -26.68 45.360001 180)
		(property "Reference" "J23"
			(at 5 16.084901 0)
			(unlocked yes)
			(layer "F.SilkS")
			(effects
				(font
					(size 0.762 0.5334)
					(thickness 0.1016)
				)
			)
		)
		(property "Value" ""
			(at 0 0 180)
			(layer "F.Fab")
			(effects
				(font
					(size 1.27 1.27)
				)
			)
		)
		(duplicate_pad_numbers_are_jumpers no)
		(fp_line
			(start 10.950001 15.3)
			(end -0.950001 15.3)
			(stroke
				(width 0.127)
				(type default)
			)
			(layer "F.SilkS")
		)
		(fp_line
			(start 10.950001 -11.999999)
			(end 10.950001 15.3)
			(stroke
				(width 0.127)
				(type default)
			)
			(layer "F.SilkS")
		)
		(fp_line
			(start -0.950001 15.3)
			(end -0.950001 -11.999999)
			(stroke
				(width 0.127)
				(type default)
			)
			(layer "F.SilkS")
		)
		(fp_line
			(start -0.950001 -11.999999)
			(end 10.950001 -11.999999)
			(stroke
				(width 0.127)
				(type default)
			)
			(layer "F.SilkS")
		)
		(fp_poly
			(pts
				(arc
					(start -4.93 12.500001)
					(mid -3.486036 15.986037)
					(end 0 17.430001)
				)
				(arc
					(start 10 17.430001)
					(mid 13.486036 15.986037)
					(end 14.930001 12.500001)
				)
				(arc
					(start 14.930001 -0.1)
					(mid 13.486037 -3.586037)
					(end 10 -5.03)
				)
				(arc
					(start 0 -5.03)
					(mid -3.486036 -3.586036)
					(end -4.93 -0.1)
				)
			)
			(stroke
				(width 0)
				(type default)
			)
			(fill no)
			(layer "B.CrtYd")
		)
		(fp_poly
			(pts
				(xy 11.949999 16.300001) (xy -1.950001 16.300001) (xy -1.950001 -12.999999) (xy 11.949999 -12.999999)
			)
			(stroke
				(width 0)
				(type default)
			)
			(fill no)
			(layer "F.CrtYd")
		)
		(fp_line
			(start 10.950001 15.3)
			(end -0.950001 15.3)
			(stroke
				(width 0.1)
				(type default)
			)
			(layer "F.Fab")
		)
		(fp_line
			(start 10.950001 -11.999999)
			(end 10.950001 15.3)
			(stroke
				(width 0.1)
				(type default)
			)
			(layer "F.Fab")
		)
		(fp_line
			(start -0.950001 15.3)
			(end -0.950001 -11.999999)
			(stroke
				(width 0.1)
				(type default)
			)
			(layer "F.Fab")
		)
		(fp_line
			(start -0.950001 -11.999999)
			(end 10.950001 -11.999999)
			(stroke
				(width 0.1)
				(type default)
			)
			(layer "F.Fab")
		)
		(fp_text user "I6"
			(at 12.130999 11.0809 0)
			(unlocked yes)
			(layer "F.SilkS")
			(effects
				(font
					(size 0.762 0.5334)
					(thickness 0.1016)
				)
			)
		)
		(fp_text user "E6"
			(at 12.130999 5.480901 0)
			(unlocked yes)
			(layer "F.SilkS")
			(effects
				(font
					(size 0.762 0.5334)
					(thickness 0.1016)
				)
			)
		)
		(fp_text user "A6"
			(at 12.130999 -0.1191 0)
			(unlocked yes)
			(layer "F.SilkS")
			(effects
				(font
					(size 0.762 0.5334)
					(thickness 0.1016)
				)
			)
		)
		(fp_text user "*"
			(at -1.5 -1.328549 0)
			(unlocked yes)
			(layer "F.SilkS")
			(effects
				(font
					(size 0.381 0.381)
					(thickness 0.381)
				)
			)
		)
		(fp_text user "I1"
			(at -1.876999 10.9539 0)
			(unlocked yes)
			(layer "F.SilkS")
			(effects
				(font
					(size 0.762 0.5334)
					(thickness 0.1016)
				)
			)
		)
		(fp_text user "E1"
			(at -1.876999 5.353901 0)
			(unlocked yes)
			(layer "F.SilkS")
			(effects
				(font
					(size 0.762 0.5334)
					(thickness 0.1016)
				)
			)
		)
		(fp_text user "A1"
			(at -1.876999 -0.2461 0)
			(unlocked yes)
			(layer "F.SilkS")
			(effects
				(font
					(size 0.762 0.5334)
					(thickness 0.1016)
				)
			)
		)
		(fp_text user "I8"
			(at 11.55 11.0809 0)
			(unlocked yes)
			(layer "B.SilkS")
			(effects
				(font
					(size 0.762 0.5334)
					(thickness 0.1016)
				)
				(justify mirror)
			)
		)
		(fp_text user "E8"
			(at 11.55 5.480901 0)
			(unlocked yes)
			(layer "B.SilkS")
			(effects
				(font
					(size 0.762 0.5334)
					(thickness 0.1016)
				)
				(justify mirror)
			)
		)
		(fp_text user "A8"
			(at 11.55 -0.1191 0)
			(unlocked yes)
			(layer "B.SilkS")
			(effects
				(font
					(size 0.762 0.5334)
					(thickness 0.1016)
				)
				(justify mirror)
			)
		)
		(fp_text user "E1"
			(at -1.29524 5.774101 0)
			(unlocked yes)
			(layer "B.SilkS")
			(effects
				(font
					(size 0.762 0.5334)
					(thickness 0.1016)
				)
				(justify mirror)
			)
		)
		(fp_text user "I1"
			(at -1.5 11.0809 0)
			(unlocked yes)
			(layer "B.SilkS")
			(effects
				(font
					(size 0.762 0.5334)
					(thickness 0.1016)
				)
				(justify mirror)
			)
		)
		(fp_text user "A1"
			(at -1.549999 -0.1191 0)
			(unlocked yes)
			(layer "B.SilkS")
			(effects
				(font
					(size 0.762 0.5334)
					(thickness 0.1016)
				)
				(justify mirror)
			)
		)
		(pad "A1" thru_hole circle
			(at 0 0 180)
			(size 0.8128 0.8128)
			(drill 0.508)
			(layers "*.Cu" "*.Mask")
			(remove_unused_layers no)
			(net "SAS_B2_TX1P")
		)
		(pad "A2" thru_hole circle
			(at 2.000001 -0.1 180)
			(size 0.8128 0.8128)
			(drill 0.508)
			(layers "*.Cu" "*.Mask")
			(remove_unused_layers no)
			(net "GND")
		)
		(pad "A3" thru_hole circle
			(at 4 0 180)
			(size 0.8128 0.8128)
			(drill 0.508)
			(layers "*.Cu" "*.Mask")
			(remove_unused_layers no)
			(net "SERIAL_B2_TX1")
		)
		(pad "A4" thru_hole circle
			(at 6.000001 -0.1 180)
			(size 0.8128 0.8128)
			(drill 0.508)
			(layers "*.Cu" "*.Mask")
			(remove_unused_layers no)
			(net "GND")
		)
		(pad "A5" thru_hole circle
			(at 7.999999 0 180)
			(size 0.8128 0.8128)
			(drill 0.508)
			(layers "*.Cu" "*.Mask")
			(remove_unused_layers no)
			(net "SAS_B2_TX6P")
		)
		(pad "A6" thru_hole circle
			(at 10 -0.1 180)
			(size 0.8128 0.8128)
			(drill 0.508)
			(layers "*.Cu" "*.Mask")
			(remove_unused_layers no)
			(net "GND")
		)
		(pad "B1" thru_hole circle
			(at 0 1.4 180)
			(size 0.8128 0.8128)
			(drill 0.508)
			(layers "*.Cu" "*.Mask")
			(remove_unused_layers no)
			(net "SAS_B2_TX1N")
		)
		(pad "B2" thru_hole circle
			(at 2.000001 1.3 180)
			(size 0.8128 0.8128)
			(drill 0.508)
			(layers "*.Cu" "*.Mask")
			(remove_unused_layers no)
			(net "SAS_B2_RX3P")
		)
		(pad "B3" thru_hole circle
			(at 4 1.4 180)
			(size 0.8128 0.8128)
			(drill 0.508)
			(layers "*.Cu" "*.Mask")
			(remove_unused_layers no)
			(net "SERIAL_B2_RX1")
		)
		(pad "B4" thru_hole circle
			(at 6.000001 1.3 180)
			(size 0.8128 0.8128)
			(drill 0.508)
			(layers "*.Cu" "*.Mask")
			(remove_unused_layers no)
			(net "JBOD_B2_MATED_N")
		)
		(pad "B5" thru_hole circle
			(at 7.999999 1.4 180)
			(size 0.8128 0.8128)
			(drill 0.508)
			(layers "*.Cu" "*.Mask")
			(remove_unused_layers no)
			(net "SAS_B2_TX6N")
		)
		(pad "B6" thru_hole circle
			(at 10 1.3 180)
			(size 0.8128 0.8128)
			(drill 0.508)
			(layers "*.Cu" "*.Mask")
			(remove_unused_layers no)
			(net "SAS_B2_RX8P")
		)
		(pad "C1" thru_hole circle
			(at 0 2.799999 180)
			(size 0.8128 0.8128)
			(drill 0.508)
			(layers "*.Cu" "*.Mask")
			(remove_unused_layers no)
			(net "GND")
		)
		(pad "C2" thru_hole circle
			(at 2.000001 2.7 180)
			(size 0.8128 0.8128)
			(drill 0.508)
			(layers "*.Cu" "*.Mask")
			(remove_unused_layers no)
			(net "SAS_B2_RX3N")
		)
		(pad "C3" thru_hole circle
			(at 4 2.799999 180)
			(size 0.8128 0.8128)
			(drill 0.508)
			(layers "*.Cu" "*.Mask")
			(remove_unused_layers no)
			(net "GND")
		)
		(pad "C4" thru_hole circle
			(at 6.000001 2.7 180)
			(size 0.8128 0.8128)
			(drill 0.508)
			(layers "*.Cu" "*.Mask")
			(remove_unused_layers no)
			(net "BLADE_B2_EN1")
		)
		(pad "C5" thru_hole circle
			(at 7.999999 2.799999 180)
			(size 0.8128 0.8128)
			(drill 0.508)
			(layers "*.Cu" "*.Mask")
			(remove_unused_layers no)
			(net "GND")
		)
		(pad "C6" thru_hole circle
			(at 10 2.7 180)
			(size 0.8128 0.8128)
			(drill 0.508)
			(layers "*.Cu" "*.Mask")
			(remove_unused_layers no)
			(net "SAS_B2_RX8N")
		)
		(pad "D1" thru_hole circle
			(at 0 4.199999 180)
			(size 0.8128 0.8128)
			(drill 0.508)
			(layers "*.Cu" "*.Mask")
			(remove_unused_layers no)
			(net "SAS_B2_RX1P")
		)
		(pad "D2" thru_hole circle
			(at 2.000001 4.099999 180)
			(size 0.8128 0.8128)
			(drill 0.508)
			(layers "*.Cu" "*.Mask")
			(remove_unused_layers no)
			(net "GND")
		)
		(pad "D3" thru_hole circle
			(at 4 4.199999 180)
			(size 0.8128 0.8128)
			(drill 0.508)
			(layers "*.Cu" "*.Mask")
			(remove_unused_layers no)
			(net "SAS_B2_RX4P")
		)
		(pad "D4" thru_hole circle
			(at 6.000001 4.099999 180)
			(size 0.8128 0.8128)
			(drill 0.508)
			(layers "*.Cu" "*.Mask")
			(remove_unused_layers no)
			(net "GND")
		)
		(pad "D5" thru_hole circle
			(at 7.999999 4.199999 180)
			(size 0.8128 0.8128)
			(drill 0.508)
			(layers "*.Cu" "*.Mask")
			(remove_unused_layers no)
			(net "SAS_B2_RX6P")
		)
		(pad "D6" thru_hole circle
			(at 10 4.099999 180)
			(size 0.8128 0.8128)
			(drill 0.508)
			(layers "*.Cu" "*.Mask")
			(remove_unused_layers no)
			(net "GND")
		)
		(pad "E1" thru_hole circle
			(at 0 5.599999 180)
			(size 0.8128 0.8128)
			(drill 0.508)
			(layers "*.Cu" "*.Mask")
			(remove_unused_layers no)
			(net "SAS_B2_RX1N")
		)
		(pad "E2" thru_hole circle
			(at 2.000001 5.499999 180)
			(size 0.8128 0.8128)
			(drill 0.508)
			(layers "*.Cu" "*.Mask")
			(remove_unused_layers no)
			(net "SAS_B2_TX3P")
		)
		(pad "E3" thru_hole circle
			(at 4 5.599999 180)
			(size 0.8128 0.8128)
			(drill 0.508)
			(layers "*.Cu" "*.Mask")
			(remove_unused_layers no)
			(net "SAS_B2_RX4N")
		)
		(pad "E4" thru_hole circle
			(at 6.000001 5.499999 180)
			(size 0.8128 0.8128)
			(drill 0.508)
			(layers "*.Cu" "*.Mask")
			(remove_unused_layers no)
			(net "SAS_B2_TX5P")
		)
		(pad "E5" thru_hole circle
			(at 7.999999 5.599999 180)
			(size 0.8128 0.8128)
			(drill 0.508)
			(layers "*.Cu" "*.Mask")
			(remove_unused_layers no)
			(net "SAS_B2_RX6N")
		)
		(pad "E6" thru_hole circle
			(at 10 5.499999 180)
			(size 0.8128 0.8128)
			(drill 0.508)
			(layers "*.Cu" "*.Mask")
			(remove_unused_layers no)
			(net "SAS_B2_TX8P")
		)
		(pad "F1" thru_hole circle
			(at 0 7.000001 180)
			(size 0.8128 0.8128)
			(drill 0.508)
			(layers "*.Cu" "*.Mask")
			(remove_unused_layers no)
			(net "GND")
		)
		(pad "F2" thru_hole circle
			(at 2.000001 6.899999 180)
			(size 0.8128 0.8128)
			(drill 0.508)
			(layers "*.Cu" "*.Mask")
			(remove_unused_layers no)
			(net "SAS_B2_TX3N")
		)
		(pad "F3" thru_hole circle
			(at 4 7.000001 180)
			(size 0.8128 0.8128)
			(drill 0.508)
			(layers "*.Cu" "*.Mask")
			(remove_unused_layers no)
			(net "GND")
		)
		(pad "F4" thru_hole circle
			(at 6.000001 6.899999 180)
			(size 0.8128 0.8128)
			(drill 0.508)
			(layers "*.Cu" "*.Mask")
			(remove_unused_layers no)
			(net "SAS_B2_TX5N")
		)
		(pad "F5" thru_hole circle
			(at 7.999999 7.000001 180)
			(size 0.8128 0.8128)
			(drill 0.508)
			(layers "*.Cu" "*.Mask")
			(remove_unused_layers no)
			(net "GND")
		)
		(pad "F6" thru_hole circle
			(at 10 6.899999 180)
			(size 0.8128 0.8128)
			(drill 0.508)
			(layers "*.Cu" "*.Mask")
			(remove_unused_layers no)
			(net "SAS_B2_TX8N")
		)
		(pad "G1" thru_hole circle
			(at 0 8.400001 180)
			(size 0.8128 0.8128)
			(drill 0.508)
			(layers "*.Cu" "*.Mask")
			(remove_unused_layers no)
			(net "SAS_B2_TX2P")
		)
		(pad "G2" thru_hole circle
			(at 2.000001 8.300001 180)
			(size 0.8128 0.8128)
			(drill 0.508)
			(layers "*.Cu" "*.Mask")
			(remove_unused_layers no)
			(net "GND")
		)
		(pad "G3" thru_hole circle
			(at 4 8.400001 180)
			(size 0.8128 0.8128)
			(drill 0.508)
			(layers "*.Cu" "*.Mask")
			(remove_unused_layers no)
			(net "SAS_B2_TX4P")
		)
		(pad "G4" thru_hole circle
			(at 6.000001 8.300001 180)
			(size 0.8128 0.8128)
			(drill 0.508)
			(layers "*.Cu" "*.Mask")
			(remove_unused_layers no)
			(net "GND")
		)
		(pad "G5" thru_hole circle
			(at 7.999999 8.400001 180)
			(size 0.8128 0.8128)
			(drill 0.508)
			(layers "*.Cu" "*.Mask")
			(remove_unused_layers no)
			(net "SAS_B2_TX7P")
		)
		(pad "G6" thru_hole circle
			(at 10 8.300001 180)
			(size 0.8128 0.8128)
			(drill 0.508)
			(layers "*.Cu" "*.Mask")
			(remove_unused_layers no)
			(net "GND")
		)
		(pad "H1" thru_hole circle
			(at 0 9.800001 180)
			(size 0.8128 0.8128)
			(drill 0.508)
			(layers "*.Cu" "*.Mask")
			(remove_unused_layers no)
			(net "SAS_B2_TX2N")
		)
		(pad "H2" thru_hole circle
			(at 2.000001 9.700001 180)
			(size 0.8128 0.8128)
			(drill 0.508)
			(layers "*.Cu" "*.Mask")
			(remove_unused_layers no)
			(net "SAS_B2_RX2P")
		)
		(pad "H3" thru_hole circle
			(at 4 9.800001 180)
			(size 0.8128 0.8128)
			(drill 0.508)
			(layers "*.Cu" "*.Mask")
			(remove_unused_layers no)
			(net "SAS_B2_TX4N")
		)
		(pad "H4" thru_hole circle
			(at 6.000001 9.700001 180)
			(size 0.8128 0.8128)
			(drill 0.508)
			(layers "*.Cu" "*.Mask")
			(remove_unused_layers no)
			(net "SAS_B2_RX5P")
		)
		(pad "H5" thru_hole circle
			(at 7.999999 9.800001 180)
			(size 0.8128 0.8128)
			(drill 0.508)
			(layers "*.Cu" "*.Mask")
			(remove_unused_layers no)
			(net "SAS_B2_TX7N")
		)
		(pad "H6" thru_hole circle
			(at 10 9.700001 180)
			(size 0.8128 0.8128)
			(drill 0.508)
			(layers "*.Cu" "*.Mask")
			(remove_unused_layers no)
			(net "SAS_B2_RX7P")
		)
		(pad "I1" thru_hole circle
			(at 0 11.2 180)
			(size 0.8128 0.8128)
			(drill 0.508)
			(layers "*.Cu" "*.Mask")
			(remove_unused_layers no)
			(net "GND")
		)
		(pad "I2" thru_hole circle
			(at 2.000001 11.100001 180)
			(size 0.8128 0.8128)
			(drill 0.508)
			(layers "*.Cu" "*.Mask")
			(remove_unused_layers no)
			(net "SAS_B2_RX2N")
		)
		(pad "I3" thru_hole circle
			(at 4 11.2 180)
			(size 0.8128 0.8128)
			(drill 0.508)
			(layers "*.Cu" "*.Mask")
			(remove_unused_layers no)
			(net "GND")
		)
		(pad "I4" thru_hole circle
			(at 6.000001 11.100001 180)
			(size 0.8128 0.8128)
			(drill 0.508)
			(layers "*.Cu" "*.Mask")
			(remove_unused_layers no)
			(net "SAS_B2_RX5N")
		)
		(pad "I5" thru_hole circle
			(at 7.999999 11.2 180)
			(size 0.8128 0.8128)
			(drill 0.508)
			(layers "*.Cu" "*.Mask")
			(remove_unused_layers no)
			(net "GND")
		)
		(pad "I6" thru_hole circle
			(at 10 11.100001 180)
			(size 0.8128 0.8128)
			(drill 0.508)
			(layers "*.Cu" "*.Mask")
			(remove_unused_layers no)
			(net "SAS_B2_RX7N")
		)
		(pad "J2" thru_hole circle
			(at 2.000001 12.5 180)
			(size 0.8128 0.8128)
			(drill 0.508)
			(layers "*.Cu" "*.Mask")
			(remove_unused_layers no)
			(net "GND")
		)
		(pad "J4" thru_hole circle
			(at 6.000001 12.5 180)
			(size 0.8128 0.8128)
			(drill 0.508)
			(layers "*.Cu" "*.Mask")
			(remove_unused_layers no)
			(net "GND")
		)
		(pad "J6" thru_hole circle
			(at 10 12.5 180)
			(size 0.8128 0.8128)
			(drill 0.508)
			(layers "*.Cu" "*.Mask")
			(remove_unused_layers no)
			(net "GND")
		)
	)
	(footprint ""
		(layer "F.Cu")
		(at -266.2174 4.2164 180)
		(property "Reference" "C39"
			(at -3.3655 0.04572 0)
			(unlocked yes)
			(layer "F.SilkS")
			(effects
				(font
					(size 0.762 0.5334)
					(thickness 0.1016)
				)
			)
		)
		(property "Value" ""
			(at 0 0 180)
			(layer "F.Fab")
			(effects
				(font
					(size 1.27 1.27)
				)
			)
		)
		(duplicate_pad_numbers_are_jumpers no)
		(fp_line
			(start 0 -0.381)
			(end 0 0.381)
			(stroke
				(width 0.127)
				(type default)
			)
			(layer "F.SilkS")
		)
		(fp_poly
			(pts
				(xy 1.2533 0.656399) (xy -1.253299 0.656399) (xy -1.253299 -0.6564) (xy 1.2533 -0.6564)
			)
			(stroke
				(width 0)
				(type default)
			)
			(fill no)
			(layer "F.CrtYd")
		)
		(fp_line
			(start 0.762 0.381)
			(end 0.762 -0.381)
			(stroke
				(width 0.1)
				(type default)
			)
			(layer "F.Fab")
		)
		(fp_line
			(start 0.762 -0.381)
			(end -0.762 -0.381)
			(stroke
				(width 0.1)
				(type default)
			)
			(layer "F.Fab")
		)
		(fp_line
			(start -0.762 0.381)
			(end 0.762 0.381)
			(stroke
				(width 0.1)
				(type default)
			)
			(layer "F.Fab")
		)
		(fp_line
			(start -0.762 -0.381)
			(end -0.762 0.381)
			(stroke
				(width 0.1)
				(type default)
			)
			(layer "F.Fab")
		)
		(pad "1" smd rect
			(at -0.6477 0 180)
			(size 0.7112 0.8128)
			(layers "F.Cu" "F.Mask" "F.Paste")
			(net "P3V3_B1_QSFP")
		)
		(pad "2" smd rect
			(at 0.6477 0)
			(size 0.7112 0.8128)
			(layers "F.Cu" "F.Mask" "F.Paste")
			(net "GND")
		)
	)
	(footprint ""
		(layer "F.Cu")
		(at -276.9362 45.6438)
		(property "Reference" "FS2"
			(at 0.0762 1.1303 0)
			(unlocked yes)
			(layer "F.SilkS")
			(effects
				(font
					(size 0.762 0.5334)
					(thickness 0.1016)
				)
			)
		)
		(property "Value" ""
			(at 0 0 0)
			(layer "F.Fab")
			(effects
				(font
					(size 1.27 1.27)
				)
			)
		)
		(duplicate_pad_numbers_are_jumpers no)
		(fp_poly
			(pts
				(xy -1.002101 0.504) (xy -1.002101 -0.503999) (xy 1.002101 -0.503999) (xy 1.002101 0.504)
			)
			(stroke
				(width 0)
				(type default)
			)
			(fill no)
			(layer "F.CrtYd")
		)
		(fp_line
			(start -0.499999 -0.249999)
			(end -0.499999 0.25)
			(stroke
				(width 0.1)
				(type default)
			)
			(layer "F.Fab")
		)
		(fp_line
			(start -0.499999 0.25)
			(end 0.499999 0.25)
			(stroke
				(width 0.1)
				(type default)
			)
			(layer "F.Fab")
		)
		(fp_line
			(start 0.499999 -0.249999)
			(end -0.499999 -0.249999)
			(stroke
				(width 0.1)
				(type default)
			)
			(layer "F.Fab")
		)
		(fp_line
			(start 0.499999 0.25)
			(end 0.499999 -0.249999)
			(stroke
				(width 0.1)
				(type default)
			)
			(layer "F.Fab")
		)
		(pad "1" smd rect
			(at -0.459999 0 90)
			(size 0.508 0.5842)
			(layers "F.Cu" "F.Mask" "F.Paste")
			(net "UNNAMED_4_FERRITE_I151_B")
		)
		(pad "2" smd rect
			(at 0.459999 0 90)
			(size 0.508 0.5842)
			(layers "F.Cu" "F.Mask" "F.Paste")
			(net "P3V3_B1_QSFP")
		)
	)
	(footprint ""
		(layer "F.Cu")
		(at -136.017 31.6992 90)
		(property "Reference" "C14"
			(at -2.286 -0.0889 90)
			(unlocked yes)
			(layer "F.SilkS")
			(effects
				(font
					(size 0.762 0.5334)
					(thickness 0.1016)
				)
			)
		)
		(property "Value" ""
			(at 0 0 90)
			(layer "F.Fab")
			(effects
				(font
					(size 1.27 1.27)
				)
			)
		)
		(duplicate_pad_numbers_are_jumpers no)
		(fp_line
			(start 0 -0.381)
			(end 0 0.381)
			(stroke
				(width 0.127)
				(type default)
			)
			(layer "F.SilkS")
		)
		(fp_poly
			(pts
				(xy 1.253299 0.656399) (xy -1.2533 0.656399) (xy -1.2533 -0.6564) (xy 1.253299 -0.6564)
			)
			(stroke
				(width 0)
				(type default)
			)
			(fill no)
			(layer "F.CrtYd")
		)
		(fp_line
			(start 0.762 -0.381)
			(end -0.762 -0.381)
			(stroke
				(width 0.1)
				(type default)
			)
			(layer "F.Fab")
		)
		(fp_line
			(start -0.762 -0.381)
			(end -0.762 0.381)
			(stroke
				(width 0.1)
				(type default)
			)
			(layer "F.Fab")
		)
		(fp_line
			(start 0.762 0.381)
			(end 0.762 -0.381)
			(stroke
				(width 0.1)
				(type default)
			)
			(layer "F.Fab")
		)
		(fp_line
			(start -0.762 0.381)
			(end 0.762 0.381)
			(stroke
				(width 0.1)
				(type default)
			)
			(layer "F.Fab")
		)
		(pad "1" smd rect
			(at -0.6477 0 90)
			(size 0.7112 0.8128)
			(layers "F.Cu" "F.Mask" "F.Paste")
			(net "P12V")
		)
		(pad "2" smd rect
			(at 0.6477 0 270)
			(size 0.7112 0.8128)
			(layers "F.Cu" "F.Mask" "F.Paste")
			(net "GND")
		)
	)
	(footprint ""
		(layer "F.Cu")
		(at -131.8768 31.877 90)
		(property "Reference" "C16"
			(at -2.286 0.0381 90)
			(unlocked yes)
			(layer "F.SilkS")
			(effects
				(font
					(size 0.762 0.5334)
					(thickness 0.1016)
				)
			)
		)
		(property "Value" ""
			(at 0 0 90)
			(layer "F.Fab")
			(effects
				(font
					(size 1.27 1.27)
				)
			)
		)
		(duplicate_pad_numbers_are_jumpers no)
		(fp_poly
			(pts
				(xy -0.9993 0.503999) (xy -0.9993 -0.504) (xy 0.999299 -0.504) (xy 0.999299 0.503999)
			)
			(stroke
				(width 0)
				(type default)
			)
			(fill no)
			(layer "F.CrtYd")
		)
		(fp_line
			(start 0.499999 -0.25)
			(end 0.499999 0.249999)
			(stroke
				(width 0.1)
				(type default)
			)
			(layer "F.Fab")
		)
		(fp_line
			(start -0.499999 -0.25)
			(end 0.499999 -0.25)
			(stroke
				(width 0.1)
				(type default)
			)
			(layer "F.Fab")
		)
		(fp_line
			(start 0.499999 0.249999)
			(end -0.499999 0.249999)
			(stroke
				(width 0.1)
				(type default)
			)
			(layer "F.Fab")
		)
		(fp_line
			(start -0.499999 0.249999)
			(end -0.499999 -0.25)
			(stroke
				(width 0.1)
				(type default)
			)
			(layer "F.Fab")
		)
		(pad "1" smd rect
			(at -0.4572 0 180)
			(size 0.508 0.5842)
			(layers "F.Cu" "F.Mask" "F.Paste")
			(net "P12V")
		)
		(pad "2" smd rect
			(at 0.4572 0 180)
			(size 0.508 0.5842)
			(layers "F.Cu" "F.Mask" "F.Paste")
			(net "GND")
		)
	)
	(footprint ""
		(layer "F.Cu")
		(at -55.9308 45.6946)
		(property "Reference" "FS4"
			(at -0.0762 1.0795 0)
			(unlocked yes)
			(layer "F.SilkS")
			(effects
				(font
					(size 0.762 0.5334)
					(thickness 0.1016)
				)
			)
		)
		(property "Value" ""
			(at 0 0 0)
			(layer "F.Fab")
			(effects
				(font
					(size 1.27 1.27)
				)
			)
		)
		(duplicate_pad_numbers_are_jumpers no)
		(fp_poly
			(pts
				(xy -1.002101 0.504) (xy -1.002101 -0.503999) (xy 1.002101 -0.503999) (xy 1.002101 0.504)
			)
			(stroke
				(width 0)
				(type default)
			)
			(fill no)
			(layer "F.CrtYd")
		)
		(fp_line
			(start -0.499999 -0.249999)
			(end -0.499999 0.25)
			(stroke
				(width 0.1)
				(type default)
			)
			(layer "F.Fab")
		)
		(fp_line
			(start -0.499999 0.25)
			(end 0.499999 0.25)
			(stroke
				(width 0.1)
				(type default)
			)
			(layer "F.Fab")
		)
		(fp_line
			(start 0.499999 -0.249999)
			(end -0.499999 -0.249999)
			(stroke
				(width 0.1)
				(type default)
			)
			(layer "F.Fab")
		)
		(fp_line
			(start 0.499999 0.25)
			(end 0.499999 -0.249999)
			(stroke
				(width 0.1)
				(type default)
			)
			(layer "F.Fab")
		)
		(pad "1" smd rect
			(at -0.459999 0 90)
			(size 0.508 0.5842)
			(layers "F.Cu" "F.Mask" "F.Paste")
			(net "UNNAMED_6_FERRITE_I27_B")
		)
		(pad "2" smd rect
			(at 0.459999 0 90)
			(size 0.508 0.5842)
			(layers "F.Cu" "F.Mask" "F.Paste")
			(net "P3V3_B2_QSFP")
		)
	)
	(footprint ""
		(layer "F.Cu")
		(at -80.0862 9.2456 180)
		(property "Reference" "R33"
			(at 3.0988 -0.0635 0)
			(unlocked yes)
			(layer "F.SilkS")
			(effects
				(font
					(size 0.762 0.5334)
					(thickness 0.1016)
				)
			)
		)
		(property "Value" ""
			(at 0 0 180)
			(layer "F.Fab")
			(effects
				(font
					(size 1.27 1.27)
				)
			)
		)
		(duplicate_pad_numbers_are_jumpers no)
		(fp_line
			(start 0 -0.381)
			(end 0 0.381)
			(stroke
				(width 0.127)
				(type default)
			)
			(layer "F.SilkS")
		)
		(fp_poly
			(pts
				(xy 1.255601 0.656399) (xy -1.255601 0.656399) (xy -1.255601 -0.6564) (xy 1.255601 -0.6564)
			)
			(stroke
				(width 0)
				(type default)
			)
			(fill no)
			(layer "F.CrtYd")
		)
		(fp_line
			(start 0.800001 0.399999)
			(end 0.800001 -0.399999)
			(stroke
				(width 0.1)
				(type default)
			)
			(layer "F.Fab")
		)
		(fp_line
			(start 0.800001 -0.399999)
			(end -0.800001 -0.399999)
			(stroke
				(width 0.1)
				(type default)
			)
			(layer "F.Fab")
		)
		(fp_line
			(start -0.800001 0.399999)
			(end 0.800001 0.399999)
			(stroke
				(width 0.1)
				(type default)
			)
			(layer "F.Fab")
		)
		(fp_line
			(start -0.800001 -0.399999)
			(end -0.800001 0.399999)
			(stroke
				(width 0.1)
				(type default)
			)
			(layer "F.Fab")
		)
		(pad "1" smd rect
			(at -0.650001 0 180)
			(size 0.7112 0.8128)
			(layers "F.Cu" "F.Mask" "F.Paste")
			(net "SKU_B2_ID1")
		)
		(pad "2" smd rect
			(at 0.650001 0)
			(size 0.7112 0.8128)
			(layers "F.Cu" "F.Mask" "F.Paste")
			(net "GND")
		)
	)
	(footprint ""
		(layer "F.Cu")
		(at -46.393001 11.519002 90)
		(property "Reference" "FB7"
			(at 0.513182 -2.374999 0)
			(unlocked yes)
			(layer "F.SilkS")
			(effects
				(font
					(size 0.762 0.5334)
					(thickness 0.1016)
				)
				(justify left)
			)
		)
		(property "Value" ""
			(at 0 0 90)
			(layer "F.Fab")
			(effects
				(font
					(size 1.27 1.27)
				)
			)
		)
		(duplicate_pad_numbers_are_jumpers no)
		(fp_poly
			(pts
				(xy -1.016 0.508) (xy -1.016 -0.508) (xy 1.016 -0.508) (xy 1.016 0.508)
			)
			(stroke
				(width 0)
				(type default)
			)
			(fill no)
			(layer "F.CrtYd")
		)
		(fp_line
			(start 0.508 -0.254)
			(end 0.508 0.254)
			(stroke
				(width 0.1)
				(type default)
			)
			(layer "F.Fab")
		)
		(fp_line
			(start -0.508 -0.254)
			(end 0.508 -0.254)
			(stroke
				(width 0.1)
				(type default)
			)
			(layer "F.Fab")
		)
		(fp_line
			(start 0.508 0.254)
			(end -0.508 0.254)
			(stroke
				(width 0.1)
				(type default)
			)
			(layer "F.Fab")
		)
		(fp_line
			(start -0.508 0.254)
			(end -0.508 -0.254)
			(stroke
				(width 0.1)
				(type default)
			)
			(layer "F.Fab")
		)
		(pad "1" smd rect
			(at -0.4572 0 180)
			(size 0.508 0.5842)
			(layers "F.Cu" "F.Mask" "F.Paste")
			(net "P3V3_40G_B2_VCC1")
		)
		(pad "2" smd rect
			(at 0.4572 0 180)
			(size 0.508 0.5842)
			(layers "F.Cu" "F.Mask" "F.Paste")
			(net "UNNAMED_8_FERRITE_I47_B")
		)
	)
	(footprint ""
		(layer "F.Cu")
		(at -331.47 20.2438 180)
		(property "Reference" "R7"
			(at -1.9812 0.05842 0)
			(unlocked yes)
			(layer "F.SilkS")
			(effects
				(font
					(size 0.762 0.5334)
					(thickness 0.1016)
				)
			)
		)
		(property "Value" ""
			(at 0 0 180)
			(layer "F.Fab")
			(effects
				(font
					(size 1.27 1.27)
				)
			)
		)
		(duplicate_pad_numbers_are_jumpers no)
		(fp_line
			(start 0 -0.381)
			(end 0 0.381)
			(stroke
				(width 0.127)
				(type default)
			)
			(layer "F.SilkS")
		)
		(fp_poly
			(pts
				(xy 1.255601 0.656399) (xy -1.255601 0.656399) (xy -1.255601 -0.6564) (xy 1.255601 -0.6564)
			)
			(stroke
				(width 0)
				(type default)
			)
			(fill no)
			(layer "F.CrtYd")
		)
		(fp_line
			(start 0.800001 0.399999)
			(end 0.800001 -0.399999)
			(stroke
				(width 0.1)
				(type default)
			)
			(layer "F.Fab")
		)
		(fp_line
			(start 0.800001 -0.399999)
			(end -0.800001 -0.399999)
			(stroke
				(width 0.1)
				(type default)
			)
			(layer "F.Fab")
		)
		(fp_line
			(start -0.800001 0.399999)
			(end 0.800001 0.399999)
			(stroke
				(width 0.1)
				(type default)
			)
			(layer "F.Fab")
		)
		(fp_line
			(start -0.800001 -0.399999)
			(end -0.800001 0.399999)
			(stroke
				(width 0.1)
				(type default)
			)
			(layer "F.Fab")
		)
		(pad "1" smd rect
			(at -0.650001 0 180)
			(size 0.7112 0.8128)
			(layers "F.Cu" "F.Mask" "F.Paste")
			(net "SKU_B1_ID2")
		)
		(pad "2" smd rect
			(at 0.650001 0)
			(size 0.7112 0.8128)
			(layers "F.Cu" "F.Mask" "F.Paste")
			(net "GND")
		)
	)
	(footprint ""
		(layer "F.Cu")
		(at -80.0862 0.381 180)
		(property "Reference" "R57"
			(at 3.07086 -0.03048 0)
			(unlocked yes)
			(layer "F.SilkS")
			(effects
				(font
					(size 0.762 0.5334)
					(thickness 0.1016)
				)
			)
		)
		(property "Value" ""
			(at 0 0 180)
			(layer "F.Fab")
			(effects
				(font
					(size 1.27 1.27)
				)
			)
		)
		(duplicate_pad_numbers_are_jumpers no)
		(fp_line
			(start 0 -0.381)
			(end 0 0.381)
			(stroke
				(width 0.127)
				(type default)
			)
			(layer "F.SilkS")
		)
		(fp_poly
			(pts
				(xy 1.255601 0.6564) (xy -1.255601 0.6564) (xy -1.255601 -0.6564) (xy 1.255601 -0.6564)
			)
			(stroke
				(width 0)
				(type default)
			)
			(fill no)
			(layer "F.CrtYd")
		)
		(fp_line
			(start 0.800001 0.399999)
			(end 0.800001 -0.399999)
			(stroke
				(width 0.1)
				(type default)
			)
			(layer "F.Fab")
		)
		(fp_line
			(start 0.800001 -0.399999)
			(end -0.800001 -0.399999)
			(stroke
				(width 0.1)
				(type default)
			)
			(layer "F.Fab")
		)
		(fp_line
			(start -0.800001 0.399999)
			(end 0.800001 0.399999)
			(stroke
				(width 0.1)
				(type default)
			)
			(layer "F.Fab")
		)
		(fp_line
			(start -0.800001 -0.399999)
			(end -0.800001 0.399999)
			(stroke
				(width 0.1)
				(type default)
			)
			(layer "F.Fab")
		)
		(pad "1" smd rect
			(at -0.650001 0 180)
			(size 0.7112 0.8128)
			(layers "F.Cu" "F.Mask" "F.Paste")
			(net "ETH10G_B2_MOD_ABS")
		)
		(pad "2" smd rect
			(at 0.650001 0)
			(size 0.7112 0.8128)
			(layers "F.Cu" "F.Mask" "F.Paste")
			(net "P3V3_B2_QSFP")
		)
	)
	(footprint ""
		(layer "F.Cu")
		(at -279.610401 44.488202)
		(property "Reference" "C6"
			(at 2.242401 -0.000102 0)
			(unlocked yes)
			(layer "F.SilkS")
			(effects
				(font
					(size 0.762 0.5334)
					(thickness 0.1016)
				)
			)
		)
		(property "Value" ""
			(at 0 0 0)
			(layer "F.Fab")
			(effects
				(font
					(size 1.27 1.27)
				)
			)
		)
		(duplicate_pad_numbers_are_jumpers no)
		(fp_poly
			(pts
				(xy -0.999299 0.503999) (xy -0.999299 -0.504) (xy 0.9993 -0.504) (xy 0.9993 0.503999)
			)
			(stroke
				(width 0)
				(type default)
			)
			(fill no)
			(layer "F.CrtYd")
		)
		(fp_line
			(start -0.499999 -0.25)
			(end 0.499999 -0.25)
			(stroke
				(width 0.1)
				(type default)
			)
			(layer "F.Fab")
		)
		(fp_line
			(start -0.499999 0.249999)
			(end -0.499999 -0.25)
			(stroke
				(width 0.1)
				(type default)
			)
			(layer "F.Fab")
		)
		(fp_line
			(start 0.499999 -0.25)
			(end 0.499999 0.249999)
			(stroke
				(width 0.1)
				(type default)
			)
			(layer "F.Fab")
		)
		(fp_line
			(start 0.499999 0.249999)
			(end -0.499999 0.249999)
			(stroke
				(width 0.1)
				(type default)
			)
			(layer "F.Fab")
		)
		(pad "1" smd rect
			(at -0.4572 0 90)
			(size 0.508 0.5842)
			(layers "F.Cu" "F.Mask" "F.Paste")
			(net "P3V3_10G_B1_VCCT")
		)
		(pad "2" smd rect
			(at 0.4572 0 90)
			(size 0.508 0.5842)
			(layers "F.Cu" "F.Mask" "F.Paste")
			(net "GND")
		)
	)
	(footprint ""
		(layer "F.Cu")
		(at -63.563401 44.488202 180)
		(property "Reference" "C12"
			(at 2.603599 -0.126898 0)
			(unlocked yes)
			(layer "F.SilkS")
			(effects
				(font
					(size 0.762 0.5334)
					(thickness 0.1016)
				)
			)
		)
		(property "Value" ""
			(at 0 0 180)
			(layer "F.Fab")
			(effects
				(font
					(size 1.27 1.27)
				)
			)
		)
		(duplicate_pad_numbers_are_jumpers no)
		(fp_poly
			(pts
				(xy -0.9993 0.504) (xy -0.9993 -0.503999) (xy 0.999299 -0.503999) (xy 0.999299 0.504)
			)
			(stroke
				(width 0)
				(type default)
			)
			(fill no)
			(layer "F.CrtYd")
		)
		(fp_line
			(start 0.499999 0.25)
			(end -0.499999 0.25)
			(stroke
				(width 0.1)
				(type default)
			)
			(layer "F.Fab")
		)
		(fp_line
			(start 0.499999 -0.249999)
			(end 0.499999 0.25)
			(stroke
				(width 0.1)
				(type default)
			)
			(layer "F.Fab")
		)
		(fp_line
			(start -0.499999 0.25)
			(end -0.499999 -0.249999)
			(stroke
				(width 0.1)
				(type default)
			)
			(layer "F.Fab")
		)
		(fp_line
			(start -0.499999 -0.249999)
			(end 0.499999 -0.249999)
			(stroke
				(width 0.1)
				(type default)
			)
			(layer "F.Fab")
		)
		(pad "1" smd rect
			(at -0.4572 0 270)
			(size 0.508 0.5842)
			(layers "F.Cu" "F.Mask" "F.Paste")
			(net "P3V3_10G_B2_VCCR")
		)
		(pad "2" smd rect
			(at 0.4572 0 270)
			(size 0.508 0.5842)
			(layers "F.Cu" "F.Mask" "F.Paste")
			(net "GND")
		)
	)
	(footprint ""
		(layer "F.Cu")
		(at -110.8456 20.2184 180)
		(property "Reference" "R35"
			(at -3.2766 0.1143 0)
			(unlocked yes)
			(layer "F.SilkS")
			(effects
				(font
					(size 0.762 0.5334)
					(thickness 0.1016)
				)
			)
		)
		(property "Value" ""
			(at 0 0 180)
			(layer "F.Fab")
			(effects
				(font
					(size 1.27 1.27)
				)
			)
		)
		(duplicate_pad_numbers_are_jumpers no)
		(fp_line
			(start 0 -0.381)
			(end 0 0.381)
			(stroke
				(width 0.127)
				(type default)
			)
			(layer "F.SilkS")
		)
		(fp_poly
			(pts
				(xy 1.255601 0.656399) (xy -1.255601 0.656399) (xy -1.255601 -0.6564) (xy 1.255601 -0.6564)
			)
			(stroke
				(width 0)
				(type default)
			)
			(fill no)
			(layer "F.CrtYd")
		)
		(fp_line
			(start 0.800001 0.399999)
			(end 0.800001 -0.399999)
			(stroke
				(width 0.1)
				(type default)
			)
			(layer "F.Fab")
		)
		(fp_line
			(start 0.800001 -0.399999)
			(end -0.800001 -0.399999)
			(stroke
				(width 0.1)
				(type default)
			)
			(layer "F.Fab")
		)
		(fp_line
			(start -0.800001 0.399999)
			(end 0.800001 0.399999)
			(stroke
				(width 0.1)
				(type default)
			)
			(layer "F.Fab")
		)
		(fp_line
			(start -0.800001 -0.399999)
			(end -0.800001 0.399999)
			(stroke
				(width 0.1)
				(type default)
			)
			(layer "F.Fab")
		)
		(pad "1" smd rect
			(at -0.650001 0 180)
			(size 0.7112 0.8128)
			(layers "F.Cu" "F.Mask" "F.Paste")
			(net "SKU_B2_ID2")
		)
		(pad "2" smd rect
			(at 0.650001 0)
			(size 0.7112 0.8128)
			(layers "F.Cu" "F.Mask" "F.Paste")
			(net "GND")
		)
	)
	(footprint ""
		(layer "F.Cu")
		(at -300.9392 0 180)
		(property "Reference" "R29"
			(at 3.3782 -0.0381 0)
			(unlocked yes)
			(layer "F.SilkS")
			(effects
				(font
					(size 0.762 0.5334)
					(thickness 0.1016)
				)
			)
		)
		(property "Value" ""
			(at 0 0 180)
			(layer "F.Fab")
			(effects
				(font
					(size 1.27 1.27)
				)
			)
		)
		(duplicate_pad_numbers_are_jumpers no)
		(fp_line
			(start 0 -0.381)
			(end 0 0.381)
			(stroke
				(width 0.127)
				(type default)
			)
			(layer "F.SilkS")
		)
		(fp_poly
			(pts
				(xy 1.255601 0.6564) (xy -1.255601 0.6564) (xy -1.255601 -0.6564) (xy 1.255601 -0.6564)
			)
			(stroke
				(width 0)
				(type default)
			)
			(fill no)
			(layer "F.CrtYd")
		)
		(fp_line
			(start 0.800001 0.399999)
			(end 0.800001 -0.399999)
			(stroke
				(width 0.1)
				(type default)
			)
			(layer "F.Fab")
		)
		(fp_line
			(start 0.800001 -0.399999)
			(end -0.800001 -0.399999)
			(stroke
				(width 0.1)
				(type default)
			)
			(layer "F.Fab")
		)
		(fp_line
			(start -0.800001 0.399999)
			(end 0.800001 0.399999)
			(stroke
				(width 0.1)
				(type default)
			)
			(layer "F.Fab")
		)
		(fp_line
			(start -0.800001 -0.399999)
			(end -0.800001 0.399999)
			(stroke
				(width 0.1)
				(type default)
			)
			(layer "F.Fab")
		)
		(pad "1" smd rect
			(at -0.650001 0 180)
			(size 0.7112 0.8128)
			(layers "F.Cu" "F.Mask" "F.Paste")
			(net "ETH10G_B1_MOD_ABS")
		)
		(pad "2" smd rect
			(at 0.650001 0)
			(size 0.7112 0.8128)
			(layers "F.Cu" "F.Mask" "F.Paste")
			(net "P3V3_B1_QSFP")
		)
	)
	(footprint ""
		(layer "F.Cu")
		(at -240.850001 13.639371 180)
		(property "Reference" "J12"
			(at 8.500001 -13.9151 0)
			(unlocked yes)
			(layer "F.SilkS")
			(effects
				(font
					(size 0.762 0.5334)
					(thickness 0.1016)
				)
			)
		)
		(property "Value" ""
			(at 0 0 180)
			(layer "F.Fab")
			(effects
				(font
					(size 1.27 1.27)
				)
			)
		)
		(duplicate_pad_numbers_are_jumpers no)
		(fp_line
			(start 19.625 24.759999)
			(end 19.625 14.950001)
			(stroke
				(width 0.127)
				(type default)
			)
			(layer "F.SilkS")
		)
		(fp_line
			(start 19.625 1.699999)
			(end 19.625 12.95)
			(stroke
				(width 0.127)
				(type default)
			)
			(layer "F.SilkS")
		)
		(fp_line
			(start 19.625 -13.239999)
			(end 19.625 -0.299999)
			(stroke
				(width 0.127)
				(type default)
			)
			(layer "F.SilkS")
		)
		(fp_line
			(start 17.999999 -13.239999)
			(end 19.625 -13.239999)
			(stroke
				(width 0.127)
				(type default)
			)
			(layer "F.SilkS")
		)
		(fp_line
			(start 0.499999 -13.239999)
			(end -2.625001 -13.239999)
			(stroke
				(width 0.127)
				(type default)
			)
			(layer "F.SilkS")
		)
		(fp_line
			(start -2.625001 24.759999)
			(end 19.625 24.759999)
			(stroke
				(width 0.127)
				(type default)
			)
			(layer "F.SilkS")
		)
		(fp_line
			(start -2.625001 14.950001)
			(end -2.625001 24.759999)
			(stroke
				(width 0.127)
				(type default)
			)
			(layer "F.SilkS")
		)
		(fp_line
			(start -2.625001 12.95)
			(end -2.625001 1.699999)
			(stroke
				(width 0.127)
				(type default)
			)
			(layer "F.SilkS")
		)
		(fp_line
			(start -2.625001 -13.239999)
			(end -2.625001 -0.299999)
			(stroke
				(width 0.127)
				(type default)
			)
			(layer "F.SilkS")
		)
		(fp_poly
			(pts
				(arc
					(start -2.5 19.06)
					(mid -6.070889 17.580889)
					(end -7.55 14.01)
				)
				(arc
					(start -7.55 0.700001)
					(mid -7.480978 -0.132072)
					(end -7.2758 -0.9414)
				)
				(arc
					(start -3.378599 -14.414299)
					(mid -1.57533 -17.115548)
					(end 1.499999 -18.159999)
				)
				(xy 5.9849 -18.159999) (xy 6.014999 -18.159999)
				(arc
					(start 16.984901 -18.159999)
					(mid 20.058046 -17.128812)
					(end 21.871201 -14.4418)
				)
				(xy 22.0277 -13.583699)
				(arc
					(start 24.457401 -0.262699)
					(mid 24.526799 0.216429)
					(end 24.549999 0.700001)
				)
				(arc
					(start 24.549999 14.01)
					(mid 23.070888 17.580889)
					(end 19.499999 19.06)
				)
			)
			(stroke
				(width 0)
				(type default)
			)
			(fill no)
			(layer "B.CrtYd")
		)
		(fp_poly
			(pts
				(xy -3.624999 25.76)
				(arc
					(start -3.624999 15.090699)
					(mid -4.059979 14.01)
					(end -3.624999 12.929301)
				)
				(arc
					(start -3.624999 1.7807)
					(mid -4.05998 0.7)
					(end -3.624999 -0.3807)
				)
				(xy -3.624999 -14.239999)
				(arc
					(start 0.4245 -14.239999)
					(mid 1.499999 -14.669998)
					(end 2.575499 -14.239999)
				)
				(arc
					(start 4.924501 -14.239999)
					(mid 6.000001 -14.669999)
					(end 7.0755 -14.239999)
				)
				(arc
					(start 11.424501 -14.239999)
					(mid 12.5 -14.669998)
					(end 13.5755 -14.239999)
				)
				(arc
					(start 15.924499 -14.239999)
					(mid 17 -14.67)
					(end 18.075501 -14.239999)
				)
				(xy 20.625001 -14.239999)
				(arc
					(start 20.625001 -0.3807)
					(mid 21.05998 0.7)
					(end 20.625001 1.7807)
				)
				(arc
					(start 20.625001 12.929301)
					(mid 21.05998 14.01)
					(end 20.625001 15.090699)
				)
				(xy 20.625001 25.76)
			)
			(stroke
				(width 0)
				(type default)
			)
			(fill no)
			(layer "F.CrtYd")
		)
		(fp_line
			(start 19.625 24.759999)
			(end -2.625001 24.759999)
			(stroke
				(width 0.1)
				(type default)
			)
			(layer "F.Fab")
		)
		(fp_line
			(start 19.625 -13.239999)
			(end 19.625 24.759999)
			(stroke
				(width 0.1)
				(type default)
			)
			(layer "F.Fab")
		)
		(fp_line
			(start -2.625001 24.759999)
			(end -2.625001 -13.239999)
			(stroke
				(width 0.1)
				(type default)
			)
			(layer "F.Fab")
		)
		(fp_line
			(start -2.625001 -13.239999)
			(end 19.625 -13.239999)
			(stroke
				(width 0.1)
				(type default)
			)
			(layer "F.Fab")
		)
		(fp_text user "2A"
			(at 20.769999 1.917271 0)
			(unlocked yes)
			(layer "F.SilkS")
			(effects
				(font
					(size 0.762 0.5334)
					(thickness 0.1016)
				)
			)
		)
		(fp_text user "2C"
			(at 20.388999 -7.734729 0)
			(unlocked yes)
			(layer "F.SilkS")
			(effects
				(font
					(size 0.762 0.5334)
					(thickness 0.1016)
				)
			)
		)
		(fp_text user "2B"
			(at 20.373 -3.169099 0)
			(unlocked yes)
			(layer "F.SilkS")
			(effects
				(font
					(size 0.762 0.5334)
					(thickness 0.1016)
				)
			)
		)
		(fp_text user "2D"
			(at 20.373 -10.6691 0)
			(unlocked yes)
			(layer "F.SilkS")
			(effects
				(font
					(size 0.762 0.5334)
					(thickness 0.1016)
				)
			)
		)
		(fp_text user "*"
			(at -3.487001 -0.159179 0)
			(unlocked yes)
			(layer "F.SilkS")
			(effects
				(font
					(size 0.381 0.381)
					(thickness 0.381)
				)
			)
		)
		(fp_text user "1A"
			(at -3.754001 0.818901 0)
			(unlocked yes)
			(layer "F.SilkS")
			(effects
				(font
					(size 0.762 0.5334)
					(thickness 0.1016)
				)
			)
		)
		(fp_text user "1B"
			(at -3.754001 -3.931099 0)
			(unlocked yes)
			(layer "F.SilkS")
			(effects
				(font
					(size 0.762 0.5334)
					(thickness 0.1016)
				)
			)
		)
		(fp_text user "1C"
			(at -3.754001 -7.681099 0)
			(unlocked yes)
			(layer "F.SilkS")
			(effects
				(font
					(size 0.762 0.5334)
					(thickness 0.1016)
				)
			)
		)
		(fp_text user "1D"
			(at -3.754001 -11.4311 0)
			(unlocked yes)
			(layer "F.SilkS")
			(effects
				(font
					(size 0.762 0.5334)
					(thickness 0.1016)
				)
			)
		)
		(pad "" thru_hole circle
			(at 2.999999 4.399999 180)
			(size 3.81 3.81)
			(drill 2.2098)
			(layers "*.Cu" "*.Mask")
			(remove_unused_layers no)
		)
		(pad "" thru_hole circle
			(at 14 4.399999 180)
			(size 3.81 3.81)
			(drill 2.2098)
			(layers "*.Cu" "*.Mask")
			(remove_unused_layers no)
		)
		(pad "1" thru_hole circle
			(at 1.5 -13.109999 180)
			(size 1.1176 1.1176)
			(drill 0.6096)
			(layers "*.Cu" "*.Mask")
			(remove_unused_layers no)
			(net "GND")
		)
		(pad "1A1" thru_hole circle
			(at 0 0 180)
			(size 0.6858 0.6858)
			(drill 0.381)
			(layers "*.Cu" "*.Mask")
			(remove_unused_layers no)
			(net "Net_409")
		)
		(pad "1A2" thru_hole circle
			(at 0.750001 1.4 180)
			(size 0.6858 0.6858)
			(drill 0.381)
			(layers "*.Cu" "*.Mask")
			(remove_unused_layers no)
			(net "Net_408")
		)
		(pad "1A3" thru_hole circle
			(at 1.5 0.700001 180)
			(size 0.6858 0.6858)
			(drill 0.381)
			(layers "*.Cu" "*.Mask")
			(remove_unused_layers no)
			(net "GND")
		)
		(pad "1A4" thru_hole circle
			(at 2.250001 0 180)
			(size 0.6858 0.6858)
			(drill 0.381)
			(layers "*.Cu" "*.Mask")
			(remove_unused_layers no)
			(net "SAS_B1_RX2P")
		)
		(pad "1A5" thru_hole circle
			(at 2.999999 1.4 180)
			(size 0.6858 0.6858)
			(drill 0.381)
			(layers "*.Cu" "*.Mask")
			(remove_unused_layers no)
			(net "SAS_B1_RX2N")
		)
		(pad "1A6" thru_hole circle
			(at 3.75 0.700001 180)
			(size 0.6858 0.6858)
			(drill 0.381)
			(layers "*.Cu" "*.Mask")
			(remove_unused_layers no)
			(net "GND")
		)
		(pad "1A7" thru_hole circle
			(at 4.500001 0 180)
			(size 0.6858 0.6858)
			(drill 0.381)
			(layers "*.Cu" "*.Mask")
			(remove_unused_layers no)
			(net "SAS_B1_RX4P")
		)
		(pad "1A8" thru_hole circle
			(at 5.25 1.4 180)
			(size 0.6858 0.6858)
			(drill 0.381)
			(layers "*.Cu" "*.Mask")
			(remove_unused_layers no)
			(net "SAS_B1_RX4N")
		)
		(pad "1A9" thru_hole circle
			(at 6.000001 0.700001 180)
			(size 0.6858 0.6858)
			(drill 0.381)
			(layers "*.Cu" "*.Mask")
			(remove_unused_layers no)
			(net "GND")
		)
		(pad "1B1" thru_hole circle
			(at 0 -3.8 180)
			(size 0.6858 0.6858)
			(drill 0.381)
			(layers "*.Cu" "*.Mask")
			(remove_unused_layers no)
			(net "Net_407")
		)
		(pad "1B2" thru_hole circle
			(at 0.750001 -2.4 180)
			(size 0.6858 0.6858)
			(drill 0.381)
			(layers "*.Cu" "*.Mask")
			(remove_unused_layers no)
			(net "Net_406")
		)
		(pad "1B3" thru_hole circle
			(at 1.5 -3.099999 180)
			(size 0.6858 0.6858)
			(drill 0.381)
			(layers "*.Cu" "*.Mask")
			(remove_unused_layers no)
			(net "GND")
		)
		(pad "1B4" thru_hole circle
			(at 2.250001 -3.8 180)
			(size 0.6858 0.6858)
			(drill 0.381)
			(layers "*.Cu" "*.Mask")
			(remove_unused_layers no)
			(net "SAS_B1_RX1P")
		)
		(pad "1B5" thru_hole circle
			(at 2.999999 -2.4 180)
			(size 0.6858 0.6858)
			(drill 0.381)
			(layers "*.Cu" "*.Mask")
			(remove_unused_layers no)
			(net "SAS_B1_RX1N")
		)
		(pad "1B6" thru_hole circle
			(at 3.75 -3.099999 180)
			(size 0.6858 0.6858)
			(drill 0.381)
			(layers "*.Cu" "*.Mask")
			(remove_unused_layers no)
			(net "GND")
		)
		(pad "1B7" thru_hole circle
			(at 4.500001 -3.8 180)
			(size 0.6858 0.6858)
			(drill 0.381)
			(layers "*.Cu" "*.Mask")
			(remove_unused_layers no)
			(net "SAS_B1_RX3P")
		)
		(pad "1B8" thru_hole circle
			(at 5.25 -2.4 180)
			(size 0.6858 0.6858)
			(drill 0.381)
			(layers "*.Cu" "*.Mask")
			(remove_unused_layers no)
			(net "SAS_B1_RX3N")
		)
		(pad "1B9" thru_hole circle
			(at 6.000001 -3.099999 180)
			(size 0.6858 0.6858)
			(drill 0.381)
			(layers "*.Cu" "*.Mask")
			(remove_unused_layers no)
			(net "GND")
		)
		(pad "1C1" thru_hole circle
			(at 0 -7.6 180)
			(size 0.6858 0.6858)
			(drill 0.381)
			(layers "*.Cu" "*.Mask")
			(remove_unused_layers no)
			(net "Net_405")
		)
		(pad "1C2" thru_hole circle
			(at 0.750001 -6.2 180)
			(size 0.6858 0.6858)
			(drill 0.381)
			(layers "*.Cu" "*.Mask")
			(remove_unused_layers no)
			(net "Net_404")
		)
		(pad "1C3" thru_hole circle
			(at 1.5 -6.899999 180)
			(size 0.6858 0.6858)
			(drill 0.381)
			(layers "*.Cu" "*.Mask")
			(remove_unused_layers no)
			(net "GND")
		)
		(pad "1C4" thru_hole circle
			(at 2.250001 -7.6 180)
			(size 0.6858 0.6858)
			(drill 0.381)
			(layers "*.Cu" "*.Mask")
			(remove_unused_layers no)
			(net "SAS_B1_TX2P")
		)
		(pad "1C5" thru_hole circle
			(at 2.999999 -6.2 180)
			(size 0.6858 0.6858)
			(drill 0.381)
			(layers "*.Cu" "*.Mask")
			(remove_unused_layers no)
			(net "SAS_B1_TX2N")
		)
		(pad "1C6" thru_hole circle
			(at 3.75 -6.899999 180)
			(size 0.6858 0.6858)
			(drill 0.381)
			(layers "*.Cu" "*.Mask")
			(remove_unused_layers no)
			(net "GND")
		)
		(pad "1C7" thru_hole circle
			(at 4.500001 -7.6 180)
			(size 0.6858 0.6858)
			(drill 0.381)
			(layers "*.Cu" "*.Mask")
			(remove_unused_layers no)
			(net "SAS_B1_TX4P")
		)
		(pad "1C8" thru_hole circle
			(at 5.25 -6.2 180)
			(size 0.6858 0.6858)
			(drill 0.381)
			(layers "*.Cu" "*.Mask")
			(remove_unused_layers no)
			(net "SAS_B1_TX4N")
		)
		(pad "1C9" thru_hole circle
			(at 6.000001 -6.899999 180)
			(size 0.6858 0.6858)
			(drill 0.381)
			(layers "*.Cu" "*.Mask")
			(remove_unused_layers no)
			(net "GND")
		)
		(pad "1D1" thru_hole circle
			(at 0 -11.4 180)
			(size 0.6858 0.6858)
			(drill 0.381)
			(layers "*.Cu" "*.Mask")
			(remove_unused_layers no)
			(net "Net_403")
		)
		(pad "1D2" thru_hole circle
			(at 0.750001 -10 180)
			(size 0.6858 0.6858)
			(drill 0.381)
			(layers "*.Cu" "*.Mask")
			(remove_unused_layers no)
			(net "Net_402")
		)
		(pad "1D3" thru_hole circle
			(at 1.5 -10.699999 180)
			(size 0.6858 0.6858)
			(drill 0.381)
			(layers "*.Cu" "*.Mask")
			(remove_unused_layers no)
			(net "GND")
		)
		(pad "1D4" thru_hole circle
			(at 2.250001 -11.4 180)
			(size 0.6858 0.6858)
			(drill 0.381)
			(layers "*.Cu" "*.Mask")
			(remove_unused_layers no)
			(net "SAS_B1_TX1P")
		)
		(pad "1D5" thru_hole circle
			(at 2.999999 -10 180)
			(size 0.6858 0.6858)
			(drill 0.381)
			(layers "*.Cu" "*.Mask")
			(remove_unused_layers no)
			(net "SAS_B1_TX1N")
		)
		(pad "1D6" thru_hole circle
			(at 3.75 -10.699999 180)
			(size 0.6858 0.6858)
			(drill 0.381)
			(layers "*.Cu" "*.Mask")
			(remove_unused_layers no)
			(net "GND")
		)
		(pad "1D7" thru_hole circle
			(at 4.500001 -11.4 180)
			(size 0.6858 0.6858)
			(drill 0.381)
			(layers "*.Cu" "*.Mask")
			(remove_unused_layers no)
			(net "SAS_B1_TX3P")
		)
		(pad "1D8" thru_hole circle
			(at 5.25 -10 180)
			(size 0.6858 0.6858)
			(drill 0.381)
			(layers "*.Cu" "*.Mask")
			(remove_unused_layers no)
			(net "SAS_B1_TX3N")
		)
		(pad "1D9" thru_hole circle
			(at 6.000001 -10.699999 180)
			(size 0.6858 0.6858)
			(drill 0.381)
			(layers "*.Cu" "*.Mask")
			(remove_unused_layers no)
			(net "GND")
		)
		(pad "2" thru_hole circle
			(at 6.000001 -13.109999 180)
			(size 1.1176 1.1176)
			(drill 0.6096)
			(layers "*.Cu" "*.Mask")
			(remove_unused_layers no)
			(net "GND")
		)
		(pad "2A1" thru_hole circle
			(at 11.000001 0 180)
			(size 0.6858 0.6858)
			(drill 0.381)
			(layers "*.Cu" "*.Mask")
			(remove_unused_layers no)
			(net "Net_401")
		)
		(pad "2A2" thru_hole circle
			(at 11.749999 1.4 180)
			(size 0.6858 0.6858)
			(drill 0.381)
			(layers "*.Cu" "*.Mask")
			(remove_unused_layers no)
			(net "Net_400")
		)
		(pad "2A3" thru_hole circle
			(at 12.5 0.700001 180)
			(size 0.6858 0.6858)
			(drill 0.381)
			(layers "*.Cu" "*.Mask")
			(remove_unused_layers no)
			(net "GND")
		)
		(pad "2A4" thru_hole circle
			(at 13.249999 0 180)
			(size 0.6858 0.6858)
			(drill 0.381)
			(layers "*.Cu" "*.Mask")
			(remove_unused_layers no)
			(net "SAS_B1_RX6P")
		)
		(pad "2A5" thru_hole circle
			(at 14 1.4 180)
			(size 0.6858 0.6858)
			(drill 0.381)
			(layers "*.Cu" "*.Mask")
			(remove_unused_layers no)
			(net "SAS_B1_RX6N")
		)
		(pad "2A6" thru_hole circle
			(at 14.750001 0.700001 180)
			(size 0.6858 0.6858)
			(drill 0.381)
			(layers "*.Cu" "*.Mask")
			(remove_unused_layers no)
			(net "GND")
		)
		(pad "2A7" thru_hole circle
			(at 15.499999 0 180)
			(size 0.6858 0.6858)
			(drill 0.381)
			(layers "*.Cu" "*.Mask")
			(remove_unused_layers no)
			(net "SAS_B1_RX8P")
		)
		(pad "2A8" thru_hole circle
			(at 16.250001 1.4 180)
			(size 0.6858 0.6858)
			(drill 0.381)
			(layers "*.Cu" "*.Mask")
			(remove_unused_layers no)
			(net "SAS_B1_RX8N")
		)
		(pad "2A9" thru_hole circle
			(at 16.999999 0.700001 180)
			(size 0.6858 0.6858)
			(drill 0.381)
			(layers "*.Cu" "*.Mask")
			(remove_unused_layers no)
			(net "GND")
		)
		(pad "2B1" thru_hole circle
			(at 11.000001 -3.8 180)
			(size 0.6858 0.6858)
			(drill 0.381)
			(layers "*.Cu" "*.Mask")
			(remove_unused_layers no)
			(net "Net_399")
		)
		(pad "2B2" thru_hole circle
			(at 11.749999 -2.4 180)
			(size 0.6858 0.6858)
			(drill 0.381)
			(layers "*.Cu" "*.Mask")
			(remove_unused_layers no)
			(net "Net_398")
		)
		(pad "2B3" thru_hole circle
			(at 12.5 -3.099999 180)
			(size 0.6858 0.6858)
			(drill 0.381)
			(layers "*.Cu" "*.Mask")
			(remove_unused_layers no)
			(net "GND")
		)
		(pad "2B4" thru_hole circle
			(at 13.249999 -3.8 180)
			(size 0.6858 0.6858)
			(drill 0.381)
			(layers "*.Cu" "*.Mask")
			(remove_unused_layers no)
			(net "SAS_B1_RX5P")
		)
		(pad "2B5" thru_hole circle
			(at 14 -2.4 180)
			(size 0.6858 0.6858)
			(drill 0.381)
			(layers "*.Cu" "*.Mask")
			(remove_unused_layers no)
			(net "SAS_B1_RX5N")
		)
		(pad "2B6" thru_hole circle
			(at 14.750001 -3.099999 180)
			(size 0.6858 0.6858)
			(drill 0.381)
			(layers "*.Cu" "*.Mask")
			(remove_unused_layers no)
			(net "GND")
		)
		(pad "2B7" thru_hole circle
			(at 15.499999 -3.8 180)
			(size 0.6858 0.6858)
			(drill 0.381)
			(layers "*.Cu" "*.Mask")
			(remove_unused_layers no)
			(net "SAS_B1_RX7P")
		)
		(pad "2B8" thru_hole circle
			(at 16.250001 -2.4 180)
			(size 0.6858 0.6858)
			(drill 0.381)
			(layers "*.Cu" "*.Mask")
			(remove_unused_layers no)
			(net "SAS_B1_RX7N")
		)
		(pad "2B9" thru_hole circle
			(at 16.999999 -3.099999 180)
			(size 0.6858 0.6858)
			(drill 0.381)
			(layers "*.Cu" "*.Mask")
			(remove_unused_layers no)
			(net "GND")
		)
		(pad "2C1" thru_hole circle
			(at 11.000001 -7.6 180)
			(size 0.6858 0.6858)
			(drill 0.381)
			(layers "*.Cu" "*.Mask")
			(remove_unused_layers no)
			(net "Net_397")
		)
		(pad "2C2" thru_hole circle
			(at 11.749999 -6.2 180)
			(size 0.6858 0.6858)
			(drill 0.381)
			(layers "*.Cu" "*.Mask")
			(remove_unused_layers no)
			(net "Net_396")
		)
		(pad "2C3" thru_hole circle
			(at 12.5 -6.899999 180)
			(size 0.6858 0.6858)
			(drill 0.381)
			(layers "*.Cu" "*.Mask")
			(remove_unused_layers no)
			(net "GND")
		)
		(pad "2C4" thru_hole circle
			(at 13.249999 -7.6 180)
			(size 0.6858 0.6858)
			(drill 0.381)
			(layers "*.Cu" "*.Mask")
			(remove_unused_layers no)
			(net "SAS_B1_TX6P")
		)
		(pad "2C5" thru_hole circle
			(at 14 -6.2 180)
			(size 0.6858 0.6858)
			(drill 0.381)
			(layers "*.Cu" "*.Mask")
			(remove_unused_layers no)
			(net "SAS_B1_TX6N")
		)
		(pad "2C6" thru_hole circle
			(at 14.750001 -6.899999 180)
			(size 0.6858 0.6858)
			(drill 0.381)
			(layers "*.Cu" "*.Mask")
			(remove_unused_layers no)
			(net "GND")
		)
		(pad "2C7" thru_hole circle
			(at 15.499999 -7.6 180)
			(size 0.6858 0.6858)
			(drill 0.381)
			(layers "*.Cu" "*.Mask")
			(remove_unused_layers no)
			(net "SAS_B1_TX8P")
		)
		(pad "2C8" thru_hole circle
			(at 16.250001 -6.2 180)
			(size 0.6858 0.6858)
			(drill 0.381)
			(layers "*.Cu" "*.Mask")
			(remove_unused_layers no)
			(net "SAS_B1_TX8N")
		)
		(pad "2C9" thru_hole circle
			(at 16.999999 -6.899999 180)
			(size 0.6858 0.6858)
			(drill 0.381)
			(layers "*.Cu" "*.Mask")
			(remove_unused_layers no)
			(net "GND")
		)
		(pad "2D1" thru_hole circle
			(at 11.000001 -11.4 180)
			(size 0.6858 0.6858)
			(drill 0.381)
			(layers "*.Cu" "*.Mask")
			(remove_unused_layers no)
			(net "Net_395")
		)
		(pad "2D2" thru_hole circle
			(at 11.749999 -10 180)
			(size 0.6858 0.6858)
			(drill 0.381)
			(layers "*.Cu" "*.Mask")
			(remove_unused_layers no)
			(net "Net_394")
		)
		(pad "2D3" thru_hole circle
			(at 12.5 -10.699999 180)
			(size 0.6858 0.6858)
			(drill 0.381)
			(layers "*.Cu" "*.Mask")
			(remove_unused_layers no)
			(net "GND")
		)
		(pad "2D4" thru_hole circle
			(at 13.249999 -11.4 180)
			(size 0.6858 0.6858)
			(drill 0.381)
			(layers "*.Cu" "*.Mask")
			(remove_unused_layers no)
			(net "SAS_B1_TX5P")
		)
		(pad "2D5" thru_hole circle
			(at 14 -10 180)
			(size 0.6858 0.6858)
			(drill 0.381)
			(layers "*.Cu" "*.Mask")
			(remove_unused_layers no)
			(net "SAS_B1_TX5N")
		)
		(pad "2D6" thru_hole circle
			(at 14.750001 -10.699999 180)
			(size 0.6858 0.6858)
			(drill 0.381)
			(layers "*.Cu" "*.Mask")
			(remove_unused_layers no)
			(net "GND")
		)
		(pad "2D7" thru_hole circle
			(at 15.499999 -11.4 180)
			(size 0.6858 0.6858)
			(drill 0.381)
			(layers "*.Cu" "*.Mask")
			(remove_unused_layers no)
			(net "SAS_B1_TX7P")
		)
		(pad "2D8" thru_hole circle
			(at 16.250001 -10 180)
			(size 0.6858 0.6858)
			(drill 0.381)
			(layers "*.Cu" "*.Mask")
			(remove_unused_layers no)
			(net "SAS_B1_TX7N")
		)
		(pad "2D9" thru_hole circle
			(at 16.999999 -10.699999 180)
			(size 0.6858 0.6858)
			(drill 0.381)
			(layers "*.Cu" "*.Mask")
			(remove_unused_layers no)
			(net "GND")
		)
		(pad "3" thru_hole circle
			(at 12.5 -13.109999 180)
			(size 1.1176 1.1176)
			(drill 0.6096)
			(layers "*.Cu" "*.Mask")
			(remove_unused_layers no)
			(net "GND")
		)
		(pad "4" thru_hole circle
			(at 16.999999 -13.109999 180)
			(size 1.1176 1.1176)
			(drill 0.6096)
			(layers "*.Cu" "*.Mask")
			(remove_unused_layers no)
			(net "GND")
		)
		(pad "5" thru_hole circle
			(at -2.5 0.700001 180)
			(size 1.1176 1.1176)
			(drill 0.6096)
			(layers "*.Cu" "*.Mask")
			(remove_unused_layers no)
			(net "GND")
		)
		(pad "6" thru_hole circle
			(at 8.500001 0.700001 180)
			(size 1.1176 1.1176)
			(drill 0.6096)
			(layers "*.Cu" "*.Mask")
			(remove_unused_layers no)
			(net "GND")
		)
		(pad "7" thru_hole circle
			(at 19.499999 0.700001 180)
			(size 1.1176 1.1176)
			(drill 0.6096)
			(layers "*.Cu" "*.Mask")
			(remove_unused_layers no)
			(net "GND")
		)
		(pad "8" thru_hole circle
			(at -2.5 14.01 180)
			(size 1.1176 1.1176)
			(drill 0.6096)
			(layers "*.Cu" "*.Mask")
			(remove_unused_layers no)
			(net "GND")
		)
		(pad "9" thru_hole circle
			(at 8.500001 14.01 180)
			(size 1.1176 1.1176)
			(drill 0.6096)
			(layers "*.Cu" "*.Mask")
			(remove_unused_layers no)
			(net "GND")
		)
		(pad "10" thru_hole circle
			(at 19.499999 14.01 180)
			(size 1.1176 1.1176)
			(drill 0.6096)
			(layers "*.Cu" "*.Mask")
			(remove_unused_layers no)
			(net "GND")
		)
	)
	(footprint ""
		(layer "F.Cu")
		(at -296.145801 5.524602 180)
		(property "Reference" "R23"
			(at -3.052661 -0.309778 0)
			(unlocked yes)
			(layer "F.SilkS")
			(effects
				(font
					(size 0.762 0.5334)
					(thickness 0.1016)
				)
			)
		)
		(property "Value" ""
			(at 0 0 180)
			(layer "F.Fab")
			(effects
				(font
					(size 1.27 1.27)
				)
			)
		)
		(duplicate_pad_numbers_are_jumpers no)
		(fp_line
			(start 0 -0.381)
			(end 0 0.381)
			(stroke
				(width 0.127)
				(type default)
			)
			(layer "F.SilkS")
		)
		(fp_poly
			(pts
				(xy 1.255601 0.6564) (xy -1.255601 0.6564) (xy -1.255601 -0.656399) (xy 1.255601 -0.656399)
			)
			(stroke
				(width 0)
				(type default)
			)
			(fill no)
			(layer "F.CrtYd")
		)
		(fp_line
			(start 0.800001 0.4)
			(end 0.800001 -0.399999)
			(stroke
				(width 0.1)
				(type default)
			)
			(layer "F.Fab")
		)
		(fp_line
			(start 0.800001 -0.399999)
			(end -0.800001 -0.399999)
			(stroke
				(width 0.1)
				(type default)
			)
			(layer "F.Fab")
		)
		(fp_line
			(start -0.800001 0.4)
			(end 0.800001 0.4)
			(stroke
				(width 0.1)
				(type default)
			)
			(layer "F.Fab")
		)
		(fp_line
			(start -0.800001 -0.399999)
			(end -0.800001 0.4)
			(stroke
				(width 0.1)
				(type default)
			)
			(layer "F.Fab")
		)
		(pad "1" smd rect
			(at -0.650001 0 180)
			(size 0.7112 0.8128)
			(layers "F.Cu" "F.Mask" "F.Paste")
			(net "ETH10G_B1_RS0")
		)
		(pad "2" smd rect
			(at 0.650001 0)
			(size 0.7112 0.8128)
			(layers "F.Cu" "F.Mask" "F.Paste")
			(net "GND")
		)
	)
	(footprint ""
		(layer "F.Cu")
		(at -294.040001 45.360001 180)
		(property "Reference" "J7"
			(at 7.584999 17.000901 0)
			(unlocked yes)
			(layer "F.SilkS")
			(effects
				(font
					(size 0.762 0.5334)
					(thickness 0.1016)
				)
			)
		)
		(property "Value" ""
			(at 0 0 180)
			(layer "F.Fab")
			(effects
				(font
					(size 1.27 1.27)
				)
			)
		)
		(duplicate_pad_numbers_are_jumpers no)
		(fp_line
			(start 10.950001 15.3)
			(end -0.95 15.3)
			(stroke
				(width 0.127)
				(type default)
			)
			(layer "F.SilkS")
		)
		(fp_line
			(start 10.950001 5.609001)
			(end 10.950001 15.3)
			(stroke
				(width 0.127)
				(type default)
			)
			(layer "F.SilkS")
		)
		(fp_line
			(start 10.950001 -11.999999)
			(end 10.950001 4.212001)
			(stroke
				(width 0.127)
				(type default)
			)
			(layer "F.SilkS")
		)
		(fp_line
			(start -0.95 15.3)
			(end -0.95 13.356001)
			(stroke
				(width 0.127)
				(type default)
			)
			(layer "F.SilkS")
		)
		(fp_line
			(start -0.95 11.451001)
			(end -0.95 2.561001)
			(stroke
				(width 0.127)
				(type default)
			)
			(layer "F.SilkS")
		)
		(fp_line
			(start -0.95 0.656001)
			(end -0.95 -11.999999)
			(stroke
				(width 0.127)
				(type default)
			)
			(layer "F.SilkS")
		)
		(fp_line
			(start -0.95 -11.999999)
			(end 10.950001 -11.999999)
			(stroke
				(width 0.127)
				(type default)
			)
			(layer "F.SilkS")
		)
		(fp_poly
			(pts
				(arc
					(start -4.93 12.500001)
					(mid -3.486036 15.986037)
					(end 0 17.430001)
				)
				(arc
					(start 10.000001 17.430001)
					(mid 13.486037 15.986037)
					(end 14.930001 12.500001)
				)
				(arc
					(start 14.930001 -0.1)
					(mid 13.486037 -3.586036)
					(end 10.000001 -5.03)
				)
				(arc
					(start 0 -5.03)
					(mid -3.486036 -3.586036)
					(end -4.93 -0.1)
				)
			)
			(stroke
				(width 0)
				(type default)
			)
			(fill no)
			(layer "B.CrtYd")
		)
		(fp_poly
			(pts
				(xy 11.949999 16.300001) (xy -1.950001 16.300001) (xy -1.950001 -12.999999) (xy 11.949999 -12.999999)
			)
			(stroke
				(width 0)
				(type default)
			)
			(fill no)
			(layer "F.CrtYd")
		)
		(fp_line
			(start 10.950001 15.3)
			(end -0.95 15.3)
			(stroke
				(width 0.1)
				(type default)
			)
			(layer "F.Fab")
		)
		(fp_line
			(start 10.950001 -11.999999)
			(end 10.950001 15.3)
			(stroke
				(width 0.1)
				(type default)
			)
			(layer "F.Fab")
		)
		(fp_line
			(start -0.95 15.3)
			(end -0.95 -11.999999)
			(stroke
				(width 0.1)
				(type default)
			)
			(layer "F.Fab")
		)
		(fp_line
			(start -0.95 -11.999999)
			(end 10.950001 -11.999999)
			(stroke
				(width 0.1)
				(type default)
			)
			(layer "F.Fab")
		)
		(fp_text user "*"
			(at -2.067001 -1.204549 0)
			(unlocked yes)
			(layer "F.SilkS")
			(effects
				(font
					(size 0.381 0.381)
					(thickness 0.381)
				)
			)
		)
		(fp_text user "A1"
			(at -2.321001 0.109901 0)
			(unlocked yes)
			(layer "F.SilkS")
			(effects
				(font
					(size 0.762 0.5334)
					(thickness 0.1016)
				)
			)
		)
		(fp_text user "I6"
			(at 11.423 10.9539 0)
			(unlocked yes)
			(layer "B.SilkS")
			(effects
				(font
					(size 0.762 0.5334)
					(thickness 0.1016)
				)
				(justify mirror)
			)
		)
		(fp_text user "A6"
			(at 11.423 -0.2461 0)
			(unlocked yes)
			(layer "B.SilkS")
			(effects
				(font
					(size 0.762 0.5334)
					(thickness 0.1016)
				)
				(justify mirror)
			)
		)
		(fp_text user "E6"
			(at 11.267999 5.189901 0)
			(unlocked yes)
			(layer "B.SilkS")
			(effects
				(font
					(size 0.762 0.5334)
					(thickness 0.1016)
				)
				(justify mirror)
			)
		)
		(fp_text user "I1"
			(at -1.289761 11.273201 0)
			(unlocked yes)
			(layer "B.SilkS")
			(effects
				(font
					(size 0.762 0.5334)
					(thickness 0.1016)
				)
				(justify mirror)
			)
		)
		(fp_text user "E1"
			(at -1.289761 5.923961 0)
			(unlocked yes)
			(layer "B.SilkS")
			(effects
				(font
					(size 0.762 0.5334)
					(thickness 0.1016)
				)
				(justify mirror)
			)
		)
		(fp_text user "A1"
			(at -1.295999 -0.1191 0)
			(unlocked yes)
			(layer "B.SilkS")
			(effects
				(font
					(size 0.762 0.5334)
					(thickness 0.1016)
				)
				(justify mirror)
			)
		)
		(pad "A1" thru_hole circle
			(at 0 0 180)
			(size 0.8128 0.8128)
			(drill 0.508)
			(layers "*.Cu" "*.Mask")
			(remove_unused_layers no)
			(net "ETH40G_B1_TX3P")
		)
		(pad "A2" thru_hole circle
			(at 2.000001 -0.1 180)
			(size 0.8128 0.8128)
			(drill 0.508)
			(layers "*.Cu" "*.Mask")
			(remove_unused_layers no)
			(net "GND")
		)
		(pad "A3" thru_hole circle
			(at 4 0 180)
			(size 0.8128 0.8128)
			(drill 0.508)
			(layers "*.Cu" "*.Mask")
			(remove_unused_layers no)
			(net "ETH40G_B1_RX2P")
		)
		(pad "A4" thru_hole circle
			(at 6.000001 -0.1 180)
			(size 0.8128 0.8128)
			(drill 0.508)
			(layers "*.Cu" "*.Mask")
			(remove_unused_layers no)
			(net "GND")
		)
		(pad "A5" thru_hole circle
			(at 7.999999 0 180)
			(size 0.8128 0.8128)
			(drill 0.508)
			(layers "*.Cu" "*.Mask")
			(remove_unused_layers no)
			(net "ETH40G_B1_RX1P")
		)
		(pad "A6" thru_hole circle
			(at 10 -0.1 180)
			(size 0.8128 0.8128)
			(drill 0.508)
			(layers "*.Cu" "*.Mask")
			(remove_unused_layers no)
			(net "GND")
		)
		(pad "B1" thru_hole circle
			(at 0 1.4 180)
			(size 0.8128 0.8128)
			(drill 0.508)
			(layers "*.Cu" "*.Mask")
			(remove_unused_layers no)
			(net "ETH40G_B1_TX3N")
		)
		(pad "B2" thru_hole circle
			(at 2.000001 1.3 180)
			(size 0.8128 0.8128)
			(drill 0.508)
			(layers "*.Cu" "*.Mask")
			(remove_unused_layers no)
			(net "ETH40G_B1_RX3P")
		)
		(pad "B3" thru_hole circle
			(at 4 1.4 180)
			(size 0.8128 0.8128)
			(drill 0.508)
			(layers "*.Cu" "*.Mask")
			(remove_unused_layers no)
			(net "ETH40G_B1_RX2N")
		)
		(pad "B4" thru_hole circle
			(at 6.000001 1.3 180)
			(size 0.8128 0.8128)
			(drill 0.508)
			(layers "*.Cu" "*.Mask")
			(remove_unused_layers no)
			(net "ETH40G_B1_TX2P")
		)
		(pad "B5" thru_hole circle
			(at 7.999999 1.4 180)
			(size 0.8128 0.8128)
			(drill 0.508)
			(layers "*.Cu" "*.Mask")
			(remove_unused_layers no)
			(net "ETH40G_B1_RX1N")
		)
		(pad "B6" thru_hole circle
			(at 10 1.3 180)
			(size 0.8128 0.8128)
			(drill 0.508)
			(layers "*.Cu" "*.Mask")
			(remove_unused_layers no)
			(net "ETH40G_B1_TX1P")
		)
		(pad "C1" thru_hole circle
			(at 0 2.799999 180)
			(size 0.8128 0.8128)
			(drill 0.508)
			(layers "*.Cu" "*.Mask")
			(remove_unused_layers no)
			(net "GND")
		)
		(pad "C2" thru_hole circle
			(at 2.000001 2.7 180)
			(size 0.8128 0.8128)
			(drill 0.508)
			(layers "*.Cu" "*.Mask")
			(remove_unused_layers no)
			(net "ETH40G_B1_RX3N")
		)
		(pad "C3" thru_hole circle
			(at 4 2.799999 180)
			(size 0.8128 0.8128)
			(drill 0.508)
			(layers "*.Cu" "*.Mask")
			(remove_unused_layers no)
			(net "GND")
		)
		(pad "C4" thru_hole circle
			(at 6.000001 2.7 180)
			(size 0.8128 0.8128)
			(drill 0.508)
			(layers "*.Cu" "*.Mask")
			(remove_unused_layers no)
			(net "ETH40G_B1_TX2N")
		)
		(pad "C5" thru_hole circle
			(at 7.999999 2.799999 180)
			(size 0.8128 0.8128)
			(drill 0.508)
			(layers "*.Cu" "*.Mask")
			(remove_unused_layers no)
			(net "GND")
		)
		(pad "C6" thru_hole circle
			(at 10 2.7 180)
			(size 0.8128 0.8128)
			(drill 0.508)
			(layers "*.Cu" "*.Mask")
			(remove_unused_layers no)
			(net "ETH40G_B1_TX1N")
		)
		(pad "D1" thru_hole circle
			(at 0 4.199999 180)
			(size 0.8128 0.8128)
			(drill 0.508)
			(layers "*.Cu" "*.Mask")
			(remove_unused_layers no)
			(net "ETH10G_B1_RXP")
		)
		(pad "D2" thru_hole circle
			(at 2.000001 4.099999 180)
			(size 0.8128 0.8128)
			(drill 0.508)
			(layers "*.Cu" "*.Mask")
			(remove_unused_layers no)
			(net "GND")
		)
		(pad "D3" thru_hole circle
			(at 4 4.199999 180)
			(size 0.8128 0.8128)
			(drill 0.508)
			(layers "*.Cu" "*.Mask")
			(remove_unused_layers no)
			(net "ETH10G_B1_SDA")
		)
		(pad "D4" thru_hole circle
			(at 6.000001 4.099999 180)
			(size 0.8128 0.8128)
			(drill 0.508)
			(layers "*.Cu" "*.Mask")
			(remove_unused_layers no)
			(net "GND")
		)
		(pad "D5" thru_hole circle
			(at 7.999999 4.199999 180)
			(size 0.8128 0.8128)
			(drill 0.508)
			(layers "*.Cu" "*.Mask")
			(remove_unused_layers no)
			(net "P3V3_B1_QSFP")
		)
		(pad "D6" thru_hole circle
			(at 10 4.099999 180)
			(size 0.8128 0.8128)
			(drill 0.508)
			(layers "*.Cu" "*.Mask")
			(remove_unused_layers no)
			(net "GND")
		)
		(pad "E1" thru_hole circle
			(at 0 5.599999 180)
			(size 0.8128 0.8128)
			(drill 0.508)
			(layers "*.Cu" "*.Mask")
			(remove_unused_layers no)
			(net "ETH10G_B1_RXN")
		)
		(pad "E2" thru_hole circle
			(at 2.000001 5.499999 180)
			(size 0.8128 0.8128)
			(drill 0.508)
			(layers "*.Cu" "*.Mask")
			(remove_unused_layers no)
			(net "Net_15")
		)
		(pad "E3" thru_hole circle
			(at 4 5.599999 180)
			(size 0.8128 0.8128)
			(drill 0.508)
			(layers "*.Cu" "*.Mask")
			(remove_unused_layers no)
			(net "ETH10G_B1_SCL")
		)
		(pad "E4" thru_hole circle
			(at 6.000001 5.499999 180)
			(size 0.8128 0.8128)
			(drill 0.508)
			(layers "*.Cu" "*.Mask")
			(remove_unused_layers no)
			(net "ETH40G_B1_SDA")
		)
		(pad "E5" thru_hole circle
			(at 7.999999 5.599999 180)
			(size 0.8128 0.8128)
			(drill 0.508)
			(layers "*.Cu" "*.Mask")
			(remove_unused_layers no)
			(net "P3V3_B1_QSFP")
		)
		(pad "E6" thru_hole circle
			(at 10 5.499999 180)
			(size 0.8128 0.8128)
			(drill 0.508)
			(layers "*.Cu" "*.Mask")
			(remove_unused_layers no)
			(net "ETH40G_B1_RX0P")
		)
		(pad "F1" thru_hole circle
			(at 0 7.000001 180)
			(size 0.8128 0.8128)
			(drill 0.508)
			(layers "*.Cu" "*.Mask")
			(remove_unused_layers no)
			(net "GND")
		)
		(pad "F2" thru_hole circle
			(at 2.000001 6.899999 180)
			(size 0.8128 0.8128)
			(drill 0.508)
			(layers "*.Cu" "*.Mask")
			(remove_unused_layers no)
			(net "SKU_B1_ID2")
		)
		(pad "F3" thru_hole circle
			(at 4 7.000001 180)
			(size 0.8128 0.8128)
			(drill 0.508)
			(layers "*.Cu" "*.Mask")
			(remove_unused_layers no)
			(net "SKU_B1_ID0")
		)
		(pad "F4" thru_hole circle
			(at 6.000001 6.899999 180)
			(size 0.8128 0.8128)
			(drill 0.508)
			(layers "*.Cu" "*.Mask")
			(remove_unused_layers no)
			(net "ETH40G_B1_SCL")
		)
		(pad "F5" thru_hole circle
			(at 7.999999 7.000001 180)
			(size 0.8128 0.8128)
			(drill 0.508)
			(layers "*.Cu" "*.Mask")
			(remove_unused_layers no)
			(net "GND")
		)
		(pad "F6" thru_hole circle
			(at 10 6.899999 180)
			(size 0.8128 0.8128)
			(drill 0.508)
			(layers "*.Cu" "*.Mask")
			(remove_unused_layers no)
			(net "ETH40G_B1_RX0N")
		)
		(pad "G1" thru_hole circle
			(at 0 8.400001 180)
			(size 0.8128 0.8128)
			(drill 0.508)
			(layers "*.Cu" "*.Mask")
			(remove_unused_layers no)
			(net "ETH10G_B1_TXP")
		)
		(pad "G2" thru_hole circle
			(at 2.000001 8.300001 180)
			(size 0.8128 0.8128)
			(drill 0.508)
			(layers "*.Cu" "*.Mask")
			(remove_unused_layers no)
			(net "GND")
		)
		(pad "G3" thru_hole circle
			(at 4 8.400001 180)
			(size 0.8128 0.8128)
			(drill 0.508)
			(layers "*.Cu" "*.Mask")
			(remove_unused_layers no)
			(net "SERIAL_B1_RX1")
		)
		(pad "G4" thru_hole circle
			(at 6.000001 8.300001 180)
			(size 0.8128 0.8128)
			(drill 0.508)
			(layers "*.Cu" "*.Mask")
			(remove_unused_layers no)
			(net "SERIAL_B1_RX2")
		)
		(pad "G5" thru_hole circle
			(at 7.999999 8.400001 180)
			(size 0.8128 0.8128)
			(drill 0.508)
			(layers "*.Cu" "*.Mask")
			(remove_unused_layers no)
			(net "PSU_B1_ALERT_N")
		)
		(pad "G6" thru_hole circle
			(at 10 8.300001 180)
			(size 0.8128 0.8128)
			(drill 0.508)
			(layers "*.Cu" "*.Mask")
			(remove_unused_layers no)
			(net "GND")
		)
		(pad "H1" thru_hole circle
			(at 0 9.800001 180)
			(size 0.8128 0.8128)
			(drill 0.508)
			(layers "*.Cu" "*.Mask")
			(remove_unused_layers no)
			(net "ETH10G_B1_TXN")
		)
		(pad "H2" thru_hole circle
			(at 2.000001 9.700001 180)
			(size 0.8128 0.8128)
			(drill 0.508)
			(layers "*.Cu" "*.Mask")
			(remove_unused_layers no)
			(net "BLADE_B1_EN1")
		)
		(pad "H3" thru_hole circle
			(at 4 9.800001 180)
			(size 0.8128 0.8128)
			(drill 0.508)
			(layers "*.Cu" "*.Mask")
			(remove_unused_layers no)
			(net "SERIAL_B1_TX1")
		)
		(pad "H4" thru_hole circle
			(at 6.000001 9.700001 180)
			(size 0.8128 0.8128)
			(drill 0.508)
			(layers "*.Cu" "*.Mask")
			(remove_unused_layers no)
			(net "SERIAL_B1_TX2")
		)
		(pad "H5" thru_hole circle
			(at 7.999999 9.800001 180)
			(size 0.8128 0.8128)
			(drill 0.508)
			(layers "*.Cu" "*.Mask")
			(remove_unused_layers no)
			(net "ETH40G_B1_PRES_N")
		)
		(pad "H6" thru_hole circle
			(at 10 9.700001 180)
			(size 0.8128 0.8128)
			(drill 0.508)
			(layers "*.Cu" "*.Mask")
			(remove_unused_layers no)
			(net "ETH40G_B1_TX0P")
		)
		(pad "I1" thru_hole circle
			(at 0 11.2 180)
			(size 0.8128 0.8128)
			(drill 0.508)
			(layers "*.Cu" "*.Mask")
			(remove_unused_layers no)
			(net "GND")
		)
		(pad "I2" thru_hole circle
			(at 2.000001 11.100001 180)
			(size 0.8128 0.8128)
			(drill 0.508)
			(layers "*.Cu" "*.Mask")
			(remove_unused_layers no)
			(net "ETH10G_B1_PRES_N")
		)
		(pad "I3" thru_hole circle
			(at 4 11.2 180)
			(size 0.8128 0.8128)
			(drill 0.508)
			(layers "*.Cu" "*.Mask")
			(remove_unused_layers no)
			(net "P3V3_B1_QSFP")
		)
		(pad "I4" thru_hole circle
			(at 6.000001 11.100001 180)
			(size 0.8128 0.8128)
			(drill 0.508)
			(layers "*.Cu" "*.Mask")
			(remove_unused_layers no)
			(net "SKU_B1_ID1")
		)
		(pad "I5" thru_hole circle
			(at 7.999999 11.2 180)
			(size 0.8128 0.8128)
			(drill 0.508)
			(layers "*.Cu" "*.Mask")
			(remove_unused_layers no)
			(net "BLADE_B1_MATED_N<1>")
		)
		(pad "I6" thru_hole circle
			(at 10 11.100001 180)
			(size 0.8128 0.8128)
			(drill 0.508)
			(layers "*.Cu" "*.Mask")
			(remove_unused_layers no)
			(net "ETH40G_B1_TX0N")
		)
		(pad "J2" thru_hole circle
			(at 2.000001 12.5 180)
			(size 0.8128 0.8128)
			(drill 0.508)
			(layers "*.Cu" "*.Mask")
			(remove_unused_layers no)
			(net "GND")
		)
		(pad "J4" thru_hole circle
			(at 6.000001 12.5 180)
			(size 0.8128 0.8128)
			(drill 0.508)
			(layers "*.Cu" "*.Mask")
			(remove_unused_layers no)
			(net "GND")
		)
		(pad "J6" thru_hole circle
			(at 10 12.5 180)
			(size 0.8128 0.8128)
			(drill 0.508)
			(layers "*.Cu" "*.Mask")
			(remove_unused_layers no)
			(net "GND")
		)
	)
	(footprint ""
		(layer "F.Cu")
		(at -44.958 1.143 180)
		(property "Reference" "FB6"
			(at -2.032 -0.1651 0)
			(unlocked yes)
			(layer "F.SilkS")
			(effects
				(font
					(size 0.762 0.5334)
					(thickness 0.1016)
				)
				(justify left)
			)
		)
		(property "Value" ""
			(at 0 0 180)
			(layer "F.Fab")
			(effects
				(font
					(size 1.27 1.27)
				)
			)
		)
		(duplicate_pad_numbers_are_jumpers no)
		(fp_poly
			(pts
				(xy -1.016 0.508) (xy -1.016 -0.508) (xy 1.016 -0.508) (xy 1.016 0.508)
			)
			(stroke
				(width 0)
				(type default)
			)
			(fill no)
			(layer "F.CrtYd")
		)
		(fp_line
			(start 0.508 0.254)
			(end -0.508 0.254)
			(stroke
				(width 0.1)
				(type default)
			)
			(layer "F.Fab")
		)
		(fp_line
			(start 0.508 -0.254)
			(end 0.508 0.254)
			(stroke
				(width 0.1)
				(type default)
			)
			(layer "F.Fab")
		)
		(fp_line
			(start -0.508 0.254)
			(end -0.508 -0.254)
			(stroke
				(width 0.1)
				(type default)
			)
			(layer "F.Fab")
		)
		(fp_line
			(start -0.508 -0.254)
			(end 0.508 -0.254)
			(stroke
				(width 0.1)
				(type default)
			)
			(layer "F.Fab")
		)
		(pad "1" smd rect
			(at -0.4572 0 270)
			(size 0.508 0.5842)
			(layers "F.Cu" "F.Mask" "F.Paste")
			(net "UNNAMED_8_FERRITE_I54_A")
		)
		(pad "2" smd rect
			(at 0.4572 0 270)
			(size 0.508 0.5842)
			(layers "F.Cu" "F.Mask" "F.Paste")
			(net "P3V3_40G_B2_VCC_RX")
		)
	)
	(footprint ""
		(layer "F.Cu")
		(at -284.563401 44.488202 180)
		(property "Reference" "C8"
			(at 2.126399 0.025502 0)
			(unlocked yes)
			(layer "F.SilkS")
			(effects
				(font
					(size 0.762 0.5334)
					(thickness 0.1016)
				)
			)
		)
		(property "Value" ""
			(at 0 0 180)
			(layer "F.Fab")
			(effects
				(font
					(size 1.27 1.27)
				)
			)
		)
		(duplicate_pad_numbers_are_jumpers no)
		(fp_poly
			(pts
				(xy -0.9993 0.504) (xy -0.9993 -0.503999) (xy 0.999299 -0.503999) (xy 0.999299 0.504)
			)
			(stroke
				(width 0)
				(type default)
			)
			(fill no)
			(layer "F.CrtYd")
		)
		(fp_line
			(start 0.499999 0.25)
			(end -0.499999 0.25)
			(stroke
				(width 0.1)
				(type default)
			)
			(layer "F.Fab")
		)
		(fp_line
			(start 0.499999 -0.249999)
			(end 0.499999 0.25)
			(stroke
				(width 0.1)
				(type default)
			)
			(layer "F.Fab")
		)
		(fp_line
			(start -0.499999 0.25)
			(end -0.499999 -0.249999)
			(stroke
				(width 0.1)
				(type default)
			)
			(layer "F.Fab")
		)
		(fp_line
			(start -0.499999 -0.249999)
			(end 0.499999 -0.249999)
			(stroke
				(width 0.1)
				(type default)
			)
			(layer "F.Fab")
		)
		(pad "1" smd rect
			(at -0.4572 0 270)
			(size 0.508 0.5842)
			(layers "F.Cu" "F.Mask" "F.Paste")
			(net "P3V3_10G_B1_VCCR")
		)
		(pad "2" smd rect
			(at 0.4572 0 270)
			(size 0.508 0.5842)
			(layers "F.Cu" "F.Mask" "F.Paste")
			(net "GND")
		)
	)
	(footprint ""
		(layer "F.Cu")
		(at -296.145801 6.845402)
		(property "Reference" "R22"
			(at 3.052661 0.258978 0)
			(unlocked yes)
			(layer "F.SilkS")
			(effects
				(font
					(size 0.762 0.5334)
					(thickness 0.1016)
				)
			)
		)
		(property "Value" ""
			(at 0 0 0)
			(layer "F.Fab")
			(effects
				(font
					(size 1.27 1.27)
				)
			)
		)
		(duplicate_pad_numbers_are_jumpers no)
		(fp_line
			(start 0 -0.381)
			(end 0 0.381)
			(stroke
				(width 0.127)
				(type default)
			)
			(layer "F.SilkS")
		)
		(fp_poly
			(pts
				(xy 1.255601 0.656399) (xy -1.255601 0.656399) (xy -1.255601 -0.6564) (xy 1.255601 -0.6564)
			)
			(stroke
				(width 0)
				(type default)
			)
			(fill no)
			(layer "F.CrtYd")
		)
		(fp_line
			(start -0.800001 -0.4)
			(end -0.800001 0.399999)
			(stroke
				(width 0.1)
				(type default)
			)
			(layer "F.Fab")
		)
		(fp_line
			(start -0.800001 0.399999)
			(end 0.800001 0.399999)
			(stroke
				(width 0.1)
				(type default)
			)
			(layer "F.Fab")
		)
		(fp_line
			(start 0.800001 -0.4)
			(end -0.800001 -0.4)
			(stroke
				(width 0.1)
				(type default)
			)
			(layer "F.Fab")
		)
		(fp_line
			(start 0.800001 0.399999)
			(end 0.800001 -0.4)
			(stroke
				(width 0.1)
				(type default)
			)
			(layer "F.Fab")
		)
		(pad "1" smd rect
			(at -0.650001 0)
			(size 0.7112 0.8128)
			(layers "F.Cu" "F.Mask" "F.Paste")
			(net "P3V3_B1_QSFP")
		)
		(pad "2" smd rect
			(at 0.650001 0 180)
			(size 0.7112 0.8128)
			(layers "F.Cu" "F.Mask" "F.Paste")
			(net "ETH10G_B1_RS0")
		)
	)
	(footprint ""
		(layer "F.Cu")
		(at -61.750001 32.059999 180)
		(property "Reference" "J17"
			(at 7.231319 -7.183001 0)
			(unlocked yes)
			(layer "F.SilkS")
			(effects
				(font
					(size 0.762 0.5334)
					(thickness 0.1016)
				)
			)
		)
		(property "Value" ""
			(at 0 0 180)
			(layer "F.Fab")
			(effects
				(font
					(size 1.27 1.27)
				)
			)
		)
		(duplicate_pad_numbers_are_jumpers no)
		(fp_line
			(start 5.499999 3.85)
			(end 4.500001 3.85)
			(stroke
				(width 0.127)
				(type default)
			)
			(layer "F.SilkS")
		)
		(fp_line
			(start 5.499999 1.499999)
			(end 5.499999 3.85)
			(stroke
				(width 0.127)
				(type default)
			)
			(layer "F.SilkS")
		)
		(fp_line
			(start 5.499999 -1.5)
			(end 5.499999 -3.85)
			(stroke
				(width 0.127)
				(type default)
			)
			(layer "F.SilkS")
		)
		(fp_line
			(start 5.499999 -3.85)
			(end 4 -3.85)
			(stroke
				(width 0.127)
				(type default)
			)
			(layer "F.SilkS")
		)
		(fp_line
			(start -4 3.85)
			(end -5.499999 3.85)
			(stroke
				(width 0.127)
				(type default)
			)
			(layer "F.SilkS")
		)
		(fp_line
			(start -5.499999 3.85)
			(end -5.499999 1.499999)
			(stroke
				(width 0.127)
				(type default)
			)
			(layer "F.SilkS")
		)
		(fp_line
			(start -5.499999 -1.5)
			(end -5.499999 -2.85)
			(stroke
				(width 0.127)
				(type default)
			)
			(layer "F.SilkS")
		)
		(fp_line
			(start -5.499999 -2.85)
			(end -4.500001 -3.85)
			(stroke
				(width 0.127)
				(type default)
			)
			(layer "F.SilkS")
		)
		(fp_poly
			(pts
				(xy -4.154 5.603301) (xy -4.154 4.349999) (xy -6.000001 4.349999) (xy -6.000001 -4.349999) (xy -4.553999 -4.349999)
				(xy -4.553999 -5.603301) (xy 4.154 -5.603301) (xy 4.154 -4.349999) (xy 6.000001 -4.349999) (xy 6.000001 4.349999)
				(xy 4.553999 4.349999) (xy 4.553999 5.603301)
			)
			(stroke
				(width 0)
				(type default)
			)
			(fill no)
			(layer "F.CrtYd")
		)
		(fp_line
			(start 5.499999 3.85)
			(end -5.499999 3.85)
			(stroke
				(width 0.1)
				(type default)
			)
			(layer "F.Fab")
		)
		(fp_line
			(start 5.499999 -3.85)
			(end 5.499999 3.85)
			(stroke
				(width 0.1)
				(type default)
			)
			(layer "F.Fab")
		)
		(fp_line
			(start -4.500001 -3.85)
			(end 5.499999 -3.85)
			(stroke
				(width 0.1)
				(type default)
			)
			(layer "F.Fab")
		)
		(fp_line
			(start -5.499999 3.85)
			(end -5.499999 -2.85)
			(stroke
				(width 0.1)
				(type default)
			)
			(layer "F.Fab")
		)
		(fp_line
			(start -5.499999 -2.85)
			(end -4.500001 -3.85)
			(stroke
				(width 0.1)
				(type default)
			)
			(layer "F.Fab")
		)
		(fp_text user "10"
			(at 4.968179 4.625459 0)
			(unlocked yes)
			(layer "F.SilkS")
			(effects
				(font
					(size 0.762 0.5334)
					(thickness 0.1016)
				)
			)
		)
		(fp_text user "11"
			(at 4.871659 -4.589661 0)
			(unlocked yes)
			(layer "F.SilkS")
			(effects
				(font
					(size 0.762 0.5334)
					(thickness 0.1016)
				)
			)
		)
		(fp_text user "*"
			(at -4.600001 4.571448 0)
			(unlocked yes)
			(layer "F.SilkS")
			(effects
				(font
					(size 0.381 0.381)
					(thickness 0.381)
				)
			)
		)
		(fp_text user "20"
			(at -4.935281 -4.541401 0)
			(unlocked yes)
			(layer "F.SilkS")
			(effects
				(font
					(size 0.762 0.5334)
					(thickness 0.1016)
				)
			)
		)
		(pad "" np_thru_hole circle
			(at -4.800001 0 180)
			(size 1.27 1.27)
			(drill 1.6002)
			(layers "*.Cu" "*.Mask")
		)
		(pad "" np_thru_hole circle
			(at 4.800001 0 180)
			(size 1.27 1.27)
			(drill 1.6002)
			(layers "*.Cu" "*.Mask")
		)
		(pad "1" smd oval
			(at -3.400001 4.099999 180)
			(size 0.508 2.0066)
			(layers "F.Cu" "F.Mask" "F.Paste")
			(net "GND")
		)
		(pad "2" smd oval
			(at -2.6 4.099999 180)
			(size 0.508 2.0066)
			(layers "F.Cu" "F.Mask" "F.Paste")
			(net "ETH10G_B2_TX_FAULT")
		)
		(pad "3" smd oval
			(at -1.799999 4.099999 180)
			(size 0.508 2.0066)
			(layers "F.Cu" "F.Mask" "F.Paste")
			(net "ETH10G_B2_TX_DIS")
		)
		(pad "4" smd oval
			(at -1.000001 4.099999 180)
			(size 0.508 2.0066)
			(layers "F.Cu" "F.Mask" "F.Paste")
			(net "ETH10G_B2_SDA")
		)
		(pad "5" smd oval
			(at -0.2 4.099999 180)
			(size 0.508 2.0066)
			(layers "F.Cu" "F.Mask" "F.Paste")
			(net "ETH10G_B2_SCL")
		)
		(pad "6" smd oval
			(at 0.599999 4.099999 180)
			(size 0.508 2.0066)
			(layers "F.Cu" "F.Mask" "F.Paste")
			(net "ETH10G_B2_MOD_ABS")
		)
		(pad "7" smd oval
			(at 1.4 4.099999 180)
			(size 0.508 2.0066)
			(layers "F.Cu" "F.Mask" "F.Paste")
			(net "ETH10G_B2_RS0")
		)
		(pad "8" smd oval
			(at 2.200001 4.099999 180)
			(size 0.508 2.0066)
			(layers "F.Cu" "F.Mask" "F.Paste")
			(net "ETH10G_B2_RX_LOS")
		)
		(pad "9" smd oval
			(at 2.999999 4.099999 180)
			(size 0.508 2.0066)
			(layers "F.Cu" "F.Mask" "F.Paste")
			(net "ETH10G_B2_RS1")
		)
		(pad "10" smd oval
			(at 3.8 4.099999 180)
			(size 0.508 2.0066)
			(layers "F.Cu" "F.Mask" "F.Paste")
			(net "GND")
		)
		(pad "11" smd oval
			(at 3.400001 -4.099999 180)
			(size 0.508 2.0066)
			(layers "F.Cu" "F.Mask" "F.Paste")
			(net "GND")
		)
		(pad "12" smd oval
			(at 2.6 -4.099999 180)
			(size 0.508 2.0066)
			(layers "F.Cu" "F.Mask" "F.Paste")
			(net "ETH10G_B2_RXN")
		)
		(pad "13" smd oval
			(at 1.799999 -4.099999 180)
			(size 0.508 2.0066)
			(layers "F.Cu" "F.Mask" "F.Paste")
			(net "ETH10G_B2_RXP")
		)
		(pad "14" smd oval
			(at 1.000001 -4.099999 180)
			(size 0.508 2.0066)
			(layers "F.Cu" "F.Mask" "F.Paste")
			(net "GND")
		)
		(pad "15" smd oval
			(at 0.2 -4.099999 180)
			(size 0.508 2.0066)
			(layers "F.Cu" "F.Mask" "F.Paste")
			(net "P3V3_10G_B2_VCCR")
		)
		(pad "16" smd oval
			(at -0.599999 -4.099999 180)
			(size 0.508 2.0066)
			(layers "F.Cu" "F.Mask" "F.Paste")
			(net "P3V3_10G_B2_VCCT")
		)
		(pad "17" smd oval
			(at -1.4 -4.099999 180)
			(size 0.508 2.0066)
			(layers "F.Cu" "F.Mask" "F.Paste")
			(net "GND")
		)
		(pad "18" smd oval
			(at -2.200001 -4.099999 180)
			(size 0.508 2.0066)
			(layers "F.Cu" "F.Mask" "F.Paste")
			(net "ETH10G_B2_TXP")
		)
		(pad "19" smd oval
			(at -2.999999 -4.099999 180)
			(size 0.508 2.0066)
			(layers "F.Cu" "F.Mask" "F.Paste")
			(net "ETH10G_B2_TXN")
		)
		(pad "20" smd oval
			(at -3.8 -4.099999 180)
			(size 0.508 2.0066)
			(layers "F.Cu" "F.Mask" "F.Paste")
			(net "GND")
		)
		(zone
			(layers "F.Cu" "B.Cu" "In1.Cu" "In2.Cu" "In3.Cu" "In4.Cu" "In5.Cu" "In6.Cu")
			(hatch none 0.5)
			(connect_pads
				(clearance 0)
			)
			(min_thickness 0.25)
			(keepout
				(tracks not_allowed)
				(vias allowed)
				(pads allowed)
				(copperpour not_allowed)
				(footprints allowed)
			)
			(placement
				(enabled no)
				(sheetname "")
			)
			(fill
				(thermal_gap 0.5)
				(thermal_bridge_width 0.5)
				(island_removal_mode 0)
			)
			(polygon
				(pts
					(arc
						(start -67.730002 32.059999)
						(mid -65.370002 32.059999)
						(end -67.730002 32.059999)
					)
				)
			)
		)
		(zone
			(layers "F.Cu" "B.Cu" "In1.Cu" "In2.Cu" "In3.Cu" "In4.Cu" "In5.Cu" "In6.Cu")
			(hatch none 0.5)
			(connect_pads
				(clearance 0)
			)
			(min_thickness 0.25)
			(keepout
				(tracks not_allowed)
				(vias allowed)
				(pads allowed)
				(copperpour not_allowed)
				(footprints allowed)
			)
			(placement
				(enabled no)
				(sheetname "")
			)
			(fill
				(thermal_gap 0.5)
				(thermal_bridge_width 0.5)
				(island_removal_mode 0)
			)
			(polygon
				(pts
					(arc
						(start -58.130001 32.059999)
						(mid -55.769999 32.059999)
						(end -58.130001 32.059999)
					)
				)
			)
		)
	)
	(footprint ""
		(layer "F.Cu")
		(at -268.224 2.921 -90)
		(property "Reference" "C32"
			(at 1.88976 0.14478 90)
			(unlocked yes)
			(layer "F.SilkS")
			(effects
				(font
					(size 0.762 0.5334)
					(thickness 0.1016)
				)
			)
		)
		(property "Value" ""
			(at 0 0 270)
			(layer "F.Fab")
			(effects
				(font
					(size 1.27 1.27)
				)
			)
		)
		(duplicate_pad_numbers_are_jumpers no)
		(fp_poly
			(pts
				(xy -0.999299 0.504) (xy -0.999299 -0.503999) (xy 0.9993 -0.503999) (xy 0.9993 0.504)
			)
			(stroke
				(width 0)
				(type default)
			)
			(fill no)
			(layer "F.CrtYd")
		)
		(fp_line
			(start -0.499999 0.25)
			(end -0.499999 -0.249999)
			(stroke
				(width 0.1)
				(type default)
			)
			(layer "F.Fab")
		)
		(fp_line
			(start 0.499999 0.25)
			(end -0.499999 0.25)
			(stroke
				(width 0.1)
				(type default)
			)
			(layer "F.Fab")
		)
		(fp_line
			(start -0.499999 -0.249999)
			(end 0.499999 -0.249999)
			(stroke
				(width 0.1)
				(type default)
			)
			(layer "F.Fab")
		)
		(fp_line
			(start 0.499999 -0.249999)
			(end 0.499999 0.25)
			(stroke
				(width 0.1)
				(type default)
			)
			(layer "F.Fab")
		)
		(pad "1" smd rect
			(at -0.4572 0)
			(size 0.508 0.5842)
			(layers "F.Cu" "F.Mask" "F.Paste")
			(net "P3V3_40G_B1_VCC_RX")
		)
		(pad "2" smd rect
			(at 0.4572 0)
			(size 0.508 0.5842)
			(layers "F.Cu" "F.Mask" "F.Paste")
			(net "GND")
		)
	)
	(footprint ""
		(layer "F.Cu")
		(at -75.329199 2.476398 180)
		(property "Reference" "R52"
			(at -3.066199 0.025298 0)
			(unlocked yes)
			(layer "F.SilkS")
			(effects
				(font
					(size 0.762 0.5334)
					(thickness 0.1016)
				)
			)
		)
		(property "Value" ""
			(at 0 0 180)
			(layer "F.Fab")
			(effects
				(font
					(size 1.27 1.27)
				)
			)
		)
		(duplicate_pad_numbers_are_jumpers no)
		(fp_line
			(start 0 -0.381)
			(end 0 0.381)
			(stroke
				(width 0.127)
				(type default)
			)
			(layer "F.SilkS")
		)
		(fp_poly
			(pts
				(xy 1.255601 0.656399) (xy -1.255601 0.656399) (xy -1.255601 -0.6564) (xy 1.255601 -0.6564)
			)
			(stroke
				(width 0)
				(type default)
			)
			(fill no)
			(layer "F.CrtYd")
		)
		(fp_line
			(start 0.800001 0.399999)
			(end 0.800001 -0.4)
			(stroke
				(width 0.1)
				(type default)
			)
			(layer "F.Fab")
		)
		(fp_line
			(start 0.800001 -0.4)
			(end -0.800001 -0.4)
			(stroke
				(width 0.1)
				(type default)
			)
			(layer "F.Fab")
		)
		(fp_line
			(start -0.800001 0.399999)
			(end 0.800001 0.399999)
			(stroke
				(width 0.1)
				(type default)
			)
			(layer "F.Fab")
		)
		(fp_line
			(start -0.800001 -0.4)
			(end -0.800001 0.399999)
			(stroke
				(width 0.1)
				(type default)
			)
			(layer "F.Fab")
		)
		(pad "1" smd rect
			(at -0.650001 0 180)
			(size 0.7112 0.8128)
			(layers "F.Cu" "F.Mask" "F.Paste")
			(net "P3V3_B2_QSFP")
		)
		(pad "2" smd rect
			(at 0.650001 0)
			(size 0.7112 0.8128)
			(layers "F.Cu" "F.Mask" "F.Paste")
			(net "ETH10G_B2_RS1")
		)
	)
	(footprint ""
		(layer "F.Cu")
		(at -110.8456 10.4394)
		(property "Reference" "R69"
			(at 3.1496 0.0127 0)
			(unlocked yes)
			(layer "F.SilkS")
			(effects
				(font
					(size 0.762 0.5334)
					(thickness 0.1016)
				)
			)
		)
		(property "Value" ""
			(at 0 0 0)
			(layer "F.Fab")
			(effects
				(font
					(size 1.27 1.27)
				)
			)
		)
		(duplicate_pad_numbers_are_jumpers no)
		(fp_line
			(start 0 -0.381)
			(end 0 0.381)
			(stroke
				(width 0.127)
				(type default)
			)
			(layer "F.SilkS")
		)
		(fp_poly
			(pts
				(xy 1.255601 0.6564) (xy -1.255601 0.6564) (xy -1.255601 -0.656399) (xy 1.255601 -0.656399)
			)
			(stroke
				(width 0)
				(type default)
			)
			(fill no)
			(layer "F.CrtYd")
		)
		(fp_line
			(start -0.800001 -0.399999)
			(end -0.800001 0.399999)
			(stroke
				(width 0.1)
				(type default)
			)
			(layer "F.Fab")
		)
		(fp_line
			(start -0.800001 0.399999)
			(end 0.800001 0.399999)
			(stroke
				(width 0.1)
				(type default)
			)
			(layer "F.Fab")
		)
		(fp_line
			(start 0.800001 -0.399999)
			(end -0.800001 -0.399999)
			(stroke
				(width 0.1)
				(type default)
			)
			(layer "F.Fab")
		)
		(fp_line
			(start 0.800001 0.399999)
			(end 0.800001 -0.399999)
			(stroke
				(width 0.1)
				(type default)
			)
			(layer "F.Fab")
		)
		(pad "1" smd rect
			(at -0.650001 0)
			(size 0.7112 0.8128)
			(layers "F.Cu" "F.Mask" "F.Paste")
			(net "P3V3_B2_QSFP")
		)
		(pad "2" smd rect
			(at 0.650001 0 180)
			(size 0.7112 0.8128)
			(layers "F.Cu" "F.Mask" "F.Paste")
			(net "ETH40G_B2_RESET_N")
		)
	)
	(footprint ""
		(layer "F.Cu")
		(at -116.250049 32.460001)
		(property "Reference" "J16"
			(at 6.014049 -6.513901 0)
			(unlocked yes)
			(layer "F.SilkS")
			(effects
				(font
					(size 0.762 0.5334)
					(thickness 0.1016)
				)
			)
		)
		(property "Value" ""
			(at 0 0 0)
			(layer "F.Fab")
			(effects
				(font
					(size 1.27 1.27)
				)
			)
		)
		(duplicate_pad_numbers_are_jumpers no)
		(fp_line
			(start -1.925 -5.549999)
			(end 9.924999 -5.549999)
			(stroke
				(width 0.127)
				(type default)
			)
			(layer "F.SilkS")
		)
		(fp_line
			(start -1.925 23.750001)
			(end -1.925 -5.549999)
			(stroke
				(width 0.127)
				(type default)
			)
			(layer "F.SilkS")
		)
		(fp_line
			(start 9.924999 -5.549999)
			(end 9.924999 23.750001)
			(stroke
				(width 0.127)
				(type default)
			)
			(layer "F.SilkS")
		)
		(fp_line
			(start 9.924999 23.750001)
			(end -1.925 23.750001)
			(stroke
				(width 0.127)
				(type default)
			)
			(layer "F.SilkS")
		)
		(fp_poly
			(pts
				(arc
					(start 7.999999 -5.2)
					(mid 11.676954 -3.676955)
					(end 13.199999 0)
				)
				(arc
					(start 13.199999 11.999999)
					(mid 11.676955 15.676956)
					(end 7.999999 17.200001)
				)
				(arc
					(start 0 17.200001)
					(mid -3.676956 15.676955)
					(end -5.2 11.999999)
				)
				(arc
					(start -5.2 0)
					(mid -3.676955 -3.676955)
					(end 0 -5.2)
				)
			)
			(stroke
				(width 0)
				(type default)
			)
			(fill no)
			(layer "B.CrtYd")
		)
		(fp_poly
			(pts
				(xy 10.924999 24.749999) (xy -2.925001 24.749999) (xy -2.925001 -6.549999) (xy 10.924999 -6.549999)
			)
			(stroke
				(width 0)
				(type default)
			)
			(fill no)
			(layer "F.CrtYd")
		)
		(fp_line
			(start -1.925 -5.549999)
			(end 9.924999 -5.549999)
			(stroke
				(width 0.1)
				(type default)
			)
			(layer "F.Fab")
		)
		(fp_line
			(start -1.925 23.750001)
			(end -1.925 -5.549999)
			(stroke
				(width 0.1)
				(type default)
			)
			(layer "F.Fab")
		)
		(fp_line
			(start 9.924999 -5.549999)
			(end 9.924999 23.750001)
			(stroke
				(width 0.1)
				(type default)
			)
			(layer "F.Fab")
		)
		(fp_line
			(start 9.924999 23.750001)
			(end -1.925 23.750001)
			(stroke
				(width 0.1)
				(type default)
			)
			(layer "F.Fab")
		)
		(fp_text user "*"
			(at -2.671451 0 90)
			(unlocked yes)
			(layer "F.SilkS")
			(effects
				(font
					(size 0.381 0.381)
					(thickness 0.381)
				)
			)
		)
		(fp_text user "4"
			(at -2.500001 7.907099 0)
			(unlocked yes)
			(layer "F.SilkS")
			(effects
				(font
					(size 0.762 0.5334)
					(thickness 0.1016)
				)
			)
		)
		(fp_text user "2"
			(at 10.459049 -0.417901 0)
			(unlocked yes)
			(layer "F.SilkS")
			(effects
				(font
					(size 0.762 0.5334)
					(thickness 0.1016)
				)
			)
		)
		(fp_text user "3"
			(at 10.499999 7.907099 0)
			(unlocked yes)
			(layer "F.SilkS")
			(effects
				(font
					(size 0.762 0.5334)
					(thickness 0.1016)
				)
			)
		)
		(pad "" np_thru_hole circle
			(at 4 5.499999)
			(size 1.27 1.27)
			(drill 2.1844)
			(layers "*.Cu" "*.Mask")
		)
		(pad "1A" thru_hole rect
			(at 0 0)
			(size 1.3716 1.3716)
			(drill 0.762)
			(layers "*.Cu" "*.Mask")
			(remove_unused_layers no)
			(net "GND")
			(padstack
				(mode front_inner_back)
				(layer "Inner"
					(shape circle)
					(size 1.3716 1.3716)
				)
				(layer "B.Cu"
					(shape rect)
					(size 1.3716 1.3716)
				)
			)
		)
		(pad "1B" thru_hole circle
			(at 2.000001 0)
			(size 1.3716 1.3716)
			(drill 0.762)
			(layers "*.Cu" "*.Mask")
			(remove_unused_layers no)
			(net "GND")
		)
		(pad "1C" thru_hole circle
			(at 0 2.000001)
			(size 1.3716 1.3716)
			(drill 0.762)
			(layers "*.Cu" "*.Mask")
			(remove_unused_layers no)
			(net "GND")
		)
		(pad "1D" thru_hole circle
			(at 2.000001 2.000001)
			(size 1.3716 1.3716)
			(drill 0.762)
			(layers "*.Cu" "*.Mask")
			(remove_unused_layers no)
			(net "GND")
		)
		(pad "1E" thru_hole circle
			(at 0 4)
			(size 1.3716 1.3716)
			(drill 0.762)
			(layers "*.Cu" "*.Mask")
			(remove_unused_layers no)
			(net "GND")
		)
		(pad "1F" thru_hole circle
			(at 2.000001 4)
			(size 1.3716 1.3716)
			(drill 0.762)
			(layers "*.Cu" "*.Mask")
			(remove_unused_layers no)
			(net "GND")
		)
		(pad "2A" thru_hole circle
			(at 6.000001 0)
			(size 1.3716 1.3716)
			(drill 0.762)
			(layers "*.Cu" "*.Mask")
			(remove_unused_layers no)
			(net "P12V")
		)
		(pad "2B" thru_hole circle
			(at 7.999999 0)
			(size 1.3716 1.3716)
			(drill 0.762)
			(layers "*.Cu" "*.Mask")
			(remove_unused_layers no)
			(net "P12V")
		)
		(pad "2C" thru_hole circle
			(at 6.000001 2.000001)
			(size 1.3716 1.3716)
			(drill 0.762)
			(layers "*.Cu" "*.Mask")
			(remove_unused_layers no)
			(net "P12V")
		)
		(pad "2D" thru_hole circle
			(at 7.999999 2.000001)
			(size 1.3716 1.3716)
			(drill 0.762)
			(layers "*.Cu" "*.Mask")
			(remove_unused_layers no)
			(net "P12V")
		)
		(pad "2E" thru_hole circle
			(at 6.000001 4)
			(size 1.3716 1.3716)
			(drill 0.762)
			(layers "*.Cu" "*.Mask")
			(remove_unused_layers no)
			(net "P12V")
		)
		(pad "2F" thru_hole circle
			(at 7.999999 4)
			(size 1.3716 1.3716)
			(drill 0.762)
			(layers "*.Cu" "*.Mask")
			(remove_unused_layers no)
			(net "P12V")
		)
		(pad "3A" thru_hole circle
			(at 6.000001 7.999999)
			(size 1.3716 1.3716)
			(drill 0.762)
			(layers "*.Cu" "*.Mask")
			(remove_unused_layers no)
			(net "P12V")
		)
		(pad "3B" thru_hole circle
			(at 7.999999 7.999999)
			(size 1.3716 1.3716)
			(drill 0.762)
			(layers "*.Cu" "*.Mask")
			(remove_unused_layers no)
			(net "P12V")
		)
		(pad "3C" thru_hole circle
			(at 6.000001 10)
			(size 1.3716 1.3716)
			(drill 0.762)
			(layers "*.Cu" "*.Mask")
			(remove_unused_layers no)
			(net "P12V")
		)
		(pad "3D" thru_hole circle
			(at 7.999999 10)
			(size 1.3716 1.3716)
			(drill 0.762)
			(layers "*.Cu" "*.Mask")
			(remove_unused_layers no)
			(net "P12V")
		)
		(pad "3E" thru_hole circle
			(at 6.000001 11.999999)
			(size 1.3716 1.3716)
			(drill 0.762)
			(layers "*.Cu" "*.Mask")
			(remove_unused_layers no)
			(net "P12V")
		)
		(pad "3F" thru_hole circle
			(at 7.999999 11.999999)
			(size 1.3716 1.3716)
			(drill 0.762)
			(layers "*.Cu" "*.Mask")
			(remove_unused_layers no)
			(net "P12V")
		)
		(pad "4A" thru_hole circle
			(at 0 7.999999)
			(size 1.3716 1.3716)
			(drill 0.762)
			(layers "*.Cu" "*.Mask")
			(remove_unused_layers no)
			(net "GND")
		)
		(pad "4B" thru_hole circle
			(at 2.000001 7.999999)
			(size 1.3716 1.3716)
			(drill 0.762)
			(layers "*.Cu" "*.Mask")
			(remove_unused_layers no)
			(net "GND")
		)
		(pad "4C" thru_hole circle
			(at 0 10)
			(size 1.3716 1.3716)
			(drill 0.762)
			(layers "*.Cu" "*.Mask")
			(remove_unused_layers no)
			(net "GND")
		)
		(pad "4D" thru_hole circle
			(at 2.000001 10)
			(size 1.3716 1.3716)
			(drill 0.762)
			(layers "*.Cu" "*.Mask")
			(remove_unused_layers no)
			(net "GND")
		)
		(pad "4E" thru_hole circle
			(at 0 11.999999)
			(size 1.3716 1.3716)
			(drill 0.762)
			(layers "*.Cu" "*.Mask")
			(remove_unused_layers no)
			(net "GND")
		)
		(pad "4F" thru_hole circle
			(at 2.000001 11.999999)
			(size 1.3716 1.3716)
			(drill 0.762)
			(layers "*.Cu" "*.Mask")
			(remove_unused_layers no)
			(net "GND")
		)
		(zone
			(layers "F.Cu" "B.Cu" "In1.Cu" "In2.Cu" "In3.Cu" "In4.Cu" "In5.Cu" "In6.Cu")
			(hatch none 0.5)
			(connect_pads
				(clearance 0)
			)
			(min_thickness 0.25)
			(keepout
				(tracks not_allowed)
				(vias allowed)
				(pads allowed)
				(copperpour not_allowed)
				(footprints allowed)
			)
			(placement
				(enabled no)
				(sheetname "")
			)
			(fill
				(thermal_gap 0.5)
				(thermal_bridge_width 0.5)
				(island_removal_mode 0)
			)
			(polygon
				(pts
					(arc
						(start -110.77685 37.96)
						(mid -113.72325 37.96)
						(end -110.77685 37.96)
					)
				)
			)
		)
	)
	(footprint ""
		(layer "F.Cu")
		(at -296.145801 1.384402)
		(property "Reference" "R18"
			(at 3.029801 0.050698 0)
			(unlocked yes)
			(layer "F.SilkS")
			(effects
				(font
					(size 0.762 0.5334)
					(thickness 0.1016)
				)
			)
		)
		(property "Value" ""
			(at 0 0 0)
			(layer "F.Fab")
			(effects
				(font
					(size 1.27 1.27)
				)
			)
		)
		(duplicate_pad_numbers_are_jumpers no)
		(fp_line
			(start 0 -0.381)
			(end 0 0.381)
			(stroke
				(width 0.127)
				(type default)
			)
			(layer "F.SilkS")
		)
		(fp_poly
			(pts
				(xy 1.255601 0.656399) (xy -1.255601 0.656399) (xy -1.255601 -0.6564) (xy 1.255601 -0.6564)
			)
			(stroke
				(width 0)
				(type default)
			)
			(fill no)
			(layer "F.CrtYd")
		)
		(fp_line
			(start -0.800001 -0.4)
			(end -0.800001 0.399999)
			(stroke
				(width 0.1)
				(type default)
			)
			(layer "F.Fab")
		)
		(fp_line
			(start -0.800001 0.399999)
			(end 0.800001 0.399999)
			(stroke
				(width 0.1)
				(type default)
			)
			(layer "F.Fab")
		)
		(fp_line
			(start 0.800001 -0.4)
			(end -0.800001 -0.4)
			(stroke
				(width 0.1)
				(type default)
			)
			(layer "F.Fab")
		)
		(fp_line
			(start 0.800001 0.399999)
			(end 0.800001 -0.4)
			(stroke
				(width 0.1)
				(type default)
			)
			(layer "F.Fab")
		)
		(pad "1" smd rect
			(at -0.650001 0)
			(size 0.7112 0.8128)
			(layers "F.Cu" "F.Mask" "F.Paste")
			(net "P3V3_B1_QSFP")
		)
		(pad "2" smd rect
			(at 0.650001 0 180)
			(size 0.7112 0.8128)
			(layers "F.Cu" "F.Mask" "F.Paste")
			(net "ETH10G_B1_TX_FAULT")
		)
	)
	(footprint ""
		(layer "F.Cu")
		(at -335.846001 21.298002 90)
		(property "Reference" "C4"
			(at -0.418998 -1.300899 90)
			(unlocked yes)
			(layer "F.SilkS")
			(effects
				(font
					(size 0.762 0.5334)
					(thickness 0.1016)
				)
			)
		)
		(property "Value" ""
			(at 0 0 90)
			(layer "F.Fab")
			(effects
				(font
					(size 1.27 1.27)
				)
			)
		)
		(duplicate_pad_numbers_are_jumpers no)
		(fp_poly
			(pts
				(xy -0.999299 0.504) (xy -0.999299 -0.503999) (xy 0.9993 -0.503999) (xy 0.9993 0.504)
			)
			(stroke
				(width 0)
				(type default)
			)
			(fill no)
			(layer "F.CrtYd")
		)
		(fp_line
			(start 0.499999 -0.249999)
			(end 0.499999 0.25)
			(stroke
				(width 0.1)
				(type default)
			)
			(layer "F.Fab")
		)
		(fp_line
			(start -0.499999 -0.249999)
			(end 0.499999 -0.249999)
			(stroke
				(width 0.1)
				(type default)
			)
			(layer "F.Fab")
		)
		(fp_line
			(start 0.499999 0.25)
			(end -0.499999 0.25)
			(stroke
				(width 0.1)
				(type default)
			)
			(layer "F.Fab")
		)
		(fp_line
			(start -0.499999 0.25)
			(end -0.499999 -0.249999)
			(stroke
				(width 0.1)
				(type default)
			)
			(layer "F.Fab")
		)
		(pad "1" smd rect
			(at -0.4572 0 180)
			(size 0.508 0.5842)
			(layers "F.Cu" "F.Mask" "F.Paste")
			(net "P12V")
		)
		(pad "2" smd rect
			(at 0.4572 0 180)
			(size 0.508 0.5842)
			(layers "F.Cu" "F.Mask" "F.Paste")
			(net "GND")
		)
	)
	(footprint ""
		(layer "F.Cu")
		(at -58.610401 45.631202)
		(property "Reference" "FB4"
			(at -0.698599 1.142898 0)
			(unlocked yes)
			(layer "F.SilkS")
			(effects
				(font
					(size 0.762 0.5334)
					(thickness 0.1016)
				)
				(justify left)
			)
		)
		(property "Value" ""
			(at 0 0 0)
			(layer "F.Fab")
			(effects
				(font
					(size 1.27 1.27)
				)
			)
		)
		(duplicate_pad_numbers_are_jumpers no)
		(fp_poly
			(pts
				(xy -1.016 0.508) (xy -1.016 -0.508) (xy 1.016 -0.508) (xy 1.016 0.508)
			)
			(stroke
				(width 0)
				(type default)
			)
			(fill no)
			(layer "F.CrtYd")
		)
		(fp_line
			(start -0.508 -0.254)
			(end 0.508 -0.254)
			(stroke
				(width 0.1)
				(type default)
			)
			(layer "F.Fab")
		)
		(fp_line
			(start -0.508 0.254)
			(end -0.508 -0.254)
			(stroke
				(width 0.1)
				(type default)
			)
			(layer "F.Fab")
		)
		(fp_line
			(start 0.508 -0.254)
			(end 0.508 0.254)
			(stroke
				(width 0.1)
				(type default)
			)
			(layer "F.Fab")
		)
		(fp_line
			(start 0.508 0.254)
			(end -0.508 0.254)
			(stroke
				(width 0.1)
				(type default)
			)
			(layer "F.Fab")
		)
		(pad "1" smd rect
			(at -0.4572 0 90)
			(size 0.508 0.5842)
			(layers "F.Cu" "F.Mask" "F.Paste")
			(net "P3V3_10G_B2_VCCT")
		)
		(pad "2" smd rect
			(at 0.4572 0 90)
			(size 0.508 0.5842)
			(layers "F.Cu" "F.Mask" "F.Paste")
			(net "UNNAMED_6_FERRITE_I27_B")
		)
	)
	(footprint ""
		(layer "F.Cu")
		(at -300.971801 5.956402)
		(property "Reference" "R24"
			(at -3.320199 0.050698 0)
			(unlocked yes)
			(layer "F.SilkS")
			(effects
				(font
					(size 0.762 0.5334)
					(thickness 0.1016)
				)
			)
		)
		(property "Value" ""
			(at 0 0 0)
			(layer "F.Fab")
			(effects
				(font
					(size 1.27 1.27)
				)
			)
		)
		(duplicate_pad_numbers_are_jumpers no)
		(fp_line
			(start 0 -0.381)
			(end 0 0.381)
			(stroke
				(width 0.127)
				(type default)
			)
			(layer "F.SilkS")
		)
		(fp_poly
			(pts
				(xy 1.255601 0.656399) (xy -1.255601 0.656399) (xy -1.255601 -0.6564) (xy 1.255601 -0.6564)
			)
			(stroke
				(width 0)
				(type default)
			)
			(fill no)
			(layer "F.CrtYd")
		)
		(fp_line
			(start -0.800001 -0.4)
			(end -0.800001 0.399999)
			(stroke
				(width 0.1)
				(type default)
			)
			(layer "F.Fab")
		)
		(fp_line
			(start -0.800001 0.399999)
			(end 0.800001 0.399999)
			(stroke
				(width 0.1)
				(type default)
			)
			(layer "F.Fab")
		)
		(fp_line
			(start 0.800001 -0.4)
			(end -0.800001 -0.4)
			(stroke
				(width 0.1)
				(type default)
			)
			(layer "F.Fab")
		)
		(fp_line
			(start 0.800001 0.399999)
			(end 0.800001 -0.4)
			(stroke
				(width 0.1)
				(type default)
			)
			(layer "F.Fab")
		)
		(pad "1" smd rect
			(at -0.650001 0)
			(size 0.7112 0.8128)
			(layers "F.Cu" "F.Mask" "F.Paste")
			(net "P3V3_B1_QSFP")
		)
		(pad "2" smd rect
			(at 0.650001 0 180)
			(size 0.7112 0.8128)
			(layers "F.Cu" "F.Mask" "F.Paste")
			(net "ETH10G_B1_RS1")
		)
	)
	(footprint ""
		(layer "F.Cu")
		(at -80.118801 6.337402)
		(property "Reference" "R30"
			(at -2.939199 -0.076302 0)
			(unlocked yes)
			(layer "F.SilkS")
			(effects
				(font
					(size 0.762 0.5334)
					(thickness 0.1016)
				)
			)
		)
		(property "Value" ""
			(at 0 0 0)
			(layer "F.Fab")
			(effects
				(font
					(size 1.27 1.27)
				)
			)
		)
		(duplicate_pad_numbers_are_jumpers no)
		(fp_line
			(start 0 -0.381)
			(end 0 0.381)
			(stroke
				(width 0.127)
				(type default)
			)
			(layer "F.SilkS")
		)
		(fp_poly
			(pts
				(xy 1.255601 0.656399) (xy -1.255601 0.656399) (xy -1.255601 -0.6564) (xy 1.255601 -0.6564)
			)
			(stroke
				(width 0)
				(type default)
			)
			(fill no)
			(layer "F.CrtYd")
		)
		(fp_line
			(start -0.800001 -0.4)
			(end -0.800001 0.399999)
			(stroke
				(width 0.1)
				(type default)
			)
			(layer "F.Fab")
		)
		(fp_line
			(start -0.800001 0.399999)
			(end 0.800001 0.399999)
			(stroke
				(width 0.1)
				(type default)
			)
			(layer "F.Fab")
		)
		(fp_line
			(start 0.800001 -0.4)
			(end -0.800001 -0.4)
			(stroke
				(width 0.1)
				(type default)
			)
			(layer "F.Fab")
		)
		(fp_line
			(start 0.800001 0.399999)
			(end 0.800001 -0.4)
			(stroke
				(width 0.1)
				(type default)
			)
			(layer "F.Fab")
		)
		(pad "1" smd rect
			(at -0.650001 0)
			(size 0.7112 0.8128)
			(layers "F.Cu" "F.Mask" "F.Paste")
			(net "P3V3_B2_QSFP")
		)
		(pad "2" smd rect
			(at 0.650001 0 180)
			(size 0.7112 0.8128)
			(layers "F.Cu" "F.Mask" "F.Paste")
			(net "SKU_B2_ID0")
		)
	)
	(footprint ""
		(layer "F.Cu")
		(at -296.164 11.176 180)
		(property "Reference" "R28"
			(at -3.048 0.0889 0)
			(unlocked yes)
			(layer "F.SilkS")
			(effects
				(font
					(size 0.762 0.5334)
					(thickness 0.1016)
				)
			)
		)
		(property "Value" ""
			(at 0 0 180)
			(layer "F.Fab")
			(effects
				(font
					(size 1.27 1.27)
				)
			)
		)
		(duplicate_pad_numbers_are_jumpers no)
		(fp_line
			(start 0 -0.381)
			(end 0 0.381)
			(stroke
				(width 0.127)
				(type default)
			)
			(layer "F.SilkS")
		)
		(fp_poly
			(pts
				(xy 1.255601 0.656399) (xy -1.255601 0.656399) (xy -1.255601 -0.6564) (xy 1.255601 -0.6564)
			)
			(stroke
				(width 0)
				(type default)
			)
			(fill no)
			(layer "F.CrtYd")
		)
		(fp_line
			(start 0.800001 0.399999)
			(end 0.800001 -0.399999)
			(stroke
				(width 0.1)
				(type default)
			)
			(layer "F.Fab")
		)
		(fp_line
			(start 0.800001 -0.399999)
			(end -0.800001 -0.399999)
			(stroke
				(width 0.1)
				(type default)
			)
			(layer "F.Fab")
		)
		(fp_line
			(start -0.800001 0.399999)
			(end 0.800001 0.399999)
			(stroke
				(width 0.1)
				(type default)
			)
			(layer "F.Fab")
		)
		(fp_line
			(start -0.800001 -0.399999)
			(end -0.800001 0.399999)
			(stroke
				(width 0.1)
				(type default)
			)
			(layer "F.Fab")
		)
		(pad "1" smd rect
			(at -0.650001 0 180)
			(size 0.7112 0.8128)
			(layers "F.Cu" "F.Mask" "F.Paste")
			(net "P3V3_B1_QSFP")
		)
		(pad "2" smd rect
			(at 0.650001 0)
			(size 0.7112 0.8128)
			(layers "F.Cu" "F.Mask" "F.Paste")
			(net "ETH10G_B1_SCL")
		)
	)
	(footprint ""
		(layer "F.Cu")
		(at -80.0862 7.8486)
		(property "Reference" "R32"
			(at -3.2258 -0.0635 0)
			(unlocked yes)
			(layer "F.SilkS")
			(effects
				(font
					(size 0.762 0.5334)
					(thickness 0.1016)
				)
			)
		)
		(property "Value" ""
			(at 0 0 0)
			(layer "F.Fab")
			(effects
				(font
					(size 1.27 1.27)
				)
			)
		)
		(duplicate_pad_numbers_are_jumpers no)
		(fp_line
			(start 0 -0.381)
			(end 0 0.381)
			(stroke
				(width 0.127)
				(type default)
			)
			(layer "F.SilkS")
		)
		(fp_poly
			(pts
				(xy 1.255601 0.6564) (xy -1.255601 0.6564) (xy -1.255601 -0.656399) (xy 1.255601 -0.656399)
			)
			(stroke
				(width 0)
				(type default)
			)
			(fill no)
			(layer "F.CrtYd")
		)
		(fp_line
			(start -0.800001 -0.399999)
			(end -0.800001 0.399999)
			(stroke
				(width 0.1)
				(type default)
			)
			(layer "F.Fab")
		)
		(fp_line
			(start -0.800001 0.399999)
			(end 0.800001 0.399999)
			(stroke
				(width 0.1)
				(type default)
			)
			(layer "F.Fab")
		)
		(fp_line
			(start 0.800001 -0.399999)
			(end -0.800001 -0.399999)
			(stroke
				(width 0.1)
				(type default)
			)
			(layer "F.Fab")
		)
		(fp_line
			(start 0.800001 0.399999)
			(end 0.800001 -0.399999)
			(stroke
				(width 0.1)
				(type default)
			)
			(layer "F.Fab")
		)
		(pad "1" smd rect
			(at -0.650001 0)
			(size 0.7112 0.8128)
			(layers "F.Cu" "F.Mask" "F.Paste")
			(net "P3V3_B2_QSFP")
		)
		(pad "2" smd rect
			(at 0.650001 0 180)
			(size 0.7112 0.8128)
			(layers "F.Cu" "F.Mask" "F.Paste")
			(net "SKU_B2_ID1")
		)
	)
	(footprint ""
		(layer "F.Cu")
		(at -75.3618 8.255 180)
		(property "Reference" "R51"
			(at -3.2131 0.0127 0)
			(unlocked yes)
			(layer "F.SilkS")
			(effects
				(font
					(size 0.762 0.5334)
					(thickness 0.1016)
				)
			)
		)
		(property "Value" ""
			(at 0 0 180)
			(layer "F.Fab")
			(effects
				(font
					(size 1.27 1.27)
				)
			)
		)
		(duplicate_pad_numbers_are_jumpers no)
		(fp_line
			(start 0 -0.381)
			(end 0 0.381)
			(stroke
				(width 0.127)
				(type default)
			)
			(layer "F.SilkS")
		)
		(fp_poly
			(pts
				(xy 1.255601 0.656399) (xy -1.255601 0.656399) (xy -1.255601 -0.6564) (xy 1.255601 -0.6564)
			)
			(stroke
				(width 0)
				(type default)
			)
			(fill no)
			(layer "F.CrtYd")
		)
		(fp_line
			(start 0.800001 0.399999)
			(end 0.800001 -0.399999)
			(stroke
				(width 0.1)
				(type default)
			)
			(layer "F.Fab")
		)
		(fp_line
			(start 0.800001 -0.399999)
			(end -0.800001 -0.399999)
			(stroke
				(width 0.1)
				(type default)
			)
			(layer "F.Fab")
		)
		(fp_line
			(start -0.800001 0.399999)
			(end 0.800001 0.399999)
			(stroke
				(width 0.1)
				(type default)
			)
			(layer "F.Fab")
		)
		(fp_line
			(start -0.800001 -0.399999)
			(end -0.800001 0.399999)
			(stroke
				(width 0.1)
				(type default)
			)
			(layer "F.Fab")
		)
		(pad "1" smd rect
			(at -0.650001 0 180)
			(size 0.7112 0.8128)
			(layers "F.Cu" "F.Mask" "F.Paste")
			(net "ETH10G_B2_RS0")
		)
		(pad "2" smd rect
			(at 0.650001 0)
			(size 0.7112 0.8128)
			(layers "F.Cu" "F.Mask" "F.Paste")
			(net "GND")
		)
	)
	(footprint ""
		(layer "F.Cu")
		(at -296.164 8.382 180)
		(property "Reference" "R2"
			(at -2.667 0.0889 0)
			(unlocked yes)
			(layer "F.SilkS")
			(effects
				(font
					(size 0.762 0.5334)
					(thickness 0.1016)
				)
			)
		)
		(property "Value" ""
			(at 0 0 180)
			(layer "F.Fab")
			(effects
				(font
					(size 1.27 1.27)
				)
			)
		)
		(duplicate_pad_numbers_are_jumpers no)
		(fp_line
			(start 0 -0.381)
			(end 0 0.381)
			(stroke
				(width 0.127)
				(type default)
			)
			(layer "F.SilkS")
		)
		(fp_poly
			(pts
				(xy 1.255601 0.656399) (xy -1.255601 0.656399) (xy -1.255601 -0.6564) (xy 1.255601 -0.6564)
			)
			(stroke
				(width 0)
				(type default)
			)
			(fill no)
			(layer "F.CrtYd")
		)
		(fp_line
			(start 0.800001 0.399999)
			(end 0.800001 -0.399999)
			(stroke
				(width 0.1)
				(type default)
			)
			(layer "F.Fab")
		)
		(fp_line
			(start 0.800001 -0.399999)
			(end -0.800001 -0.399999)
			(stroke
				(width 0.1)
				(type default)
			)
			(layer "F.Fab")
		)
		(fp_line
			(start -0.800001 0.399999)
			(end 0.800001 0.399999)
			(stroke
				(width 0.1)
				(type default)
			)
			(layer "F.Fab")
		)
		(fp_line
			(start -0.800001 -0.399999)
			(end -0.800001 0.399999)
			(stroke
				(width 0.1)
				(type default)
			)
			(layer "F.Fab")
		)
		(pad "1" smd rect
			(at -0.650001 0 180)
			(size 0.7112 0.8128)
			(layers "F.Cu" "F.Mask" "F.Paste")
			(net "P3V3_B1_QSFP")
		)
		(pad "2" smd rect
			(at 0.650001 0)
			(size 0.7112 0.8128)
			(layers "F.Cu" "F.Mask" "F.Paste")
			(net "SKU_B1_ID0")
		)
	)
	(footprint ""
		(layer "F.Cu")
		(at -73.040001 45.360001 180)
		(property "Reference" "J19"
			(at 4.175999 18.143901 0)
			(unlocked yes)
			(layer "F.SilkS")
			(effects
				(font
					(size 0.762 0.5334)
					(thickness 0.1016)
				)
			)
		)
		(property "Value" ""
			(at 0 0 180)
			(layer "F.Fab")
			(effects
				(font
					(size 1.27 1.27)
				)
			)
		)
		(duplicate_pad_numbers_are_jumpers no)
		(fp_line
			(start 10.950001 15.3)
			(end -0.95 15.3)
			(stroke
				(width 0.127)
				(type default)
			)
			(layer "F.SilkS")
		)
		(fp_line
			(start 10.950001 5.609001)
			(end 10.950001 15.3)
			(stroke
				(width 0.127)
				(type default)
			)
			(layer "F.SilkS")
		)
		(fp_line
			(start 10.950001 -11.999999)
			(end 10.950001 4.212001)
			(stroke
				(width 0.127)
				(type default)
			)
			(layer "F.SilkS")
		)
		(fp_line
			(start -0.95 15.3)
			(end -0.95 13.356001)
			(stroke
				(width 0.127)
				(type default)
			)
			(layer "F.SilkS")
		)
		(fp_line
			(start -0.95 11.451001)
			(end -0.95 2.561001)
			(stroke
				(width 0.127)
				(type default)
			)
			(layer "F.SilkS")
		)
		(fp_line
			(start -0.95 0.656001)
			(end -0.95 -11.999999)
			(stroke
				(width 0.127)
				(type default)
			)
			(layer "F.SilkS")
		)
		(fp_line
			(start -0.95 -11.999999)
			(end 10.950001 -11.999999)
			(stroke
				(width 0.127)
				(type default)
			)
			(layer "F.SilkS")
		)
		(fp_poly
			(pts
				(arc
					(start -4.93 12.500001)
					(mid -3.486036 15.986037)
					(end 0 17.430001)
				)
				(arc
					(start 10.000001 17.430001)
					(mid 13.486037 15.986037)
					(end 14.930001 12.500001)
				)
				(arc
					(start 14.930001 -0.1)
					(mid 13.486037 -3.586036)
					(end 10.000001 -5.03)
				)
				(arc
					(start 0 -5.03)
					(mid -3.486036 -3.586036)
					(end -4.93 -0.1)
				)
			)
			(stroke
				(width 0)
				(type default)
			)
			(fill no)
			(layer "B.CrtYd")
		)
		(fp_poly
			(pts
				(xy 11.949999 16.300001) (xy -1.950001 16.300001) (xy -1.950001 -12.999999) (xy 11.949999 -12.999999)
			)
			(stroke
				(width 0)
				(type default)
			)
			(fill no)
			(layer "F.CrtYd")
		)
		(fp_line
			(start 10.950001 15.3)
			(end -0.95 15.3)
			(stroke
				(width 0.1)
				(type default)
			)
			(layer "F.Fab")
		)
		(fp_line
			(start 10.950001 -11.999999)
			(end 10.950001 15.3)
			(stroke
				(width 0.1)
				(type default)
			)
			(layer "F.Fab")
		)
		(fp_line
			(start -0.95 15.3)
			(end -0.95 -11.999999)
			(stroke
				(width 0.1)
				(type default)
			)
			(layer "F.Fab")
		)
		(fp_line
			(start -0.95 -11.999999)
			(end 10.950001 -11.999999)
			(stroke
				(width 0.1)
				(type default)
			)
			(layer "F.Fab")
		)
		(fp_text user "I6"
			(at 11.668999 11.285901 0)
			(unlocked yes)
			(layer "F.SilkS")
			(effects
				(font
					(size 0.762 0.5334)
					(thickness 0.1016)
				)
			)
		)
		(fp_text user "E6"
			(at 11.668999 4.808901 0)
			(unlocked yes)
			(layer "F.SilkS")
			(effects
				(font
					(size 0.762 0.5334)
					(thickness 0.1016)
				)
			)
		)
		(fp_text user "A6"
			(at 11.668999 -0.017099 0)
			(unlocked yes)
			(layer "F.SilkS")
			(effects
				(font
					(size 0.762 0.5334)
					(thickness 0.1016)
				)
			)
		)
		(fp_text user "A1"
			(at 0.746999 -1.160099 0)
			(unlocked yes)
			(layer "F.SilkS")
			(effects
				(font
					(size 0.762 0.5334)
					(thickness 0.1016)
				)
			)
		)
		(fp_text user "*"
			(at -0.396001 -1.077549 0)
			(unlocked yes)
			(layer "F.SilkS")
			(effects
				(font
					(size 0.381 0.381)
					(thickness 0.381)
				)
			)
		)
		(fp_text user "I6"
			(at 11.55 11.0809 0)
			(unlocked yes)
			(layer "B.SilkS")
			(effects
				(font
					(size 0.762 0.5334)
					(thickness 0.1016)
				)
				(justify mirror)
			)
		)
		(fp_text user "A6"
			(at 11.55 -0.1191 0)
			(unlocked yes)
			(layer "B.SilkS")
			(effects
				(font
					(size 0.762 0.5334)
					(thickness 0.1016)
				)
				(justify mirror)
			)
		)
		(fp_text user "E6"
			(at 11.323559 5.268641 0)
			(unlocked yes)
			(layer "B.SilkS")
			(effects
				(font
					(size 0.762 0.5334)
					(thickness 0.1016)
				)
				(justify mirror)
			)
		)
		(fp_text user "E1"
			(at -1.241821 5.906181 0)
			(unlocked yes)
			(layer "B.SilkS")
			(effects
				(font
					(size 0.762 0.5334)
					(thickness 0.1016)
				)
				(justify mirror)
			)
		)
		(fp_text user "I1"
			(at -1.285001 10.777901 0)
			(unlocked yes)
			(layer "B.SilkS")
			(effects
				(font
					(size 0.762 0.5334)
					(thickness 0.1016)
				)
				(justify mirror)
			)
		)
		(fp_text user "A1"
			(at -1.549999 -0.1191 0)
			(unlocked yes)
			(layer "B.SilkS")
			(effects
				(font
					(size 0.762 0.5334)
					(thickness 0.1016)
				)
				(justify mirror)
			)
		)
		(pad "A1" thru_hole circle
			(at 0 0 180)
			(size 0.8128 0.8128)
			(drill 0.508)
			(layers "*.Cu" "*.Mask")
			(remove_unused_layers no)
			(net "ETH40G_B2_TX3P")
		)
		(pad "A2" thru_hole circle
			(at 2.000001 -0.1 180)
			(size 0.8128 0.8128)
			(drill 0.508)
			(layers "*.Cu" "*.Mask")
			(remove_unused_layers no)
			(net "GND")
		)
		(pad "A3" thru_hole circle
			(at 4 0 180)
			(size 0.8128 0.8128)
			(drill 0.508)
			(layers "*.Cu" "*.Mask")
			(remove_unused_layers no)
			(net "ETH40G_B2_RX2P")
		)
		(pad "A4" thru_hole circle
			(at 6.000001 -0.1 180)
			(size 0.8128 0.8128)
			(drill 0.508)
			(layers "*.Cu" "*.Mask")
			(remove_unused_layers no)
			(net "GND")
		)
		(pad "A5" thru_hole circle
			(at 7.999999 0 180)
			(size 0.8128 0.8128)
			(drill 0.508)
			(layers "*.Cu" "*.Mask")
			(remove_unused_layers no)
			(net "ETH40G_B2_RX1P")
		)
		(pad "A6" thru_hole circle
			(at 10 -0.1 180)
			(size 0.8128 0.8128)
			(drill 0.508)
			(layers "*.Cu" "*.Mask")
			(remove_unused_layers no)
			(net "GND")
		)
		(pad "B1" thru_hole circle
			(at 0 1.4 180)
			(size 0.8128 0.8128)
			(drill 0.508)
			(layers "*.Cu" "*.Mask")
			(remove_unused_layers no)
			(net "ETH40G_B2_TX3N")
		)
		(pad "B2" thru_hole circle
			(at 2.000001 1.3 180)
			(size 0.8128 0.8128)
			(drill 0.508)
			(layers "*.Cu" "*.Mask")
			(remove_unused_layers no)
			(net "ETH40G_B2_RX3P")
		)
		(pad "B3" thru_hole circle
			(at 4 1.4 180)
			(size 0.8128 0.8128)
			(drill 0.508)
			(layers "*.Cu" "*.Mask")
			(remove_unused_layers no)
			(net "ETH40G_B2_RX2N")
		)
		(pad "B4" thru_hole circle
			(at 6.000001 1.3 180)
			(size 0.8128 0.8128)
			(drill 0.508)
			(layers "*.Cu" "*.Mask")
			(remove_unused_layers no)
			(net "ETH40G_B2_TX2P")
		)
		(pad "B5" thru_hole circle
			(at 7.999999 1.4 180)
			(size 0.8128 0.8128)
			(drill 0.508)
			(layers "*.Cu" "*.Mask")
			(remove_unused_layers no)
			(net "ETH40G_B2_RX1N")
		)
		(pad "B6" thru_hole circle
			(at 10 1.3 180)
			(size 0.8128 0.8128)
			(drill 0.508)
			(layers "*.Cu" "*.Mask")
			(remove_unused_layers no)
			(net "ETH40G_B2_TX1P")
		)
		(pad "C1" thru_hole circle
			(at 0 2.799999 180)
			(size 0.8128 0.8128)
			(drill 0.508)
			(layers "*.Cu" "*.Mask")
			(remove_unused_layers no)
			(net "GND")
		)
		(pad "C2" thru_hole circle
			(at 2.000001 2.7 180)
			(size 0.8128 0.8128)
			(drill 0.508)
			(layers "*.Cu" "*.Mask")
			(remove_unused_layers no)
			(net "ETH40G_B2_RX3N")
		)
		(pad "C3" thru_hole circle
			(at 4 2.799999 180)
			(size 0.8128 0.8128)
			(drill 0.508)
			(layers "*.Cu" "*.Mask")
			(remove_unused_layers no)
			(net "GND")
		)
		(pad "C4" thru_hole circle
			(at 6.000001 2.7 180)
			(size 0.8128 0.8128)
			(drill 0.508)
			(layers "*.Cu" "*.Mask")
			(remove_unused_layers no)
			(net "ETH40G_B2_TX2N")
		)
		(pad "C5" thru_hole circle
			(at 7.999999 2.799999 180)
			(size 0.8128 0.8128)
			(drill 0.508)
			(layers "*.Cu" "*.Mask")
			(remove_unused_layers no)
			(net "GND")
		)
		(pad "C6" thru_hole circle
			(at 10 2.7 180)
			(size 0.8128 0.8128)
			(drill 0.508)
			(layers "*.Cu" "*.Mask")
			(remove_unused_layers no)
			(net "ETH40G_B2_TX1N")
		)
		(pad "D1" thru_hole circle
			(at 0 4.199999 180)
			(size 0.8128 0.8128)
			(drill 0.508)
			(layers "*.Cu" "*.Mask")
			(remove_unused_layers no)
			(net "ETH10G_B2_RXP")
		)
		(pad "D2" thru_hole circle
			(at 2.000001 4.099999 180)
			(size 0.8128 0.8128)
			(drill 0.508)
			(layers "*.Cu" "*.Mask")
			(remove_unused_layers no)
			(net "GND")
		)
		(pad "D3" thru_hole circle
			(at 4 4.199999 180)
			(size 0.8128 0.8128)
			(drill 0.508)
			(layers "*.Cu" "*.Mask")
			(remove_unused_layers no)
			(net "ETH10G_B2_SDA")
		)
		(pad "D4" thru_hole circle
			(at 6.000001 4.099999 180)
			(size 0.8128 0.8128)
			(drill 0.508)
			(layers "*.Cu" "*.Mask")
			(remove_unused_layers no)
			(net "GND")
		)
		(pad "D5" thru_hole circle
			(at 7.999999 4.199999 180)
			(size 0.8128 0.8128)
			(drill 0.508)
			(layers "*.Cu" "*.Mask")
			(remove_unused_layers no)
			(net "P3V3_B2_QSFP")
		)
		(pad "D6" thru_hole circle
			(at 10 4.099999 180)
			(size 0.8128 0.8128)
			(drill 0.508)
			(layers "*.Cu" "*.Mask")
			(remove_unused_layers no)
			(net "GND")
		)
		(pad "E1" thru_hole circle
			(at 0 5.599999 180)
			(size 0.8128 0.8128)
			(drill 0.508)
			(layers "*.Cu" "*.Mask")
			(remove_unused_layers no)
			(net "ETH10G_B2_RXN")
		)
		(pad "E2" thru_hole circle
			(at 2.000001 5.499999 180)
			(size 0.8128 0.8128)
			(drill 0.508)
			(layers "*.Cu" "*.Mask")
			(remove_unused_layers no)
			(net "Net_14")
		)
		(pad "E3" thru_hole circle
			(at 4 5.599999 180)
			(size 0.8128 0.8128)
			(drill 0.508)
			(layers "*.Cu" "*.Mask")
			(remove_unused_layers no)
			(net "ETH10G_B2_SCL")
		)
		(pad "E4" thru_hole circle
			(at 6.000001 5.499999 180)
			(size 0.8128 0.8128)
			(drill 0.508)
			(layers "*.Cu" "*.Mask")
			(remove_unused_layers no)
			(net "ETH40G_B2_SDA")
		)
		(pad "E5" thru_hole circle
			(at 7.999999 5.599999 180)
			(size 0.8128 0.8128)
			(drill 0.508)
			(layers "*.Cu" "*.Mask")
			(remove_unused_layers no)
			(net "P3V3_B2_QSFP")
		)
		(pad "E6" thru_hole circle
			(at 10 5.499999 180)
			(size 0.8128 0.8128)
			(drill 0.508)
			(layers "*.Cu" "*.Mask")
			(remove_unused_layers no)
			(net "ETH40G_B2_RX0P")
		)
		(pad "F1" thru_hole circle
			(at 0 7.000001 180)
			(size 0.8128 0.8128)
			(drill 0.508)
			(layers "*.Cu" "*.Mask")
			(remove_unused_layers no)
			(net "GND")
		)
		(pad "F2" thru_hole circle
			(at 2.000001 6.899999 180)
			(size 0.8128 0.8128)
			(drill 0.508)
			(layers "*.Cu" "*.Mask")
			(remove_unused_layers no)
			(net "SKU_B2_ID2")
		)
		(pad "F3" thru_hole circle
			(at 4 7.000001 180)
			(size 0.8128 0.8128)
			(drill 0.508)
			(layers "*.Cu" "*.Mask")
			(remove_unused_layers no)
			(net "SKU_B2_ID0")
		)
		(pad "F4" thru_hole circle
			(at 6.000001 6.899999 180)
			(size 0.8128 0.8128)
			(drill 0.508)
			(layers "*.Cu" "*.Mask")
			(remove_unused_layers no)
			(net "ETH40G_B2_SCL")
		)
		(pad "F5" thru_hole circle
			(at 7.999999 7.000001 180)
			(size 0.8128 0.8128)
			(drill 0.508)
			(layers "*.Cu" "*.Mask")
			(remove_unused_layers no)
			(net "GND")
		)
		(pad "F6" thru_hole circle
			(at 10 6.899999 180)
			(size 0.8128 0.8128)
			(drill 0.508)
			(layers "*.Cu" "*.Mask")
			(remove_unused_layers no)
			(net "ETH40G_B2_RX0N")
		)
		(pad "G1" thru_hole circle
			(at 0 8.400001 180)
			(size 0.8128 0.8128)
			(drill 0.508)
			(layers "*.Cu" "*.Mask")
			(remove_unused_layers no)
			(net "ETH10G_B2_TXP")
		)
		(pad "G2" thru_hole circle
			(at 2.000001 8.300001 180)
			(size 0.8128 0.8128)
			(drill 0.508)
			(layers "*.Cu" "*.Mask")
			(remove_unused_layers no)
			(net "GND")
		)
		(pad "G3" thru_hole circle
			(at 4 8.400001 180)
			(size 0.8128 0.8128)
			(drill 0.508)
			(layers "*.Cu" "*.Mask")
			(remove_unused_layers no)
			(net "SERIAL_B2_RX1")
		)
		(pad "G4" thru_hole circle
			(at 6.000001 8.300001 180)
			(size 0.8128 0.8128)
			(drill 0.508)
			(layers "*.Cu" "*.Mask")
			(remove_unused_layers no)
			(net "SERIAL_B2_RX2")
		)
		(pad "G5" thru_hole circle
			(at 7.999999 8.400001 180)
			(size 0.8128 0.8128)
			(drill 0.508)
			(layers "*.Cu" "*.Mask")
			(remove_unused_layers no)
			(net "PSU_B2_ALERT_N")
		)
		(pad "G6" thru_hole circle
			(at 10 8.300001 180)
			(size 0.8128 0.8128)
			(drill 0.508)
			(layers "*.Cu" "*.Mask")
			(remove_unused_layers no)
			(net "GND")
		)
		(pad "H1" thru_hole circle
			(at 0 9.800001 180)
			(size 0.8128 0.8128)
			(drill 0.508)
			(layers "*.Cu" "*.Mask")
			(remove_unused_layers no)
			(net "ETH10G_B2_TXN")
		)
		(pad "H2" thru_hole circle
			(at 2.000001 9.700001 180)
			(size 0.8128 0.8128)
			(drill 0.508)
			(layers "*.Cu" "*.Mask")
			(remove_unused_layers no)
			(net "BLADE_B2_EN1")
		)
		(pad "H3" thru_hole circle
			(at 4 9.800001 180)
			(size 0.8128 0.8128)
			(drill 0.508)
			(layers "*.Cu" "*.Mask")
			(remove_unused_layers no)
			(net "SERIAL_B2_TX1")
		)
		(pad "H4" thru_hole circle
			(at 6.000001 9.700001 180)
			(size 0.8128 0.8128)
			(drill 0.508)
			(layers "*.Cu" "*.Mask")
			(remove_unused_layers no)
			(net "SERIAL_B2_TX2")
		)
		(pad "H5" thru_hole circle
			(at 7.999999 9.800001 180)
			(size 0.8128 0.8128)
			(drill 0.508)
			(layers "*.Cu" "*.Mask")
			(remove_unused_layers no)
			(net "ETH40G_B2_PRES_N")
		)
		(pad "H6" thru_hole circle
			(at 10 9.700001 180)
			(size 0.8128 0.8128)
			(drill 0.508)
			(layers "*.Cu" "*.Mask")
			(remove_unused_layers no)
			(net "ETH40G_B2_TX0P")
		)
		(pad "I1" thru_hole circle
			(at 0 11.2 180)
			(size 0.8128 0.8128)
			(drill 0.508)
			(layers "*.Cu" "*.Mask")
			(remove_unused_layers no)
			(net "GND")
		)
		(pad "I2" thru_hole circle
			(at 2.000001 11.100001 180)
			(size 0.8128 0.8128)
			(drill 0.508)
			(layers "*.Cu" "*.Mask")
			(remove_unused_layers no)
			(net "ETH10G_B2_PRES_N")
		)
		(pad "I3" thru_hole circle
			(at 4 11.2 180)
			(size 0.8128 0.8128)
			(drill 0.508)
			(layers "*.Cu" "*.Mask")
			(remove_unused_layers no)
			(net "P3V3_B2_QSFP")
		)
		(pad "I4" thru_hole circle
			(at 6.000001 11.100001 180)
			(size 0.8128 0.8128)
			(drill 0.508)
			(layers "*.Cu" "*.Mask")
			(remove_unused_layers no)
			(net "SKU_B2_ID1")
		)
		(pad "I5" thru_hole circle
			(at 7.999999 11.2 180)
			(size 0.8128 0.8128)
			(drill 0.508)
			(layers "*.Cu" "*.Mask")
			(remove_unused_layers no)
			(net "BLADE_B2_MATED_N")
		)
		(pad "I6" thru_hole circle
			(at 10 11.100001 180)
			(size 0.8128 0.8128)
			(drill 0.508)
			(layers "*.Cu" "*.Mask")
			(remove_unused_layers no)
			(net "ETH40G_B2_TX0N")
		)
		(pad "J2" thru_hole circle
			(at 2.000001 12.5 180)
			(size 0.8128 0.8128)
			(drill 0.508)
			(layers "*.Cu" "*.Mask")
			(remove_unused_layers no)
			(net "GND")
		)
		(pad "J4" thru_hole circle
			(at 6.000001 12.5 180)
			(size 0.8128 0.8128)
			(drill 0.508)
			(layers "*.Cu" "*.Mask")
			(remove_unused_layers no)
			(net "GND")
		)
		(pad "J6" thru_hole circle
			(at 10 12.5 180)
			(size 0.8128 0.8128)
			(drill 0.508)
			(layers "*.Cu" "*.Mask")
			(remove_unused_layers no)
			(net "GND")
		)
	)
	(footprint ""
		(layer "F.Cu")
		(at -300.971801 4.635602 180)
		(property "Reference" "R25"
			(at 3.320199 0.025502 0)
			(unlocked yes)
			(layer "F.SilkS")
			(effects
				(font
					(size 0.762 0.5334)
					(thickness 0.1016)
				)
			)
		)
		(property "Value" ""
			(at 0 0 180)
			(layer "F.Fab")
			(effects
				(font
					(size 1.27 1.27)
				)
			)
		)
		(duplicate_pad_numbers_are_jumpers no)
		(fp_line
			(start 0 -0.381)
			(end 0 0.381)
			(stroke
				(width 0.127)
				(type default)
			)
			(layer "F.SilkS")
		)
		(fp_poly
			(pts
				(xy 1.255601 0.6564) (xy -1.255601 0.6564) (xy -1.255601 -0.656399) (xy 1.255601 -0.656399)
			)
			(stroke
				(width 0)
				(type default)
			)
			(fill no)
			(layer "F.CrtYd")
		)
		(fp_line
			(start 0.800001 0.4)
			(end 0.800001 -0.399999)
			(stroke
				(width 0.1)
				(type default)
			)
			(layer "F.Fab")
		)
		(fp_line
			(start 0.800001 -0.399999)
			(end -0.800001 -0.399999)
			(stroke
				(width 0.1)
				(type default)
			)
			(layer "F.Fab")
		)
		(fp_line
			(start -0.800001 0.4)
			(end 0.800001 0.4)
			(stroke
				(width 0.1)
				(type default)
			)
			(layer "F.Fab")
		)
		(fp_line
			(start -0.800001 -0.399999)
			(end -0.800001 0.4)
			(stroke
				(width 0.1)
				(type default)
			)
			(layer "F.Fab")
		)
		(pad "1" smd rect
			(at -0.650001 0 180)
			(size 0.7112 0.8128)
			(layers "F.Cu" "F.Mask" "F.Paste")
			(net "ETH10G_B1_RS1")
		)
		(pad "2" smd rect
			(at 0.650001 0)
			(size 0.7112 0.8128)
			(layers "F.Cu" "F.Mask" "F.Paste")
			(net "GND")
		)
	)
	(footprint ""
		(layer "F.Cu")
		(at -316.25 39.010001 180)
		(property "Reference" "J9"
			(at -8.27754 -8.708979 0)
			(unlocked yes)
			(layer "F.SilkS")
			(effects
				(font
					(size 0.762 0.5334)
					(thickness 0.1016)
				)
			)
		)
		(property "Value" ""
			(at 0 0 180)
			(layer "F.Fab")
			(effects
				(font
					(size 1.27 1.27)
				)
			)
		)
		(duplicate_pad_numbers_are_jumpers no)
		(fp_line
			(start 9.874999 50.85)
			(end 9.874999 34.000001)
			(stroke
				(width 0.127)
				(type default)
			)
			(layer "F.SilkS")
		)
		(fp_line
			(start 9.874999 25.000001)
			(end 9.874999 32)
			(stroke
				(width 0.127)
				(type default)
			)
			(layer "F.SilkS")
		)
		(fp_line
			(start 9.874999 16.000001)
			(end 9.874999 23)
			(stroke
				(width 0.127)
				(type default)
			)
			(layer "F.SilkS")
		)
		(fp_line
			(start 9.874999 7.000002)
			(end 9.874999 14)
			(stroke
				(width 0.127)
				(type default)
			)
			(layer "F.SilkS")
		)
		(fp_line
			(start 9.874999 -3.75)
			(end 9.874999 5)
			(stroke
				(width 0.127)
				(type default)
			)
			(layer "F.SilkS")
		)
		(fp_line
			(start -9.874999 50.85)
			(end 9.874999 50.85)
			(stroke
				(width 0.127)
				(type default)
			)
			(layer "F.SilkS")
		)
		(fp_line
			(start -9.874999 38.499999)
			(end -9.874999 50.85)
			(stroke
				(width 0.127)
				(type default)
			)
			(layer "F.SilkS")
		)
		(fp_line
			(start -9.874999 36.500001)
			(end -9.874999 29.5)
			(stroke
				(width 0.127)
				(type default)
			)
			(layer "F.SilkS")
		)
		(fp_line
			(start -9.874999 27.500001)
			(end -9.874999 20.5)
			(stroke
				(width 0.127)
				(type default)
			)
			(layer "F.SilkS")
		)
		(fp_line
			(start -9.874999 18.500001)
			(end -9.874999 11.5)
			(stroke
				(width 0.127)
				(type default)
			)
			(layer "F.SilkS")
		)
		(fp_line
			(start -9.874999 9.499999)
			(end -9.874999 0.750001)
			(stroke
				(width 0.127)
				(type default)
			)
			(layer "F.SilkS")
		)
		(fp_line
			(start -9.874999 -2.137999)
			(end -9.874999 -7.869999)
			(stroke
				(width 0.127)
				(type default)
			)
			(layer "F.SilkS")
		)
		(fp_line
			(start -9.874999 -7.869999)
			(end -6.074999 -7.869999)
			(stroke
				(width 0.127)
				(type default)
			)
			(layer "F.SilkS")
		)
		(fp_poly
			(pts
				(arc
					(start -4.199999 37.600001)
					(mid -9.703758 42.804115)
					(end -14.807001 37.2067)
				)
				(arc
					(start -14.807001 -0.1848)
					(mid -14.550292 -1.881885)
					(end -13.7654 -3.408299)
				)
				(arc
					(start -9.7682 -10.080899)
					(mid -7.846041 -12.229854)
					(end -5.084001 -13.056799)
				)
				(arc
					(start -5.0811 -13.056799)
					(mid -4.99375 -13.057419)
					(end -4.906401 -13.0566)
				)
				(arc
					(start 1.8942 -13.048599)
					(mid 3.117342 -12.977539)
					(end 4.291599 -12.627899)
				)
				(arc
					(start 10.9939 -9.842799)
					(mid 11.536623 -9.651121)
					(end 12.055399 -9.4018)
				)
				(arc
					(start 12.0555 -9.401701)
					(mid 14.088517 -7.41727)
					(end 14.8068 -4.668598)
				)
				(arc
					(start 14.8068 32.7031)
					(mid 10.110545 38.317137)
					(end 4.199999 34.000001)
				)
				(xy 4.199999 -2.5) (xy -4.199999 -2.5)
			)
			(stroke
				(width 0)
				(type default)
			)
			(fill no)
			(layer "B.CrtYd")
		)
		(fp_poly
			(pts
				(xy -10.875 51.850001)
				(arc
					(start -10.875 38.564599)
					(mid -11.270016 37.45)
					(end -10.875 36.335401)
				)
				(arc
					(start -10.875 29.5646)
					(mid -11.270017 28.450001)
					(end -10.875 27.335402)
				)
				(arc
					(start -10.875 20.5646)
					(mid -11.270017 19.449999)
					(end -10.875 18.335399)
				)
				(arc
					(start -10.875 11.5646)
					(mid -11.270016 10.45)
					(end -10.875 9.335399)
				)
				(arc
					(start -10.875 0.864601)
					(mid -11.270016 -0.249999)
					(end -10.875 -1.364599)
				)
				(xy -10.875 -8.87)
				(arc
					(start -6.370599 -8.87)
					(mid -5 -9.520011)
					(end -3.629401 -8.87)
				)
				(arc
					(start 0.829399 -8.87)
					(mid 2.2 -9.520014)
					(end 3.5706 -8.87)
				)
				(xy 10.875 -8.87)
				(arc
					(start 10.875 -5.864601)
					(mid 11.270017 -4.75)
					(end 10.875 -3.6354)
				)
				(arc
					(start 10.875 4.835401)
					(mid 11.270016 5.950001)
					(end 10.875 7.064601)
				)
				(arc
					(start 10.875 13.835401)
					(mid 11.270016 14.950001)
					(end 10.875 16.064601)
				)
				(arc
					(start 10.875 22.8354)
					(mid 11.270017 23.950001)
					(end 10.875 25.064601)
				)
				(arc
					(start 10.875 31.8354)
					(mid 11.270016 32.95)
					(end 10.875 34.064601)
				)
				(xy 10.875 51.850001)
			)
			(stroke
				(width 0)
				(type default)
			)
			(fill no)
			(layer "F.CrtYd")
		)
		(fp_line
			(start 9.874999 50.85)
			(end 9.874999 -7.869999)
			(stroke
				(width 0.1)
				(type default)
			)
			(layer "F.Fab")
		)
		(fp_line
			(start 9.874999 -7.869999)
			(end -9.874999 -7.869999)
			(stroke
				(width 0.1)
				(type default)
			)
			(layer "F.Fab")
		)
		(fp_line
			(start -9.874999 50.85)
			(end 9.874999 50.85)
			(stroke
				(width 0.1)
				(type default)
			)
			(layer "F.Fab")
		)
		(fp_line
			(start -9.874999 -7.869999)
			(end -9.874999 50.85)
			(stroke
				(width 0.1)
				(type default)
			)
			(layer "F.Fab")
		)
		(pad "1" thru_hole circle
			(at -9.499999 -0.25 270)
			(size 1.5494 1.5494)
			(drill 1.0414)
			(layers "*.Cu" "*.Mask")
			(remove_unused_layers no)
			(net "GND")
		)
		(pad "2" thru_hole circle
			(at -9.499999 10.449999 270)
			(size 1.5494 1.5494)
			(drill 1.0414)
			(layers "*.Cu" "*.Mask")
			(remove_unused_layers no)
			(net "GND")
		)
		(pad "3" thru_hole circle
			(at -9.499999 19.449999 270)
			(size 1.5494 1.5494)
			(drill 1.0414)
			(layers "*.Cu" "*.Mask")
			(remove_unused_layers no)
			(net "GND")
		)
		(pad "4" thru_hole circle
			(at -9.499999 28.449999 270)
			(size 1.5494 1.5494)
			(drill 1.0414)
			(layers "*.Cu" "*.Mask")
			(remove_unused_layers no)
			(net "GND")
		)
		(pad "5" thru_hole circle
			(at -9.499999 37.449999 270)
			(size 1.5494 1.5494)
			(drill 1.0414)
			(layers "*.Cu" "*.Mask")
			(remove_unused_layers no)
			(net "GND")
		)
		(pad "6" thru_hole circle
			(at -5 -7.75 270)
			(size 1.5494 1.5494)
			(drill 1.0414)
			(layers "*.Cu" "*.Mask")
			(remove_unused_layers no)
			(net "GND")
		)
		(pad "7" thru_hole circle
			(at 2.200001 -7.75 270)
			(size 1.5494 1.5494)
			(drill 1.0414)
			(layers "*.Cu" "*.Mask")
			(remove_unused_layers no)
			(net "GND")
		)
		(pad "8" thru_hole circle
			(at 9.499999 -4.750001 270)
			(size 1.5494 1.5494)
			(drill 1.0414)
			(layers "*.Cu" "*.Mask")
			(remove_unused_layers no)
			(net "GND")
		)
		(pad "9" thru_hole circle
			(at 9.499999 5.950001 270)
			(size 1.5494 1.5494)
			(drill 1.0414)
			(layers "*.Cu" "*.Mask")
			(remove_unused_layers no)
			(net "GND")
		)
		(pad "10" thru_hole circle
			(at 9.499999 14.950001 270)
			(size 1.5494 1.5494)
			(drill 1.0414)
			(layers "*.Cu" "*.Mask")
			(remove_unused_layers no)
			(net "GND")
		)
		(pad "11" thru_hole circle
			(at 9.499999 23.95 270)
			(size 1.5494 1.5494)
			(drill 1.0414)
			(layers "*.Cu" "*.Mask")
			(remove_unused_layers no)
			(net "GND")
		)
		(pad "12" thru_hole circle
			(at 9.499999 32.95 270)
			(size 1.5494 1.5494)
			(drill 1.0414)
			(layers "*.Cu" "*.Mask")
			(remove_unused_layers no)
			(net "GND")
		)
	)
	(footprint ""
		(layer "F.Cu")
		(at -115.423 4.9276 -90)
		(property "Reference" "R37"
			(at 1.84404 -1.1611 90)
			(unlocked yes)
			(layer "F.SilkS")
			(effects
				(font
					(size 0.762 0.5334)
					(thickness 0.1016)
				)
			)
		)
		(property "Value" ""
			(at 0 0 270)
			(layer "F.Fab")
			(effects
				(font
					(size 1.27 1.27)
				)
			)
		)
		(duplicate_pad_numbers_are_jumpers no)
		(fp_line
			(start 0 -0.381)
			(end 0 0.381)
			(stroke
				(width 0.127)
				(type default)
			)
			(layer "F.SilkS")
		)
		(fp_poly
			(pts
				(xy 1.255601 0.6564) (xy -1.255601 0.6564) (xy -1.255601 -0.656399) (xy 1.255601 -0.656399)
			)
			(stroke
				(width 0)
				(type default)
			)
			(fill no)
			(layer "F.CrtYd")
		)
		(fp_line
			(start -0.800001 0.399999)
			(end 0.800001 0.399999)
			(stroke
				(width 0.1)
				(type default)
			)
			(layer "F.Fab")
		)
		(fp_line
			(start 0.800001 0.399999)
			(end 0.800001 -0.399999)
			(stroke
				(width 0.1)
				(type default)
			)
			(layer "F.Fab")
		)
		(fp_line
			(start -0.800001 -0.399999)
			(end -0.800001 0.399999)
			(stroke
				(width 0.1)
				(type default)
			)
			(layer "F.Fab")
		)
		(fp_line
			(start 0.800001 -0.399999)
			(end -0.800001 -0.399999)
			(stroke
				(width 0.1)
				(type default)
			)
			(layer "F.Fab")
		)
		(pad "1" smd rect
			(at -0.650001 0 270)
			(size 0.7112 0.8128)
			(layers "F.Cu" "F.Mask" "F.Paste")
			(net "UNNAMED_6_1X2HDR_I52_IO")
		)
		(pad "2" smd rect
			(at 0.650001 0 90)
			(size 0.7112 0.8128)
			(layers "F.Cu" "F.Mask" "F.Paste")
			(net "GND")
		)
	)
	(footprint ""
		(layer "F.Cu")
		(at -331.47 13.2588)
		(property "Reference" "R76"
			(at 3.175 -0.0127 0)
			(unlocked yes)
			(layer "F.SilkS")
			(effects
				(font
					(size 0.762 0.5334)
					(thickness 0.1016)
				)
			)
		)
		(property "Value" ""
			(at 0 0 0)
			(layer "F.Fab")
			(effects
				(font
					(size 1.27 1.27)
				)
			)
		)
		(duplicate_pad_numbers_are_jumpers no)
		(fp_line
			(start 0 -0.381)
			(end 0 0.381)
			(stroke
				(width 0.127)
				(type default)
			)
			(layer "F.SilkS")
		)
		(fp_poly
			(pts
				(xy 1.255601 0.6564) (xy -1.255601 0.6564) (xy -1.255601 -0.656399) (xy 1.255601 -0.656399)
			)
			(stroke
				(width 0)
				(type default)
			)
			(fill no)
			(layer "F.CrtYd")
		)
		(fp_line
			(start -0.800001 -0.399999)
			(end -0.800001 0.399999)
			(stroke
				(width 0.1)
				(type default)
			)
			(layer "F.Fab")
		)
		(fp_line
			(start -0.800001 0.399999)
			(end 0.800001 0.399999)
			(stroke
				(width 0.1)
				(type default)
			)
			(layer "F.Fab")
		)
		(fp_line
			(start 0.800001 -0.399999)
			(end -0.800001 -0.399999)
			(stroke
				(width 0.1)
				(type default)
			)
			(layer "F.Fab")
		)
		(fp_line
			(start 0.800001 0.399999)
			(end 0.800001 -0.399999)
			(stroke
				(width 0.1)
				(type default)
			)
			(layer "F.Fab")
		)
		(pad "1" smd rect
			(at -0.650001 0)
			(size 0.7112 0.8128)
			(layers "F.Cu" "F.Mask" "F.Paste")
			(net "P3V3_B1_QSFP")
		)
		(pad "2" smd rect
			(at 0.650001 0 180)
			(size 0.7112 0.8128)
			(layers "F.Cu" "F.Mask" "F.Paste")
			(net "ETH40G_B1_MODSEL_N")
		)
	)
	(footprint ""
		(layer "F.Cu")
		(at -418.06 42.660001)
		(property "Reference" "MH1"
			(at 0.0522 -4.725101 0)
			(unlocked yes)
			(layer "F.SilkS")
			(effects
				(font
					(size 0.762 0.5334)
					(thickness 0.1016)
				)
			)
		)
		(property "Value" ""
			(at 0 0 0)
			(layer "F.Fab")
			(effects
				(font
					(size 1.27 1.27)
				)
			)
		)
		(duplicate_pad_numbers_are_jumpers no)
		(fp_poly
			(pts
				(arc
					(start 4.0132 0)
					(mid -4.0132 0)
					(end 4.0132 0)
				)
			)
			(stroke
				(width 0)
				(type default)
			)
			(fill no)
			(layer "B.CrtYd")
		)
		(fp_poly
			(pts
				(arc
					(start 4.0132 0)
					(mid -4.0132 0)
					(end 4.0132 0)
				)
			)
			(stroke
				(width 0)
				(type default)
			)
			(fill no)
			(layer "F.CrtYd")
		)
		(pad "1" thru_hole circle
			(at 0 0)
			(size 7.0104 7.0104)
			(drill 3.5052)
			(layers "*.Cu" "*.Mask")
			(remove_unused_layers no)
			(net "GND")
			(padstack
				(mode front_inner_back)
				(layer "Inner"
					(shape circle)
					(size 4.5212 4.5212)
				)
				(layer "B.Cu"
					(shape circle)
					(size 7.0104 7.0104)
				)
			)
		)
		(pad "2" thru_hole circle
			(at 0 -2.794)
			(size 0.6604 0.6604)
			(drill 0.3556)
			(layers "*.Cu" "*.Mask")
			(remove_unused_layers no)
			(net "GND")
		)
		(pad "3" thru_hole circle
			(at -1.905 -2.032)
			(size 0.6604 0.6604)
			(drill 0.3556)
			(layers "*.Cu" "*.Mask")
			(remove_unused_layers no)
			(net "GND")
		)
		(pad "4" thru_hole circle
			(at -2.794 0)
			(size 0.6604 0.6604)
			(drill 0.3556)
			(layers "*.Cu" "*.Mask")
			(remove_unused_layers no)
			(net "GND")
		)
		(pad "5" thru_hole circle
			(at -2.032 1.905)
			(size 0.6604 0.6604)
			(drill 0.3556)
			(layers "*.Cu" "*.Mask")
			(remove_unused_layers no)
			(net "GND")
		)
		(pad "6" thru_hole circle
			(at 0 2.794)
			(size 0.6604 0.6604)
			(drill 0.3556)
			(layers "*.Cu" "*.Mask")
			(remove_unused_layers no)
			(net "GND")
		)
		(pad "7" thru_hole circle
			(at 2.032 1.905)
			(size 0.6604 0.6604)
			(drill 0.3556)
			(layers "*.Cu" "*.Mask")
			(remove_unused_layers no)
			(net "GND")
		)
		(pad "8" thru_hole circle
			(at 2.794 0)
			(size 0.6604 0.6604)
			(drill 0.3556)
			(layers "*.Cu" "*.Mask")
			(remove_unused_layers no)
			(net "GND")
		)
		(pad "9" thru_hole circle
			(at 1.905 -2.032)
			(size 0.6604 0.6604)
			(drill 0.3556)
			(layers "*.Cu" "*.Mask")
			(remove_unused_layers no)
			(net "GND")
		)
	)
	(footprint ""
		(layer "F.Cu")
		(at -386.773001 39.357399)
		(property "Reference" "MH2"
			(at 0 -4.9149 0)
			(unlocked yes)
			(layer "F.SilkS")
			(effects
				(font
					(size 0.762 0.5334)
					(thickness 0.1016)
				)
			)
		)
		(property "Value" ""
			(at 0 0 0)
			(layer "F.Fab")
			(effects
				(font
					(size 1.27 1.27)
				)
			)
		)
		(duplicate_pad_numbers_are_jumpers no)
		(fp_poly
			(pts
				(arc
					(start 4.0132 0)
					(mid -4.0132 0)
					(end 4.0132 0)
				)
			)
			(stroke
				(width 0)
				(type default)
			)
			(fill no)
			(layer "B.CrtYd")
		)
		(fp_poly
			(pts
				(arc
					(start 4.0132 0)
					(mid -4.0132 0)
					(end 4.0132 0)
				)
			)
			(stroke
				(width 0)
				(type default)
			)
			(fill no)
			(layer "F.CrtYd")
		)
		(pad "1" thru_hole circle
			(at 0 0)
			(size 7.0104 7.0104)
			(drill 3.5052)
			(layers "*.Cu" "*.Mask")
			(remove_unused_layers no)
			(net "GND")
			(padstack
				(mode front_inner_back)
				(layer "Inner"
					(shape circle)
					(size 4.5212 4.5212)
				)
				(layer "B.Cu"
					(shape circle)
					(size 7.0104 7.0104)
				)
			)
		)
		(pad "2" thru_hole circle
			(at 0 -2.794)
			(size 0.6604 0.6604)
			(drill 0.3556)
			(layers "*.Cu" "*.Mask")
			(remove_unused_layers no)
			(net "GND")
		)
		(pad "3" thru_hole circle
			(at -1.905 -2.032)
			(size 0.6604 0.6604)
			(drill 0.3556)
			(layers "*.Cu" "*.Mask")
			(remove_unused_layers no)
			(net "GND")
		)
		(pad "4" thru_hole circle
			(at -2.794 0)
			(size 0.6604 0.6604)
			(drill 0.3556)
			(layers "*.Cu" "*.Mask")
			(remove_unused_layers no)
			(net "GND")
		)
		(pad "5" thru_hole circle
			(at -2.032 1.905)
			(size 0.6604 0.6604)
			(drill 0.3556)
			(layers "*.Cu" "*.Mask")
			(remove_unused_layers no)
			(net "GND")
		)
		(pad "6" thru_hole circle
			(at 0 2.794)
			(size 0.6604 0.6604)
			(drill 0.3556)
			(layers "*.Cu" "*.Mask")
			(remove_unused_layers no)
			(net "GND")
		)
		(pad "7" thru_hole circle
			(at 2.032 1.905)
			(size 0.6604 0.6604)
			(drill 0.3556)
			(layers "*.Cu" "*.Mask")
			(remove_unused_layers no)
			(net "GND")
		)
		(pad "8" thru_hole circle
			(at 2.794 0)
			(size 0.6604 0.6604)
			(drill 0.3556)
			(layers "*.Cu" "*.Mask")
			(remove_unused_layers no)
			(net "GND")
		)
		(pad "9" thru_hole circle
			(at 1.905 -2.032)
			(size 0.6604 0.6604)
			(drill 0.3556)
			(layers "*.Cu" "*.Mask")
			(remove_unused_layers no)
			(net "GND")
		)
	)
	(footprint ""
		(layer "F.Cu")
		(at -58.610401 44.488202)
		(property "Reference" "C10"
			(at 2.603401 -0.000102 0)
			(unlocked yes)
			(layer "F.SilkS")
			(effects
				(font
					(size 0.762 0.5334)
					(thickness 0.1016)
				)
			)
		)
		(property "Value" ""
			(at 0 0 0)
			(layer "F.Fab")
			(effects
				(font
					(size 1.27 1.27)
				)
			)
		)
		(duplicate_pad_numbers_are_jumpers no)
		(fp_poly
			(pts
				(xy -0.999299 0.503999) (xy -0.999299 -0.504) (xy 0.9993 -0.504) (xy 0.9993 0.503999)
			)
			(stroke
				(width 0)
				(type default)
			)
			(fill no)
			(layer "F.CrtYd")
		)
		(fp_line
			(start -0.499999 -0.25)
			(end 0.499999 -0.25)
			(stroke
				(width 0.1)
				(type default)
			)
			(layer "F.Fab")
		)
		(fp_line
			(start -0.499999 0.249999)
			(end -0.499999 -0.25)
			(stroke
				(width 0.1)
				(type default)
			)
			(layer "F.Fab")
		)
		(fp_line
			(start 0.499999 -0.25)
			(end 0.499999 0.249999)
			(stroke
				(width 0.1)
				(type default)
			)
			(layer "F.Fab")
		)
		(fp_line
			(start 0.499999 0.249999)
			(end -0.499999 0.249999)
			(stroke
				(width 0.1)
				(type default)
			)
			(layer "F.Fab")
		)
		(pad "1" smd rect
			(at -0.4572 0 90)
			(size 0.508 0.5842)
			(layers "F.Cu" "F.Mask" "F.Paste")
			(net "P3V3_10G_B2_VCCT")
		)
		(pad "2" smd rect
			(at 0.4572 0 90)
			(size 0.508 0.5842)
			(layers "F.Cu" "F.Mask" "F.Paste")
			(net "GND")
		)
	)
	(footprint ""
		(layer "F.Cu")
		(at -19.9136 44.196 -90)
		(property "Reference" "R71"
			(at 0.254 -2.0447 90)
			(unlocked yes)
			(layer "F.SilkS")
			(effects
				(font
					(size 0.762 0.5334)
					(thickness 0.1016)
				)
			)
		)
		(property "Value" ""
			(at 0 0 270)
			(layer "F.Fab")
			(effects
				(font
					(size 1.27 1.27)
				)
			)
		)
		(duplicate_pad_numbers_are_jumpers no)
		(fp_line
			(start 0 -0.381)
			(end 0 0.381)
			(stroke
				(width 0.127)
				(type default)
			)
			(layer "F.SilkS")
		)
		(fp_poly
			(pts
				(xy 1.255601 0.6564) (xy -1.255601 0.6564) (xy -1.255601 -0.656399) (xy 1.255601 -0.656399)
			)
			(stroke
				(width 0)
				(type default)
			)
			(fill no)
			(layer "F.CrtYd")
		)
		(fp_line
			(start -0.800001 0.399999)
			(end 0.800001 0.399999)
			(stroke
				(width 0.1)
				(type default)
			)
			(layer "F.Fab")
		)
		(fp_line
			(start 0.800001 0.399999)
			(end 0.800001 -0.399999)
			(stroke
				(width 0.1)
				(type default)
			)
			(layer "F.Fab")
		)
		(fp_line
			(start -0.800001 -0.399999)
			(end -0.800001 0.399999)
			(stroke
				(width 0.1)
				(type default)
			)
			(layer "F.Fab")
		)
		(fp_line
			(start 0.800001 -0.399999)
			(end -0.800001 -0.399999)
			(stroke
				(width 0.1)
				(type default)
			)
			(layer "F.Fab")
		)
		(pad "1" smd rect
			(at -0.650001 0 270)
			(size 0.7112 0.8128)
			(layers "F.Cu" "F.Mask" "F.Paste")
			(net "GND")
		)
		(pad "2" smd rect
			(at 0.650001 0 90)
			(size 0.7112 0.8128)
			(layers "F.Cu" "F.Mask" "F.Paste")
			(net "JBOD_B2_MATED_N")
		)
	)
	(footprint ""
		(layer "F.Cu")
		(at -331.47 14.6558)
		(property "Reference" "R82"
			(at 3.175 0.1143 0)
			(unlocked yes)
			(layer "F.SilkS")
			(effects
				(font
					(size 0.762 0.5334)
					(thickness 0.1016)
				)
			)
		)
		(property "Value" ""
			(at 0 0 0)
			(layer "F.Fab")
			(effects
				(font
					(size 1.27 1.27)
				)
			)
		)
		(duplicate_pad_numbers_are_jumpers no)
		(fp_line
			(start 0 -0.381)
			(end 0 0.381)
			(stroke
				(width 0.127)
				(type default)
			)
			(layer "F.SilkS")
		)
		(fp_poly
			(pts
				(xy 1.255601 0.6564) (xy -1.255601 0.6564) (xy -1.255601 -0.656399) (xy 1.255601 -0.656399)
			)
			(stroke
				(width 0)
				(type default)
			)
			(fill no)
			(layer "F.CrtYd")
		)
		(fp_line
			(start -0.800001 -0.399999)
			(end -0.800001 0.399999)
			(stroke
				(width 0.1)
				(type default)
			)
			(layer "F.Fab")
		)
		(fp_line
			(start -0.800001 0.399999)
			(end 0.800001 0.399999)
			(stroke
				(width 0.1)
				(type default)
			)
			(layer "F.Fab")
		)
		(fp_line
			(start 0.800001 -0.399999)
			(end -0.800001 -0.399999)
			(stroke
				(width 0.1)
				(type default)
			)
			(layer "F.Fab")
		)
		(fp_line
			(start 0.800001 0.399999)
			(end 0.800001 -0.399999)
			(stroke
				(width 0.1)
				(type default)
			)
			(layer "F.Fab")
		)
		(pad "1" smd rect
			(at -0.650001 0)
			(size 0.7112 0.8128)
			(layers "F.Cu" "F.Mask" "F.Paste")
			(net "P3V3_B1_QSFP")
		)
		(pad "2" smd rect
			(at 0.650001 0 180)
			(size 0.7112 0.8128)
			(layers "F.Cu" "F.Mask" "F.Paste")
			(net "ETH40G_B1_SCL")
		)
	)
	(footprint ""
		(layer "F.Cu")
		(at -201.607001 41.110002 90)
		(property "Reference" "U3"
			(at 9.194902 0.439001 0)
			(unlocked yes)
			(layer "F.SilkS")
			(effects
				(font
					(size 0.762 0.5334)
					(thickness 0.1016)
				)
			)
		)
		(property "Value" ""
			(at 0 0 90)
			(layer "F.Fab")
			(effects
				(font
					(size 1.27 1.27)
				)
			)
		)
		(duplicate_pad_numbers_are_jumpers no)
		(fp_line
			(start 8 -1.749999)
			(end 6.5 -1.749999)
			(stroke
				(width 0.127)
				(type default)
			)
			(layer "F.SilkS")
		)
		(fp_line
			(start -0.499999 -1.749999)
			(end -2.000001 -1.749999)
			(stroke
				(width 0.127)
				(type default)
			)
			(layer "F.SilkS")
		)
		(fp_line
			(start -2.000001 -1.749999)
			(end -2.000001 -0.249999)
			(stroke
				(width 0.127)
				(type default)
			)
			(layer "F.SilkS")
		)
		(fp_line
			(start 8 -0.249999)
			(end 8 -1.749999)
			(stroke
				(width 0.127)
				(type default)
			)
			(layer "F.SilkS")
		)
		(fp_line
			(start -2.000001 1.45)
			(end -2.000001 2.949999)
			(stroke
				(width 0.127)
				(type default)
			)
			(layer "F.SilkS")
		)
		(fp_line
			(start 8 2.949999)
			(end 8 1.45)
			(stroke
				(width 0.127)
				(type default)
			)
			(layer "F.SilkS")
		)
		(fp_line
			(start 6.5 2.949999)
			(end 8 2.949999)
			(stroke
				(width 0.127)
				(type default)
			)
			(layer "F.SilkS")
		)
		(fp_line
			(start -2.000001 2.949999)
			(end -0.499999 2.949999)
			(stroke
				(width 0.127)
				(type default)
			)
			(layer "F.SilkS")
		)
		(fp_poly
			(pts
				(arc
					(start 6.000001 -5.21)
					(mid 11.210001 0)
					(end 6.000001 5.21)
				)
				(arc
					(start 0 5.21)
					(mid -5.21 0)
					(end 0 -5.21)
				)
			)
			(stroke
				(width 0)
				(type default)
			)
			(fill no)
			(layer "B.CrtYd")
		)
		(fp_poly
			(pts
				(xy -2.5 -2.25) (xy 8.500001 -2.25) (xy 8.500001 3.450001) (xy -2.5 3.450001)
			)
			(stroke
				(width 0)
				(type default)
			)
			(fill no)
			(layer "F.CrtYd")
		)
		(fp_line
			(start 8 -1.749999)
			(end -2.000001 -1.749999)
			(stroke
				(width 0.1)
				(type default)
			)
			(layer "F.Fab")
		)
		(fp_line
			(start -2.000001 -1.749999)
			(end -2.000001 2.949999)
			(stroke
				(width 0.1)
				(type default)
			)
			(layer "F.Fab")
		)
		(fp_line
			(start 8 2.949999)
			(end 8 -1.749999)
			(stroke
				(width 0.1)
				(type default)
			)
			(layer "F.Fab")
		)
		(fp_line
			(start -2.000001 2.949999)
			(end 8 2.949999)
			(stroke
				(width 0.1)
				(type default)
			)
			(layer "F.Fab")
		)
		(fp_text user "4"
			(at 6.019902 -2.735999 0)
			(unlocked yes)
			(layer "F.SilkS")
			(effects
				(font
					(size 0.762 0.5334)
					(thickness 0.1016)
				)
			)
		)
		(fp_text user "*"
			(at 0 -2.371451 90)
			(unlocked yes)
			(layer "F.SilkS")
			(effects
				(font
					(size 0.381 0.381)
					(thickness 0.381)
				)
			)
		)
		(fp_text user "*"
			(at 0 -1.47145 90)
			(unlocked yes)
			(layer "B.SilkS")
			(effects
				(font
					(size 0.381 0.381)
					(thickness 0.381)
				)
				(justify mirror)
			)
		)
		(fp_text user "4"
			(at 5.892902 -1.465999 0)
			(unlocked yes)
			(layer "B.SilkS")
			(effects
				(font
					(size 0.762 0.5334)
					(thickness 0.1016)
				)
				(justify mirror)
			)
		)
		(pad "1" thru_hole circle
			(at 0 0 90)
			(size 1.3716 1.3716)
			(drill 1.016)
			(layers "*.Cu" "*.Mask")
			(remove_unused_layers no)
			(net "P5V_USB_B2")
		)
		(pad "2" thru_hole circle
			(at 2.000001 0 90)
			(size 1.3716 1.3716)
			(drill 1.016)
			(layers "*.Cu" "*.Mask")
			(remove_unused_layers no)
			(net "USB_B2_N")
		)
		(pad "3" thru_hole circle
			(at 4 0 90)
			(size 1.3716 1.3716)
			(drill 1.016)
			(layers "*.Cu" "*.Mask")
			(remove_unused_layers no)
			(net "USB_B2_P")
		)
		(pad "4" thru_hole circle
			(at 6.000001 0 90)
			(size 1.3716 1.3716)
			(drill 1.016)
			(layers "*.Cu" "*.Mask")
			(remove_unused_layers no)
			(net "GND")
		)
	)
	(footprint ""
		(layer "F.Cu")
		(at -353.3902 34.29 90)
		(property "Reference" "C3"
			(at -2.032 -0.0889 90)
			(unlocked yes)
			(layer "F.SilkS")
			(effects
				(font
					(size 0.762 0.5334)
					(thickness 0.1016)
				)
			)
		)
		(property "Value" ""
			(at 0 0 90)
			(layer "F.Fab")
			(effects
				(font
					(size 1.27 1.27)
				)
			)
		)
		(duplicate_pad_numbers_are_jumpers no)
		(fp_poly
			(pts
				(xy -0.9993 0.503999) (xy -0.9993 -0.504) (xy 0.999299 -0.504) (xy 0.999299 0.503999)
			)
			(stroke
				(width 0)
				(type default)
			)
			(fill no)
			(layer "F.CrtYd")
		)
		(fp_line
			(start 0.499999 -0.25)
			(end 0.499999 0.249999)
			(stroke
				(width 0.1)
				(type default)
			)
			(layer "F.Fab")
		)
		(fp_line
			(start -0.499999 -0.25)
			(end 0.499999 -0.25)
			(stroke
				(width 0.1)
				(type default)
			)
			(layer "F.Fab")
		)
		(fp_line
			(start 0.499999 0.249999)
			(end -0.499999 0.249999)
			(stroke
				(width 0.1)
				(type default)
			)
			(layer "F.Fab")
		)
		(fp_line
			(start -0.499999 0.249999)
			(end -0.499999 -0.25)
			(stroke
				(width 0.1)
				(type default)
			)
			(layer "F.Fab")
		)
		(pad "1" smd rect
			(at -0.4572 0 180)
			(size 0.508 0.5842)
			(layers "F.Cu" "F.Mask" "F.Paste")
			(net "P12V")
		)
		(pad "2" smd rect
			(at 0.4572 0 180)
			(size 0.508 0.5842)
			(layers "F.Cu" "F.Mask" "F.Paste")
			(net "GND")
		)
	)
	(footprint ""
		(layer "F.Cu")
		(at -80.098798 3.461601)
		(property "Reference" "R55"
			(at -3.213202 -0.121501 0)
			(unlocked yes)
			(layer "F.SilkS")
			(effects
				(font
					(size 0.762 0.5334)
					(thickness 0.1016)
				)
			)
		)
		(property "Value" ""
			(at 0 0 0)
			(layer "F.Fab")
			(effects
				(font
					(size 1.27 1.27)
				)
			)
		)
		(duplicate_pad_numbers_are_jumpers no)
		(fp_line
			(start 0 -0.381)
			(end 0 0.381)
			(stroke
				(width 0.127)
				(type default)
			)
			(layer "F.SilkS")
		)
		(fp_poly
			(pts
				(xy 1.2556 0.656399) (xy -1.255601 0.656399) (xy -1.255601 -0.6564) (xy 1.2556 -0.6564)
			)
			(stroke
				(width 0)
				(type default)
			)
			(fill no)
			(layer "F.CrtYd")
		)
		(fp_line
			(start -0.800001 -0.399999)
			(end -0.800001 0.399999)
			(stroke
				(width 0.1)
				(type default)
			)
			(layer "F.Fab")
		)
		(fp_line
			(start -0.800001 0.399999)
			(end 0.800001 0.399999)
			(stroke
				(width 0.1)
				(type default)
			)
			(layer "F.Fab")
		)
		(fp_line
			(start 0.800001 -0.399999)
			(end -0.800001 -0.399999)
			(stroke
				(width 0.1)
				(type default)
			)
			(layer "F.Fab")
		)
		(fp_line
			(start 0.800001 0.399999)
			(end 0.800001 -0.399999)
			(stroke
				(width 0.1)
				(type default)
			)
			(layer "F.Fab")
		)
		(pad "1" smd rect
			(at -0.650001 0)
			(size 0.7112 0.8128)
			(layers "F.Cu" "F.Mask" "F.Paste")
			(net "P3V3_B2_QSFP")
		)
		(pad "2" smd rect
			(at 0.650001 0 180)
			(size 0.7112 0.8128)
			(layers "F.Cu" "F.Mask" "F.Paste")
			(net "ETH10G_B2_RX_LOS")
		)
	)
	(footprint ""
		(layer "F.Cu")
		(at -331.47 9.0678)
		(property "Reference" "R78"
			(at 3.175 0.1143 0)
			(unlocked yes)
			(layer "F.SilkS")
			(effects
				(font
					(size 0.762 0.5334)
					(thickness 0.1016)
				)
			)
		)
		(property "Value" ""
			(at 0 0 0)
			(layer "F.Fab")
			(effects
				(font
					(size 1.27 1.27)
				)
			)
		)
		(duplicate_pad_numbers_are_jumpers no)
		(fp_line
			(start 0 -0.381)
			(end 0 0.381)
			(stroke
				(width 0.127)
				(type default)
			)
			(layer "F.SilkS")
		)
		(fp_poly
			(pts
				(xy 1.255601 0.6564) (xy -1.255601 0.6564) (xy -1.255601 -0.656399) (xy 1.255601 -0.656399)
			)
			(stroke
				(width 0)
				(type default)
			)
			(fill no)
			(layer "F.CrtYd")
		)
		(fp_line
			(start -0.800001 -0.399999)
			(end -0.800001 0.399999)
			(stroke
				(width 0.1)
				(type default)
			)
			(layer "F.Fab")
		)
		(fp_line
			(start -0.800001 0.399999)
			(end 0.800001 0.399999)
			(stroke
				(width 0.1)
				(type default)
			)
			(layer "F.Fab")
		)
		(fp_line
			(start 0.800001 -0.399999)
			(end -0.800001 -0.399999)
			(stroke
				(width 0.1)
				(type default)
			)
			(layer "F.Fab")
		)
		(fp_line
			(start 0.800001 0.399999)
			(end 0.800001 -0.399999)
			(stroke
				(width 0.1)
				(type default)
			)
			(layer "F.Fab")
		)
		(pad "1" smd rect
			(at -0.650001 0)
			(size 0.7112 0.8128)
			(layers "F.Cu" "F.Mask" "F.Paste")
			(net "P3V3_B1_QSFP")
		)
		(pad "2" smd rect
			(at 0.650001 0 180)
			(size 0.7112 0.8128)
			(layers "F.Cu" "F.Mask" "F.Paste")
			(net "ETH40G_B1_INT_N")
		)
	)
	(footprint ""
		(layer "F.Cu")
		(at -418.846 30.861 90)
		(property "Reference" "U2"
			(at 3.1369 4.318 0)
			(unlocked yes)
			(layer "F.SilkS")
			(effects
				(font
					(size 0.762 0.5334)
					(thickness 0.1016)
				)
			)
		)
		(property "Value" ""
			(at 0 0 90)
			(layer "F.Fab")
			(effects
				(font
					(size 1.27 1.27)
				)
			)
		)
		(duplicate_pad_numbers_are_jumpers no)
		(fp_line
			(start 7.999999 -1.749999)
			(end 6.5 -1.749999)
			(stroke
				(width 0.127)
				(type default)
			)
			(layer "F.SilkS")
		)
		(fp_line
			(start -0.499999 -1.749999)
			(end -2.000001 -1.749999)
			(stroke
				(width 0.127)
				(type default)
			)
			(layer "F.SilkS")
		)
		(fp_line
			(start -2.000001 -1.749999)
			(end -2.000001 -0.25)
			(stroke
				(width 0.127)
				(type default)
			)
			(layer "F.SilkS")
		)
		(fp_line
			(start 7.999999 -0.25)
			(end 7.999999 -1.749999)
			(stroke
				(width 0.127)
				(type default)
			)
			(layer "F.SilkS")
		)
		(fp_line
			(start -2.000001 1.45)
			(end -2.000001 2.949999)
			(stroke
				(width 0.127)
				(type default)
			)
			(layer "F.SilkS")
		)
		(fp_line
			(start 7.999999 2.949999)
			(end 7.999999 1.45)
			(stroke
				(width 0.127)
				(type default)
			)
			(layer "F.SilkS")
		)
		(fp_line
			(start 6.5 2.949999)
			(end 7.999999 2.949999)
			(stroke
				(width 0.127)
				(type default)
			)
			(layer "F.SilkS")
		)
		(fp_line
			(start -2.000001 2.949999)
			(end -0.499999 2.949999)
			(stroke
				(width 0.127)
				(type default)
			)
			(layer "F.SilkS")
		)
		(fp_poly
			(pts
				(arc
					(start 6.000001 -5.21)
					(mid 11.210001 0)
					(end 6.000001 5.21)
				)
				(arc
					(start 0 5.21)
					(mid -5.21 0)
					(end 0 -5.21)
				)
			)
			(stroke
				(width 0)
				(type default)
			)
			(fill no)
			(layer "B.CrtYd")
		)
		(fp_poly
			(pts
				(xy -2.5 -2.250001) (xy 8.500001 -2.250001) (xy 8.500001 3.450001) (xy -2.5 3.450001)
			)
			(stroke
				(width 0)
				(type default)
			)
			(fill no)
			(layer "F.CrtYd")
		)
		(fp_line
			(start 7.999999 -1.749999)
			(end -2.000001 -1.749999)
			(stroke
				(width 0.1)
				(type default)
			)
			(layer "F.Fab")
		)
		(fp_line
			(start -2.000001 -1.749999)
			(end -2.000001 2.949999)
			(stroke
				(width 0.1)
				(type default)
			)
			(layer "F.Fab")
		)
		(fp_line
			(start 7.999999 2.949999)
			(end 7.999999 -1.749999)
			(stroke
				(width 0.1)
				(type default)
			)
			(layer "F.Fab")
		)
		(fp_line
			(start -2.000001 2.949999)
			(end 7.999999 2.949999)
			(stroke
				(width 0.1)
				(type default)
			)
			(layer "F.Fab")
		)
		(fp_text user "4"
			(at 5.638902 -2.481999 0)
			(unlocked yes)
			(layer "F.SilkS")
			(effects
				(font
					(size 0.762 0.5334)
					(thickness 0.1016)
				)
			)
		)
		(fp_text user "*"
			(at 0 -2.371451 90)
			(unlocked yes)
			(layer "F.SilkS")
			(effects
				(font
					(size 0.381 0.381)
					(thickness 0.381)
				)
			)
		)
		(fp_text user "4"
			(at 6.146902 -1.592999 0)
			(unlocked yes)
			(layer "B.SilkS")
			(effects
				(font
					(size 0.762 0.5334)
					(thickness 0.1016)
				)
				(justify mirror)
			)
		)
		(fp_text user "*"
			(at 0 -1.47145 90)
			(unlocked yes)
			(layer "B.SilkS")
			(effects
				(font
					(size 0.381 0.381)
					(thickness 0.381)
				)
				(justify mirror)
			)
		)
		(pad "1" thru_hole circle
			(at 0 0 90)
			(size 1.3716 1.3716)
			(drill 1.016)
			(layers "*.Cu" "*.Mask")
			(remove_unused_layers no)
			(net "P5V_USB_B1")
		)
		(pad "2" thru_hole circle
			(at 2.000001 0 90)
			(size 1.3716 1.3716)
			(drill 1.016)
			(layers "*.Cu" "*.Mask")
			(remove_unused_layers no)
			(net "USB_B1_N")
		)
		(pad "3" thru_hole circle
			(at 4 0 90)
			(size 1.3716 1.3716)
			(drill 1.016)
			(layers "*.Cu" "*.Mask")
			(remove_unused_layers no)
			(net "USB_B1_P")
		)
		(pad "4" thru_hole circle
			(at 6.000001 0 90)
			(size 1.3716 1.3716)
			(drill 1.016)
			(layers "*.Cu" "*.Mask")
			(remove_unused_layers no)
			(net "GND")
		)
	)
	(footprint ""
		(layer "F.Cu")
		(at -65.9638 45.72)
		(property "Reference" "FS3"
			(at 0.0508 1.0541 0)
			(unlocked yes)
			(layer "F.SilkS")
			(effects
				(font
					(size 0.762 0.5334)
					(thickness 0.1016)
				)
			)
		)
		(property "Value" ""
			(at 0 0 0)
			(layer "F.Fab")
			(effects
				(font
					(size 1.27 1.27)
				)
			)
		)
		(duplicate_pad_numbers_are_jumpers no)
		(fp_poly
			(pts
				(xy -1.002101 0.504) (xy -1.002101 -0.503999) (xy 1.002101 -0.503999) (xy 1.002101 0.504)
			)
			(stroke
				(width 0)
				(type default)
			)
			(fill no)
			(layer "F.CrtYd")
		)
		(fp_line
			(start -0.499999 -0.249999)
			(end -0.499999 0.25)
			(stroke
				(width 0.1)
				(type default)
			)
			(layer "F.Fab")
		)
		(fp_line
			(start -0.499999 0.25)
			(end 0.499999 0.25)
			(stroke
				(width 0.1)
				(type default)
			)
			(layer "F.Fab")
		)
		(fp_line
			(start 0.499999 -0.249999)
			(end -0.499999 -0.249999)
			(stroke
				(width 0.1)
				(type default)
			)
			(layer "F.Fab")
		)
		(fp_line
			(start 0.499999 0.25)
			(end 0.499999 -0.249999)
			(stroke
				(width 0.1)
				(type default)
			)
			(layer "F.Fab")
		)
		(pad "1" smd rect
			(at -0.459999 0 90)
			(size 0.508 0.5842)
			(layers "F.Cu" "F.Mask" "F.Paste")
			(net "P3V3_B2_QSFP")
		)
		(pad "2" smd rect
			(at 0.459999 0 90)
			(size 0.508 0.5842)
			(layers "F.Cu" "F.Mask" "F.Paste")
			(net "UNNAMED_6_FERRITE_I24_A")
		)
	)
	(footprint ""
		(layer "F.Cu")
		(at -75.292801 1.130402)
		(property "Reference" "R46"
			(at 3.029801 0.050698 0)
			(unlocked yes)
			(layer "F.SilkS")
			(effects
				(font
					(size 0.762 0.5334)
					(thickness 0.1016)
				)
			)
		)
		(property "Value" ""
			(at 0 0 0)
			(layer "F.Fab")
			(effects
				(font
					(size 1.27 1.27)
				)
			)
		)
		(duplicate_pad_numbers_are_jumpers no)
		(fp_line
			(start 0 -0.381)
			(end 0 0.381)
			(stroke
				(width 0.127)
				(type default)
			)
			(layer "F.SilkS")
		)
		(fp_poly
			(pts
				(xy 1.255601 0.656399) (xy -1.255601 0.656399) (xy -1.255601 -0.6564) (xy 1.255601 -0.6564)
			)
			(stroke
				(width 0)
				(type default)
			)
			(fill no)
			(layer "F.CrtYd")
		)
		(fp_line
			(start -0.800001 -0.4)
			(end -0.800001 0.399999)
			(stroke
				(width 0.1)
				(type default)
			)
			(layer "F.Fab")
		)
		(fp_line
			(start -0.800001 0.399999)
			(end 0.800001 0.399999)
			(stroke
				(width 0.1)
				(type default)
			)
			(layer "F.Fab")
		)
		(fp_line
			(start 0.800001 -0.4)
			(end -0.800001 -0.4)
			(stroke
				(width 0.1)
				(type default)
			)
			(layer "F.Fab")
		)
		(fp_line
			(start 0.800001 0.399999)
			(end 0.800001 -0.4)
			(stroke
				(width 0.1)
				(type default)
			)
			(layer "F.Fab")
		)
		(pad "1" smd rect
			(at -0.650001 0)
			(size 0.7112 0.8128)
			(layers "F.Cu" "F.Mask" "F.Paste")
			(net "P3V3_B2_QSFP")
		)
		(pad "2" smd rect
			(at 0.650001 0 180)
			(size 0.7112 0.8128)
			(layers "F.Cu" "F.Mask" "F.Paste")
			(net "ETH10G_B2_TX_FAULT")
		)
	)
	(footprint ""
		(layer "F.Cu")
		(at -95.25 39.010001 180)
		(property "Reference" "J21"
			(at -8.79094 -8.843599 0)
			(unlocked yes)
			(layer "F.SilkS")
			(effects
				(font
					(size 0.762 0.5334)
					(thickness 0.1016)
				)
			)
		)
		(property "Value" ""
			(at 0 0 180)
			(layer "F.Fab")
			(effects
				(font
					(size 1.27 1.27)
				)
			)
		)
		(duplicate_pad_numbers_are_jumpers no)
		(fp_line
			(start 9.874999 50.85)
			(end 9.874999 34.000001)
			(stroke
				(width 0.127)
				(type default)
			)
			(layer "F.SilkS")
		)
		(fp_line
			(start 9.874999 25.000001)
			(end 9.874999 32)
			(stroke
				(width 0.127)
				(type default)
			)
			(layer "F.SilkS")
		)
		(fp_line
			(start 9.874999 16.000001)
			(end 9.874999 23)
			(stroke
				(width 0.127)
				(type default)
			)
			(layer "F.SilkS")
		)
		(fp_line
			(start 9.874999 7.000002)
			(end 9.874999 14)
			(stroke
				(width 0.127)
				(type default)
			)
			(layer "F.SilkS")
		)
		(fp_line
			(start 9.874999 -3.75)
			(end 9.874999 5)
			(stroke
				(width 0.127)
				(type default)
			)
			(layer "F.SilkS")
		)
		(fp_line
			(start -9.874999 50.85)
			(end 9.874999 50.85)
			(stroke
				(width 0.127)
				(type default)
			)
			(layer "F.SilkS")
		)
		(fp_line
			(start -9.874999 38.499999)
			(end -9.874999 50.85)
			(stroke
				(width 0.127)
				(type default)
			)
			(layer "F.SilkS")
		)
		(fp_line
			(start -9.874999 36.500001)
			(end -9.874999 29.5)
			(stroke
				(width 0.127)
				(type default)
			)
			(layer "F.SilkS")
		)
		(fp_line
			(start -9.874999 27.500001)
			(end -9.874999 20.5)
			(stroke
				(width 0.127)
				(type default)
			)
			(layer "F.SilkS")
		)
		(fp_line
			(start -9.874999 18.500001)
			(end -9.874999 11.5)
			(stroke
				(width 0.127)
				(type default)
			)
			(layer "F.SilkS")
		)
		(fp_line
			(start -9.874999 9.499999)
			(end -9.874999 0.750001)
			(stroke
				(width 0.127)
				(type default)
			)
			(layer "F.SilkS")
		)
		(fp_line
			(start -9.874999 -2.264999)
			(end -9.874999 -7.869999)
			(stroke
				(width 0.127)
				(type default)
			)
			(layer "F.SilkS")
		)
		(fp_line
			(start -9.874999 -7.869999)
			(end -6.074999 -7.869999)
			(stroke
				(width 0.127)
				(type default)
			)
			(layer "F.SilkS")
		)
		(fp_poly
			(pts
				(arc
					(start -4.199999 37.600001)
					(mid -9.703758 42.804115)
					(end -14.807001 37.2067)
				)
				(arc
					(start -14.807001 -0.1848)
					(mid -14.550292 -1.881885)
					(end -13.7654 -3.408299)
				)
				(arc
					(start -9.7682 -10.080899)
					(mid -7.846041 -12.229854)
					(end -5.084 -13.056799)
				)
				(arc
					(start -5.0811 -13.056799)
					(mid -4.99375 -13.057419)
					(end -4.906401 -13.0566)
				)
				(arc
					(start 1.8942 -13.048599)
					(mid 3.117342 -12.977539)
					(end 4.291599 -12.627899)
				)
				(arc
					(start 10.9939 -9.842799)
					(mid 11.536623 -9.651121)
					(end 12.055399 -9.4018)
				)
				(arc
					(start 12.0555 -9.401701)
					(mid 14.088517 -7.41727)
					(end 14.8068 -4.668598)
				)
				(arc
					(start 14.8068 32.7031)
					(mid 10.110545 38.317137)
					(end 4.199999 34.000001)
				)
				(xy 4.199999 -2.5) (xy -4.199999 -2.5)
			)
			(stroke
				(width 0)
				(type default)
			)
			(fill no)
			(layer "B.CrtYd")
		)
		(fp_poly
			(pts
				(xy -10.875 51.850001)
				(arc
					(start -10.875 38.564599)
					(mid -11.270016 37.45)
					(end -10.875 36.335401)
				)
				(arc
					(start -10.875 29.5646)
					(mid -11.270017 28.450001)
					(end -10.875 27.335402)
				)
				(arc
					(start -10.875 20.5646)
					(mid -11.270017 19.449999)
					(end -10.875 18.335399)
				)
				(arc
					(start -10.875 11.5646)
					(mid -11.270016 10.45)
					(end -10.875 9.335399)
				)
				(arc
					(start -10.875 0.864601)
					(mid -11.270016 -0.249999)
					(end -10.875 -1.364599)
				)
				(xy -10.875 -8.87)
				(arc
					(start -6.370599 -8.87)
					(mid -5 -9.520011)
					(end -3.629401 -8.87)
				)
				(arc
					(start 0.829399 -8.87)
					(mid 2.2 -9.520014)
					(end 3.5706 -8.87)
				)
				(xy 10.875 -8.87)
				(arc
					(start 10.875 -5.864601)
					(mid 11.270017 -4.75)
					(end 10.875 -3.6354)
				)
				(arc
					(start 10.875 4.835401)
					(mid 11.270016 5.950001)
					(end 10.875 7.064601)
				)
				(arc
					(start 10.875 13.835401)
					(mid 11.270016 14.950001)
					(end 10.875 16.064601)
				)
				(arc
					(start 10.875 22.8354)
					(mid 11.270017 23.950001)
					(end 10.875 25.064601)
				)
				(arc
					(start 10.875 31.8354)
					(mid 11.270016 32.95)
					(end 10.875 34.064601)
				)
				(xy 10.875 51.850001)
			)
			(stroke
				(width 0)
				(type default)
			)
			(fill no)
			(layer "F.CrtYd")
		)
		(fp_line
			(start 9.874999 50.85)
			(end 9.874999 -7.869999)
			(stroke
				(width 0.1)
				(type default)
			)
			(layer "F.Fab")
		)
		(fp_line
			(start 9.874999 -7.869999)
			(end -9.874999 -7.869999)
			(stroke
				(width 0.1)
				(type default)
			)
			(layer "F.Fab")
		)
		(fp_line
			(start -9.874999 50.85)
			(end 9.874999 50.85)
			(stroke
				(width 0.1)
				(type default)
			)
			(layer "F.Fab")
		)
		(fp_line
			(start -9.874999 -7.869999)
			(end -9.874999 50.85)
			(stroke
				(width 0.1)
				(type default)
			)
			(layer "F.Fab")
		)
		(pad "1" thru_hole circle
			(at -9.499999 -0.25 270)
			(size 1.5494 1.5494)
			(drill 1.0414)
			(layers "*.Cu" "*.Mask")
			(remove_unused_layers no)
			(net "GND")
		)
		(pad "2" thru_hole circle
			(at -9.499999 10.449999 270)
			(size 1.5494 1.5494)
			(drill 1.0414)
			(layers "*.Cu" "*.Mask")
			(remove_unused_layers no)
			(net "GND")
		)
		(pad "3" thru_hole circle
			(at -9.499999 19.449999 270)
			(size 1.5494 1.5494)
			(drill 1.0414)
			(layers "*.Cu" "*.Mask")
			(remove_unused_layers no)
			(net "GND")
		)
		(pad "4" thru_hole circle
			(at -9.499999 28.449999 270)
			(size 1.5494 1.5494)
			(drill 1.0414)
			(layers "*.Cu" "*.Mask")
			(remove_unused_layers no)
			(net "GND")
		)
		(pad "5" thru_hole circle
			(at -9.499999 37.449999 270)
			(size 1.5494 1.5494)
			(drill 1.0414)
			(layers "*.Cu" "*.Mask")
			(remove_unused_layers no)
			(net "GND")
		)
		(pad "6" thru_hole circle
			(at -5 -7.75 270)
			(size 1.5494 1.5494)
			(drill 1.0414)
			(layers "*.Cu" "*.Mask")
			(remove_unused_layers no)
			(net "GND")
		)
		(pad "7" thru_hole circle
			(at 2.200001 -7.75 270)
			(size 1.5494 1.5494)
			(drill 1.0414)
			(layers "*.Cu" "*.Mask")
			(remove_unused_layers no)
			(net "GND")
		)
		(pad "8" thru_hole circle
			(at 9.499999 -4.750001 270)
			(size 1.5494 1.5494)
			(drill 1.0414)
			(layers "*.Cu" "*.Mask")
			(remove_unused_layers no)
			(net "GND")
		)
		(pad "9" thru_hole circle
			(at 9.499999 5.950001 270)
			(size 1.5494 1.5494)
			(drill 1.0414)
			(layers "*.Cu" "*.Mask")
			(remove_unused_layers no)
			(net "GND")
		)
		(pad "10" thru_hole circle
			(at 9.499999 14.950001 270)
			(size 1.5494 1.5494)
			(drill 1.0414)
			(layers "*.Cu" "*.Mask")
			(remove_unused_layers no)
			(net "GND")
		)
		(pad "11" thru_hole circle
			(at 9.499999 23.95 270)
			(size 1.5494 1.5494)
			(drill 1.0414)
			(layers "*.Cu" "*.Mask")
			(remove_unused_layers no)
			(net "GND")
		)
		(pad "12" thru_hole circle
			(at 9.499999 32.95 270)
			(size 1.5494 1.5494)
			(drill 1.0414)
			(layers "*.Cu" "*.Mask")
			(remove_unused_layers no)
			(net "GND")
		)
	)
	(footprint ""
		(layer "F.Cu")
		(at -286.893 45.6946)
		(property "Reference" "FS1"
			(at 0.127 1.0795 0)
			(unlocked yes)
			(layer "F.SilkS")
			(effects
				(font
					(size 0.762 0.5334)
					(thickness 0.1016)
				)
			)
		)
		(property "Value" ""
			(at 0 0 0)
			(layer "F.Fab")
			(effects
				(font
					(size 1.27 1.27)
				)
			)
		)
		(duplicate_pad_numbers_are_jumpers no)
		(fp_poly
			(pts
				(xy -1.002101 0.504) (xy -1.002101 -0.503999) (xy 1.002101 -0.503999) (xy 1.002101 0.504)
			)
			(stroke
				(width 0)
				(type default)
			)
			(fill no)
			(layer "F.CrtYd")
		)
		(fp_line
			(start -0.499999 -0.249999)
			(end -0.499999 0.25)
			(stroke
				(width 0.1)
				(type default)
			)
			(layer "F.Fab")
		)
		(fp_line
			(start -0.499999 0.25)
			(end 0.499999 0.25)
			(stroke
				(width 0.1)
				(type default)
			)
			(layer "F.Fab")
		)
		(fp_line
			(start 0.499999 -0.249999)
			(end -0.499999 -0.249999)
			(stroke
				(width 0.1)
				(type default)
			)
			(layer "F.Fab")
		)
		(fp_line
			(start 0.499999 0.25)
			(end 0.499999 -0.249999)
			(stroke
				(width 0.1)
				(type default)
			)
			(layer "F.Fab")
		)
		(pad "1" smd rect
			(at -0.459999 0 90)
			(size 0.508 0.5842)
			(layers "F.Cu" "F.Mask" "F.Paste")
			(net "P3V3_B1_QSFP")
		)
		(pad "2" smd rect
			(at 0.459999 0 90)
			(size 0.508 0.5842)
			(layers "F.Cu" "F.Mask" "F.Paste")
			(net "UNNAMED_4_FERRITE_I148_A")
		)
	)
	(footprint ""
		(layer "F.Cu")
		(at -267.012001 13.424002)
		(property "Reference" "R74"
			(at 3.154261 0.017678 0)
			(unlocked yes)
			(layer "F.SilkS")
			(effects
				(font
					(size 0.762 0.5334)
					(thickness 0.1016)
				)
			)
		)
		(property "Value" ""
			(at 0 0 0)
			(layer "F.Fab")
			(effects
				(font
					(size 1.27 1.27)
				)
			)
		)
		(duplicate_pad_numbers_are_jumpers no)
		(fp_line
			(start 0 -0.381)
			(end 0 0.381)
			(stroke
				(width 0.127)
				(type default)
			)
			(layer "F.SilkS")
		)
		(fp_poly
			(pts
				(xy 1.255601 0.656399) (xy -1.255601 0.656399) (xy -1.255601 -0.6564) (xy 1.255601 -0.6564)
			)
			(stroke
				(width 0)
				(type default)
			)
			(fill no)
			(layer "F.CrtYd")
		)
		(fp_line
			(start -0.800001 -0.4)
			(end -0.800001 0.399999)
			(stroke
				(width 0.1)
				(type default)
			)
			(layer "F.Fab")
		)
		(fp_line
			(start -0.800001 0.399999)
			(end 0.800001 0.399999)
			(stroke
				(width 0.1)
				(type default)
			)
			(layer "F.Fab")
		)
		(fp_line
			(start 0.800001 -0.4)
			(end -0.800001 -0.4)
			(stroke
				(width 0.1)
				(type default)
			)
			(layer "F.Fab")
		)
		(fp_line
			(start 0.800001 0.399999)
			(end 0.800001 -0.4)
			(stroke
				(width 0.1)
				(type default)
			)
			(layer "F.Fab")
		)
		(pad "1" smd rect
			(at -0.650001 0)
			(size 0.7112 0.8128)
			(layers "F.Cu" "F.Mask" "F.Paste")
			(net "P3V3_40G_B1_VCC1")
		)
		(pad "2" smd rect
			(at 0.650001 0 180)
			(size 0.7112 0.8128)
			(layers "F.Cu" "F.Mask" "F.Paste")
			(net "P3V3_B1_QSFP")
		)
	)
	(footprint ""
		(layer "F.Cu")
		(at -336.423 4.9276 -90)
		(property "Reference" "R9"
			(at 1.82626 -1.00838 90)
			(unlocked yes)
			(layer "F.SilkS")
			(effects
				(font
					(size 0.762 0.5334)
					(thickness 0.1016)
				)
			)
		)
		(property "Value" ""
			(at 0 0 270)
			(layer "F.Fab")
			(effects
				(font
					(size 1.27 1.27)
				)
			)
		)
		(duplicate_pad_numbers_are_jumpers no)
		(fp_line
			(start 0 -0.381)
			(end 0 0.381)
			(stroke
				(width 0.127)
				(type default)
			)
			(layer "F.SilkS")
		)
		(fp_poly
			(pts
				(xy 1.255601 0.6564) (xy -1.255601 0.6564) (xy -1.255601 -0.656399) (xy 1.255601 -0.656399)
			)
			(stroke
				(width 0)
				(type default)
			)
			(fill no)
			(layer "F.CrtYd")
		)
		(fp_line
			(start -0.800001 0.399999)
			(end 0.800001 0.399999)
			(stroke
				(width 0.1)
				(type default)
			)
			(layer "F.Fab")
		)
		(fp_line
			(start 0.800001 0.399999)
			(end 0.800001 -0.399999)
			(stroke
				(width 0.1)
				(type default)
			)
			(layer "F.Fab")
		)
		(fp_line
			(start -0.800001 -0.399999)
			(end -0.800001 0.399999)
			(stroke
				(width 0.1)
				(type default)
			)
			(layer "F.Fab")
		)
		(fp_line
			(start 0.800001 -0.399999)
			(end -0.800001 -0.399999)
			(stroke
				(width 0.1)
				(type default)
			)
			(layer "F.Fab")
		)
		(pad "1" smd rect
			(at -0.650001 0 270)
			(size 0.7112 0.8128)
			(layers "F.Cu" "F.Mask" "F.Paste")
			(net "UNNAMED_4_1X2HDR_I81_IO")
		)
		(pad "2" smd rect
			(at 0.650001 0 90)
			(size 0.7112 0.8128)
			(layers "F.Cu" "F.Mask" "F.Paste")
			(net "GND")
		)
	)
	(footprint ""
		(layer "F.Cu")
		(at -270.237801 12.916002 90)
		(property "Reference" "C30"
			(at 0 -0.942899 90)
			(unlocked yes)
			(layer "F.SilkS")
			(effects
				(font
					(size 0.762 0.5334)
					(thickness 0.1016)
				)
			)
		)
		(property "Value" ""
			(at 0 0 90)
			(layer "F.Fab")
			(effects
				(font
					(size 1.27 1.27)
				)
			)
		)
		(duplicate_pad_numbers_are_jumpers no)
		(fp_line
			(start 0 -0.381)
			(end 0 0.381)
			(stroke
				(width 0.127)
				(type default)
			)
			(layer "F.SilkS")
		)
		(fp_poly
			(pts
				(xy 1.2533 0.6564) (xy -1.253299 0.6564) (xy -1.253299 -0.656399) (xy 1.2533 -0.656399)
			)
			(stroke
				(width 0)
				(type default)
			)
			(fill no)
			(layer "F.CrtYd")
		)
		(fp_line
			(start 0.762 -0.381)
			(end -0.762 -0.381)
			(stroke
				(width 0.1)
				(type default)
			)
			(layer "F.Fab")
		)
		(fp_line
			(start -0.762 -0.381)
			(end -0.762 0.381)
			(stroke
				(width 0.1)
				(type default)
			)
			(layer "F.Fab")
		)
		(fp_line
			(start 0.762 0.381)
			(end 0.762 -0.381)
			(stroke
				(width 0.1)
				(type default)
			)
			(layer "F.Fab")
		)
		(fp_line
			(start -0.762 0.381)
			(end 0.762 0.381)
			(stroke
				(width 0.1)
				(type default)
			)
			(layer "F.Fab")
		)
		(pad "1" smd rect
			(at -0.6477 0 90)
			(size 0.7112 0.8128)
			(layers "F.Cu" "F.Mask" "F.Paste")
			(net "P3V3_40G_B1_VCC1")
		)
		(pad "2" smd rect
			(at 0.6477 0 270)
			(size 0.7112 0.8128)
			(layers "F.Cu" "F.Mask" "F.Paste")
			(net "GND")
		)
	)
	(footprint ""
		(layer "F.Cu")
		(at -300.9392 1.4732)
		(property "Reference" "R15"
			(at -3.3528 -0.0381 0)
			(unlocked yes)
			(layer "F.SilkS")
			(effects
				(font
					(size 0.762 0.5334)
					(thickness 0.1016)
				)
			)
		)
		(property "Value" ""
			(at 0 0 0)
			(layer "F.Fab")
			(effects
				(font
					(size 1.27 1.27)
				)
			)
		)
		(duplicate_pad_numbers_are_jumpers no)
		(fp_line
			(start 0 -0.381)
			(end 0 0.381)
			(stroke
				(width 0.127)
				(type default)
			)
			(layer "F.SilkS")
		)
		(fp_poly
			(pts
				(xy 1.255601 0.6564) (xy -1.255601 0.6564) (xy -1.255601 -0.656399) (xy 1.255601 -0.656399)
			)
			(stroke
				(width 0)
				(type default)
			)
			(fill no)
			(layer "F.CrtYd")
		)
		(fp_line
			(start -0.800001 -0.399999)
			(end -0.800001 0.399999)
			(stroke
				(width 0.1)
				(type default)
			)
			(layer "F.Fab")
		)
		(fp_line
			(start -0.800001 0.399999)
			(end 0.800001 0.399999)
			(stroke
				(width 0.1)
				(type default)
			)
			(layer "F.Fab")
		)
		(fp_line
			(start 0.800001 -0.399999)
			(end -0.800001 -0.399999)
			(stroke
				(width 0.1)
				(type default)
			)
			(layer "F.Fab")
		)
		(fp_line
			(start 0.800001 0.399999)
			(end 0.800001 -0.399999)
			(stroke
				(width 0.1)
				(type default)
			)
			(layer "F.Fab")
		)
		(pad "1" smd rect
			(at -0.650001 0)
			(size 0.7112 0.8128)
			(layers "F.Cu" "F.Mask" "F.Paste")
			(net "ETH10G_B1_PRES_N")
		)
		(pad "2" smd rect
			(at 0.650001 0 180)
			(size 0.7112 0.8128)
			(layers "F.Cu" "F.Mask" "F.Paste")
			(net "ETH10G_B1_MOD_ABS")
		)
	)
	(footprint ""
		(layer "F.Cu")
		(at -300.9392 8.8646 180)
		(property "Reference" "R5"
			(at 3.6068 -0.0635 0)
			(unlocked yes)
			(layer "F.SilkS")
			(effects
				(font
					(size 0.762 0.5334)
					(thickness 0.1016)
				)
			)
		)
		(property "Value" ""
			(at 0 0 180)
			(layer "F.Fab")
			(effects
				(font
					(size 1.27 1.27)
				)
			)
		)
		(duplicate_pad_numbers_are_jumpers no)
		(fp_line
			(start 0 -0.381)
			(end 0 0.381)
			(stroke
				(width 0.127)
				(type default)
			)
			(layer "F.SilkS")
		)
		(fp_poly
			(pts
				(xy 1.255601 0.656399) (xy -1.255601 0.656399) (xy -1.255601 -0.6564) (xy 1.255601 -0.6564)
			)
			(stroke
				(width 0)
				(type default)
			)
			(fill no)
			(layer "F.CrtYd")
		)
		(fp_line
			(start 0.800001 0.399999)
			(end 0.800001 -0.399999)
			(stroke
				(width 0.1)
				(type default)
			)
			(layer "F.Fab")
		)
		(fp_line
			(start 0.800001 -0.399999)
			(end -0.800001 -0.399999)
			(stroke
				(width 0.1)
				(type default)
			)
			(layer "F.Fab")
		)
		(fp_line
			(start -0.800001 0.399999)
			(end 0.800001 0.399999)
			(stroke
				(width 0.1)
				(type default)
			)
			(layer "F.Fab")
		)
		(fp_line
			(start -0.800001 -0.399999)
			(end -0.800001 0.399999)
			(stroke
				(width 0.1)
				(type default)
			)
			(layer "F.Fab")
		)
		(pad "1" smd rect
			(at -0.650001 0 180)
			(size 0.7112 0.8128)
			(layers "F.Cu" "F.Mask" "F.Paste")
			(net "SKU_B1_ID1")
		)
		(pad "2" smd rect
			(at 0.650001 0)
			(size 0.7112 0.8128)
			(layers "F.Cu" "F.Mask" "F.Paste")
			(net "GND")
		)
	)
	(footprint ""
		(layer "F.Cu")
		(at -44.996001 11.519002 -90)
		(property "Reference" "FS7"
			(at 0.170078 -1.749961 90)
			(unlocked yes)
			(layer "F.SilkS")
			(effects
				(font
					(size 0.762 0.5334)
					(thickness 0.1016)
				)
			)
		)
		(property "Value" ""
			(at 0 0 270)
			(layer "F.Fab")
			(effects
				(font
					(size 1.27 1.27)
				)
			)
		)
		(duplicate_pad_numbers_are_jumpers no)
		(fp_poly
			(pts
				(xy -1.002102 0.503999) (xy -1.002102 -0.504) (xy 1.002101 -0.504) (xy 1.002101 0.503999)
			)
			(stroke
				(width 0)
				(type default)
			)
			(fill no)
			(layer "F.CrtYd")
		)
		(fp_line
			(start -0.499999 0.249999)
			(end 0.499999 0.249999)
			(stroke
				(width 0.1)
				(type default)
			)
			(layer "F.Fab")
		)
		(fp_line
			(start 0.499999 0.249999)
			(end 0.499999 -0.25)
			(stroke
				(width 0.1)
				(type default)
			)
			(layer "F.Fab")
		)
		(fp_line
			(start -0.499999 -0.25)
			(end -0.499999 0.249999)
			(stroke
				(width 0.1)
				(type default)
			)
			(layer "F.Fab")
		)
		(fp_line
			(start 0.499999 -0.25)
			(end -0.499999 -0.25)
			(stroke
				(width 0.1)
				(type default)
			)
			(layer "F.Fab")
		)
		(pad "1" smd rect
			(at -0.459999 0)
			(size 0.508 0.5842)
			(layers "F.Cu" "F.Mask" "F.Paste")
			(net "UNNAMED_8_FERRITE_I47_B")
		)
		(pad "2" smd rect
			(at 0.459999 0)
			(size 0.508 0.5842)
			(layers "F.Cu" "F.Mask" "F.Paste")
			(net "P3V3_B2_QSFP")
		)
	)
	(footprint ""
		(layer "F.Cu")
		(at -284.48 45.72)
		(property "Reference" "FB1"
			(at -0.635 1.0541 0)
			(unlocked yes)
			(layer "F.SilkS")
			(effects
				(font
					(size 0.762 0.5334)
					(thickness 0.1016)
				)
				(justify left)
			)
		)
		(property "Value" ""
			(at 0 0 0)
			(layer "F.Fab")
			(effects
				(font
					(size 1.27 1.27)
				)
			)
		)
		(duplicate_pad_numbers_are_jumpers no)
		(fp_poly
			(pts
				(xy -1.016 0.508) (xy -1.016 -0.508) (xy 1.016 -0.508) (xy 1.016 0.508)
			)
			(stroke
				(width 0)
				(type default)
			)
			(fill no)
			(layer "F.CrtYd")
		)
		(fp_line
			(start -0.508 -0.254)
			(end 0.508 -0.254)
			(stroke
				(width 0.1)
				(type default)
			)
			(layer "F.Fab")
		)
		(fp_line
			(start -0.508 0.254)
			(end -0.508 -0.254)
			(stroke
				(width 0.1)
				(type default)
			)
			(layer "F.Fab")
		)
		(fp_line
			(start 0.508 -0.254)
			(end 0.508 0.254)
			(stroke
				(width 0.1)
				(type default)
			)
			(layer "F.Fab")
		)
		(fp_line
			(start 0.508 0.254)
			(end -0.508 0.254)
			(stroke
				(width 0.1)
				(type default)
			)
			(layer "F.Fab")
		)
		(pad "1" smd rect
			(at -0.4572 0 90)
			(size 0.508 0.5842)
			(layers "F.Cu" "F.Mask" "F.Paste")
			(net "UNNAMED_4_FERRITE_I148_A")
		)
		(pad "2" smd rect
			(at 0.4572 0 90)
			(size 0.508 0.5842)
			(layers "F.Cu" "F.Mask" "F.Paste")
			(net "P3V3_10G_B1_VCCR")
		)
	)
	(footprint ""
		(layer "F.Cu")
		(at -45.250001 7.582002 180)
		(property "Reference" "FB5"
			(at -2.451001 0.050902 0)
			(unlocked yes)
			(layer "F.SilkS")
			(effects
				(font
					(size 0.762 0.5334)
					(thickness 0.1016)
				)
				(justify left)
			)
		)
		(property "Value" ""
			(at 0 0 180)
			(layer "F.Fab")
			(effects
				(font
					(size 1.27 1.27)
				)
			)
		)
		(duplicate_pad_numbers_are_jumpers no)
		(fp_poly
			(pts
				(xy -1.016 0.508) (xy -1.016 -0.508) (xy 1.016 -0.508) (xy 1.016 0.508)
			)
			(stroke
				(width 0)
				(type default)
			)
			(fill no)
			(layer "F.CrtYd")
		)
		(fp_line
			(start 0.508 0.254)
			(end -0.508 0.254)
			(stroke
				(width 0.1)
				(type default)
			)
			(layer "F.Fab")
		)
		(fp_line
			(start 0.508 -0.254)
			(end 0.508 0.254)
			(stroke
				(width 0.1)
				(type default)
			)
			(layer "F.Fab")
		)
		(fp_line
			(start -0.508 0.254)
			(end -0.508 -0.254)
			(stroke
				(width 0.1)
				(type default)
			)
			(layer "F.Fab")
		)
		(fp_line
			(start -0.508 -0.254)
			(end 0.508 -0.254)
			(stroke
				(width 0.1)
				(type default)
			)
			(layer "F.Fab")
		)
		(pad "1" smd rect
			(at -0.4572 0 270)
			(size 0.508 0.5842)
			(layers "F.Cu" "F.Mask" "F.Paste")
			(net "UNNAMED_8_FERRITE_I51_A")
		)
		(pad "2" smd rect
			(at 0.4572 0 270)
			(size 0.508 0.5842)
			(layers "F.Cu" "F.Mask" "F.Paste")
			(net "P3V3_40G_B2_VCC_TX")
		)
	)
	(footprint ""
		(layer "F.Cu")
		(at -266.192 8.636 180)
		(property "Reference" "R72"
			(at -2.413 -0.1651 0)
			(unlocked yes)
			(layer "F.SilkS")
			(effects
				(font
					(size 0.762 0.5334)
					(thickness 0.1016)
				)
			)
		)
		(property "Value" ""
			(at 0 0 180)
			(layer "F.Fab")
			(effects
				(font
					(size 1.27 1.27)
				)
			)
		)
		(duplicate_pad_numbers_are_jumpers no)
		(fp_line
			(start 0 -0.381)
			(end 0 0.381)
			(stroke
				(width 0.127)
				(type default)
			)
			(layer "F.SilkS")
		)
		(fp_poly
			(pts
				(xy 1.255601 0.656399) (xy -1.255601 0.656399) (xy -1.255601 -0.6564) (xy 1.255601 -0.6564)
			)
			(stroke
				(width 0)
				(type default)
			)
			(fill no)
			(layer "F.CrtYd")
		)
		(fp_line
			(start 0.800001 0.399999)
			(end 0.800001 -0.399999)
			(stroke
				(width 0.1)
				(type default)
			)
			(layer "F.Fab")
		)
		(fp_line
			(start 0.800001 -0.399999)
			(end -0.800001 -0.399999)
			(stroke
				(width 0.1)
				(type default)
			)
			(layer "F.Fab")
		)
		(fp_line
			(start -0.800001 0.399999)
			(end 0.800001 0.399999)
			(stroke
				(width 0.1)
				(type default)
			)
			(layer "F.Fab")
		)
		(fp_line
			(start -0.800001 -0.399999)
			(end -0.800001 0.399999)
			(stroke
				(width 0.1)
				(type default)
			)
			(layer "F.Fab")
		)
		(pad "1" smd rect
			(at -0.650001 0 180)
			(size 0.7112 0.8128)
			(layers "F.Cu" "F.Mask" "F.Paste")
			(net "P3V3_B1_QSFP")
		)
		(pad "2" smd rect
			(at 0.650001 0)
			(size 0.7112 0.8128)
			(layers "F.Cu" "F.Mask" "F.Paste")
			(net "P3V3_40G_B1_VCC_TX")
		)
	)
	(footprint ""
		(layer "F.Cu")
		(at -123.649689 36.82998 180)
		(property "Reference" "J15"
			(at 0 11.834899 0)
			(unlocked yes)
			(layer "F.SilkS")
			(effects
				(font
					(size 0.762 0.5334)
					(thickness 0.1016)
				)
			)
		)
		(property "Value" ""
			(at 0 0 180)
			(layer "F.Fab")
			(effects
				(font
					(size 1.27 1.27)
				)
			)
		)
		(duplicate_pad_numbers_are_jumpers no)
		(fp_line
			(start 5.325001 10.870001)
			(end -5.325001 10.870001)
			(stroke
				(width 0.127)
				(type default)
			)
			(layer "F.SilkS")
		)
		(fp_line
			(start 5.325001 -12.76)
			(end 5.325001 10.870001)
			(stroke
				(width 0.127)
				(type default)
			)
			(layer "F.SilkS")
		)
		(fp_line
			(start 2.775001 -12.76)
			(end 5.325001 -12.76)
			(stroke
				(width 0.127)
				(type default)
			)
			(layer "F.SilkS")
		)
		(fp_line
			(start 2.775001 -42.660001)
			(end 2.775001 -12.76)
			(stroke
				(width 0.127)
				(type default)
			)
			(layer "F.SilkS")
		)
		(fp_line
			(start -2.775001 -12.76)
			(end -2.775001 -42.660001)
			(stroke
				(width 0.127)
				(type default)
			)
			(layer "F.SilkS")
		)
		(fp_line
			(start -2.775001 -42.660001)
			(end 2.775001 -42.660001)
			(stroke
				(width 0.127)
				(type default)
			)
			(layer "F.SilkS")
		)
		(fp_line
			(start -5.325001 10.870001)
			(end -5.325001 -12.76)
			(stroke
				(width 0.127)
				(type default)
			)
			(layer "F.SilkS")
		)
		(fp_line
			(start -5.325001 -12.76)
			(end -2.775001 -12.76)
			(stroke
				(width 0.127)
				(type default)
			)
			(layer "F.SilkS")
		)
		(fp_poly
			(pts
				(arc
					(start -7.3152 0)
					(mid 7.3152 0)
					(end -7.3152 0)
				)
			)
			(stroke
				(width 0)
				(type default)
			)
			(fill no)
			(layer "B.CrtYd")
		)
		(fp_poly
			(pts
				(xy 6.324999 11.869999) (xy -6.324999 11.869999) (xy -6.324999 -13.76) (xy -3.774999 -13.76) (xy -3.774999 -43.659999)
				(xy 3.774999 -43.659999) (xy 3.774999 -13.76) (xy 6.324999 -13.76)
			)
			(stroke
				(width 0)
				(type default)
			)
			(fill no)
			(layer "F.CrtYd")
		)
		(fp_line
			(start 5.325001 10.870001)
			(end -5.325001 10.870001)
			(stroke
				(width 0.1)
				(type default)
			)
			(layer "F.Fab")
		)
		(fp_line
			(start 5.325001 -12.76)
			(end 5.325001 10.870001)
			(stroke
				(width 0.1)
				(type default)
			)
			(layer "F.Fab")
		)
		(fp_line
			(start 2.775001 -12.76)
			(end 5.325001 -12.76)
			(stroke
				(width 0.1)
				(type default)
			)
			(layer "F.Fab")
		)
		(fp_line
			(start 2.775001 -42.660001)
			(end 2.775001 -12.76)
			(stroke
				(width 0.1)
				(type default)
			)
			(layer "F.Fab")
		)
		(fp_line
			(start -2.775001 -12.76)
			(end -2.775001 -42.660001)
			(stroke
				(width 0.1)
				(type default)
			)
			(layer "F.Fab")
		)
		(fp_line
			(start -2.775001 -42.660001)
			(end 2.775001 -42.660001)
			(stroke
				(width 0.1)
				(type default)
			)
			(layer "F.Fab")
		)
		(fp_line
			(start -5.325001 10.870001)
			(end -5.325001 -12.76)
			(stroke
				(width 0.1)
				(type default)
			)
			(layer "F.Fab")
		)
		(fp_line
			(start -5.325001 -12.76)
			(end -2.775001 -12.76)
			(stroke
				(width 0.1)
				(type default)
			)
			(layer "F.Fab")
		)
		(pad "" np_thru_hole circle
			(at 0 -5.629999 180)
			(size 1.27 1.27)
			(drill 3.9624)
			(layers "*.Cu" "*.Mask")
		)
		(pad "" np_thru_hole circle
			(at 0 6.619999 180)
			(size 1.27 1.27)
			(drill 3.9624)
			(layers "*.Cu" "*.Mask")
		)
		(pad "1" thru_hole circle
			(at 0 0 180)
			(size 5.588 5.588)
			(drill 3.9624)
			(layers "*.Cu" "*.Mask")
			(remove_unused_layers no)
			(net "GND")
		)
		(zone
			(layers "F.Cu" "B.Cu" "In1.Cu" "In2.Cu" "In3.Cu" "In4.Cu" "In5.Cu" "In6.Cu")
			(hatch none 0.5)
			(connect_pads
				(clearance 0)
			)
			(min_thickness 0.25)
			(keepout
				(tracks not_allowed)
				(vias allowed)
				(pads allowed)
				(copperpour not_allowed)
				(footprints allowed)
			)
			(placement
				(enabled no)
				(sheetname "")
			)
			(fill
				(thermal_gap 0.5)
				(thermal_bridge_width 0.5)
				(island_removal_mode 0)
			)
			(polygon
				(pts
					(arc
						(start -121.287489 30.20998)
						(mid -126.011889 30.20998)
						(end -121.287489 30.20998)
					)
				)
			)
		)
		(zone
			(layers "F.Cu" "B.Cu" "In1.Cu" "In2.Cu" "In3.Cu" "In4.Cu" "In5.Cu" "In6.Cu")
			(hatch none 0.5)
			(connect_pads
				(clearance 0)
			)
			(min_thickness 0.25)
			(keepout
				(tracks not_allowed)
				(vias allowed)
				(pads allowed)
				(copperpour not_allowed)
				(footprints allowed)
			)
			(placement
				(enabled no)
				(sheetname "")
			)
			(fill
				(thermal_gap 0.5)
				(thermal_bridge_width 0.5)
				(island_removal_mode 0)
			)
			(polygon
				(pts
					(arc
						(start -121.287489 42.459979)
						(mid -126.011889 42.459979)
						(end -121.287489 42.459979)
					)
				)
			)
		)
	)
	(footprint ""
		(layer "F.Cu")
		(at -331.47 11.8618 180)
		(property "Reference" "R77"
			(at -3.21056 0.05334 0)
			(unlocked yes)
			(layer "F.SilkS")
			(effects
				(font
					(size 0.762 0.5334)
					(thickness 0.1016)
				)
			)
		)
		(property "Value" ""
			(at 0 0 180)
			(layer "F.Fab")
			(effects
				(font
					(size 1.27 1.27)
				)
			)
		)
		(duplicate_pad_numbers_are_jumpers no)
		(fp_line
			(start 0 -0.381)
			(end 0 0.381)
			(stroke
				(width 0.127)
				(type default)
			)
			(layer "F.SilkS")
		)
		(fp_poly
			(pts
				(xy 1.255601 0.656399) (xy -1.255601 0.656399) (xy -1.255601 -0.6564) (xy 1.255601 -0.6564)
			)
			(stroke
				(width 0)
				(type default)
			)
			(fill no)
			(layer "F.CrtYd")
		)
		(fp_line
			(start 0.800001 0.399999)
			(end 0.800001 -0.399999)
			(stroke
				(width 0.1)
				(type default)
			)
			(layer "F.Fab")
		)
		(fp_line
			(start 0.800001 -0.399999)
			(end -0.800001 -0.399999)
			(stroke
				(width 0.1)
				(type default)
			)
			(layer "F.Fab")
		)
		(fp_line
			(start -0.800001 0.399999)
			(end 0.800001 0.399999)
			(stroke
				(width 0.1)
				(type default)
			)
			(layer "F.Fab")
		)
		(fp_line
			(start -0.800001 -0.399999)
			(end -0.800001 0.399999)
			(stroke
				(width 0.1)
				(type default)
			)
			(layer "F.Fab")
		)
		(pad "1" smd rect
			(at -0.650001 0 180)
			(size 0.7112 0.8128)
			(layers "F.Cu" "F.Mask" "F.Paste")
			(net "ETH40G_B1_MODSEL_N")
		)
		(pad "2" smd rect
			(at 0.650001 0)
			(size 0.7112 0.8128)
			(layers "F.Cu" "F.Mask" "F.Paste")
			(net "GND")
		)
	)
	(footprint ""
		(layer "F.Cu")
		(at -334.6958 16.891 90)
		(property "Reference" "R84"
			(at -0.254 -1.3081 90)
			(unlocked yes)
			(layer "F.SilkS")
			(effects
				(font
					(size 0.762 0.5334)
					(thickness 0.1016)
				)
			)
		)
		(property "Value" ""
			(at 0 0 90)
			(layer "F.Fab")
			(effects
				(font
					(size 1.27 1.27)
				)
			)
		)
		(duplicate_pad_numbers_are_jumpers no)
		(fp_line
			(start 0 -0.381)
			(end 0 0.381)
			(stroke
				(width 0.127)
				(type default)
			)
			(layer "F.SilkS")
		)
		(fp_poly
			(pts
				(xy 1.255601 0.656399) (xy -1.255601 0.656399) (xy -1.255601 -0.6564) (xy 1.255601 -0.6564)
			)
			(stroke
				(width 0)
				(type default)
			)
			(fill no)
			(layer "F.CrtYd")
		)
		(fp_line
			(start 0.800001 -0.399999)
			(end -0.800001 -0.399999)
			(stroke
				(width 0.1)
				(type default)
			)
			(layer "F.Fab")
		)
		(fp_line
			(start -0.800001 -0.399999)
			(end -0.800001 0.399999)
			(stroke
				(width 0.1)
				(type default)
			)
			(layer "F.Fab")
		)
		(fp_line
			(start 0.800001 0.399999)
			(end 0.800001 -0.399999)
			(stroke
				(width 0.1)
				(type default)
			)
			(layer "F.Fab")
		)
		(fp_line
			(start -0.800001 0.399999)
			(end 0.800001 0.399999)
			(stroke
				(width 0.1)
				(type default)
			)
			(layer "F.Fab")
		)
		(pad "1" smd rect
			(at -0.650001 0 90)
			(size 0.7112 0.8128)
			(layers "F.Cu" "F.Mask" "F.Paste")
			(net "P3V3_B1_QSFP")
		)
		(pad "2" smd rect
			(at 0.650001 0 270)
			(size 0.7112 0.8128)
			(layers "F.Cu" "F.Mask" "F.Paste")
			(net "ETH40G_B1_LPMODE")
		)
	)
	(footprint ""
		(layer "F.Cu")
		(at -247.68 45.360001 180)
		(property "Reference" "J11"
			(at 5 16.084901 0)
			(unlocked yes)
			(layer "F.SilkS")
			(effects
				(font
					(size 0.762 0.5334)
					(thickness 0.1016)
				)
			)
		)
		(property "Value" ""
			(at 0 0 180)
			(layer "F.Fab")
			(effects
				(font
					(size 1.27 1.27)
				)
			)
		)
		(duplicate_pad_numbers_are_jumpers no)
		(fp_line
			(start 10.950001 15.3)
			(end -0.950001 15.3)
			(stroke
				(width 0.127)
				(type default)
			)
			(layer "F.SilkS")
		)
		(fp_line
			(start 10.950001 -11.999999)
			(end 10.950001 15.3)
			(stroke
				(width 0.127)
				(type default)
			)
			(layer "F.SilkS")
		)
		(fp_line
			(start -0.950001 15.3)
			(end -0.950001 -11.999999)
			(stroke
				(width 0.127)
				(type default)
			)
			(layer "F.SilkS")
		)
		(fp_line
			(start -0.950001 -11.999999)
			(end 10.950001 -11.999999)
			(stroke
				(width 0.127)
				(type default)
			)
			(layer "F.SilkS")
		)
		(fp_poly
			(pts
				(arc
					(start -4.93 12.500001)
					(mid -3.486036 15.986037)
					(end 0 17.430001)
				)
				(arc
					(start 10 17.430001)
					(mid 13.486036 15.986037)
					(end 14.930001 12.500001)
				)
				(arc
					(start 14.930001 -0.1)
					(mid 13.486037 -3.586037)
					(end 10 -5.03)
				)
				(arc
					(start 0 -5.03)
					(mid -3.486036 -3.586036)
					(end -4.93 -0.1)
				)
			)
			(stroke
				(width 0)
				(type default)
			)
			(fill no)
			(layer "B.CrtYd")
		)
		(fp_poly
			(pts
				(xy 11.949999 16.300001) (xy -1.950001 16.300001) (xy -1.950001 -12.999999) (xy 11.949999 -12.999999)
			)
			(stroke
				(width 0)
				(type default)
			)
			(fill no)
			(layer "F.CrtYd")
		)
		(fp_line
			(start 10.950001 15.3)
			(end -0.950001 15.3)
			(stroke
				(width 0.1)
				(type default)
			)
			(layer "F.Fab")
		)
		(fp_line
			(start 10.950001 -11.999999)
			(end 10.950001 15.3)
			(stroke
				(width 0.1)
				(type default)
			)
			(layer "F.Fab")
		)
		(fp_line
			(start -0.950001 15.3)
			(end -0.950001 -11.999999)
			(stroke
				(width 0.1)
				(type default)
			)
			(layer "F.Fab")
		)
		(fp_line
			(start -0.950001 -11.999999)
			(end 10.950001 -11.999999)
			(stroke
				(width 0.1)
				(type default)
			)
			(layer "F.Fab")
		)
		(fp_text user "I6"
			(at 11.876999 10.9539 0)
			(unlocked yes)
			(layer "F.SilkS")
			(effects
				(font
					(size 0.762 0.5334)
					(thickness 0.1016)
				)
			)
		)
		(fp_text user "E6"
			(at 11.876999 5.353901 0)
			(unlocked yes)
			(layer "F.SilkS")
			(effects
				(font
					(size 0.762 0.5334)
					(thickness 0.1016)
				)
			)
		)
		(fp_text user "A6"
			(at 11.876999 -0.2461 0)
			(unlocked yes)
			(layer "F.SilkS")
			(effects
				(font
					(size 0.762 0.5334)
					(thickness 0.1016)
				)
			)
		)
		(fp_text user "*"
			(at -1.681 -1.204549 0)
			(unlocked yes)
			(layer "F.SilkS")
			(effects
				(font
					(size 0.381 0.381)
					(thickness 0.381)
				)
			)
		)
		(fp_text user "I1"
			(at -1.749999 11.2079 0)
			(unlocked yes)
			(layer "F.SilkS")
			(effects
				(font
					(size 0.762 0.5334)
					(thickness 0.1016)
				)
			)
		)
		(fp_text user "E1"
			(at -1.749999 5.607901 0)
			(unlocked yes)
			(layer "F.SilkS")
			(effects
				(font
					(size 0.762 0.5334)
					(thickness 0.1016)
				)
			)
		)
		(fp_text user "A1"
			(at -1.749999 0.0079 0)
			(unlocked yes)
			(layer "F.SilkS")
			(effects
				(font
					(size 0.762 0.5334)
					(thickness 0.1016)
				)
			)
		)
		(fp_text user "I6"
			(at 11.423 11.0809 0)
			(unlocked yes)
			(layer "B.SilkS")
			(effects
				(font
					(size 0.762 0.5334)
					(thickness 0.1016)
				)
				(justify mirror)
			)
		)
		(fp_text user "E6"
			(at 11.423 5.480901 0)
			(unlocked yes)
			(layer "B.SilkS")
			(effects
				(font
					(size 0.762 0.5334)
					(thickness 0.1016)
				)
				(justify mirror)
			)
		)
		(fp_text user "A6"
			(at 11.423 -0.1191 0)
			(unlocked yes)
			(layer "B.SilkS")
			(effects
				(font
					(size 0.762 0.5334)
					(thickness 0.1016)
				)
				(justify mirror)
			)
		)
		(fp_text user "E1"
			(at -1.26698 5.850301 0)
			(unlocked yes)
			(layer "B.SilkS")
			(effects
				(font
					(size 0.762 0.5334)
					(thickness 0.1016)
				)
				(justify mirror)
			)
		)
		(fp_text user "I1"
			(at -1.5 11.0809 0)
			(unlocked yes)
			(layer "B.SilkS")
			(effects
				(font
					(size 0.762 0.5334)
					(thickness 0.1016)
				)
				(justify mirror)
			)
		)
		(fp_text user "A1"
			(at -1.549999 -0.1191 0)
			(unlocked yes)
			(layer "B.SilkS")
			(effects
				(font
					(size 0.762 0.5334)
					(thickness 0.1016)
				)
				(justify mirror)
			)
		)
		(pad "A1" thru_hole circle
			(at 0 0 180)
			(size 0.8128 0.8128)
			(drill 0.508)
			(layers "*.Cu" "*.Mask")
			(remove_unused_layers no)
			(net "SAS_B1_TX1P")
		)
		(pad "A2" thru_hole circle
			(at 2.000001 -0.1 180)
			(size 0.8128 0.8128)
			(drill 0.508)
			(layers "*.Cu" "*.Mask")
			(remove_unused_layers no)
			(net "GND")
		)
		(pad "A3" thru_hole circle
			(at 4 0 180)
			(size 0.8128 0.8128)
			(drill 0.508)
			(layers "*.Cu" "*.Mask")
			(remove_unused_layers no)
			(net "SERIAL_B1_TX1")
		)
		(pad "A4" thru_hole circle
			(at 6.000001 -0.1 180)
			(size 0.8128 0.8128)
			(drill 0.508)
			(layers "*.Cu" "*.Mask")
			(remove_unused_layers no)
			(net "GND")
		)
		(pad "A5" thru_hole circle
			(at 7.999999 0 180)
			(size 0.8128 0.8128)
			(drill 0.508)
			(layers "*.Cu" "*.Mask")
			(remove_unused_layers no)
			(net "SAS_B1_TX6P")
		)
		(pad "A6" thru_hole circle
			(at 10 -0.1 180)
			(size 0.8128 0.8128)
			(drill 0.508)
			(layers "*.Cu" "*.Mask")
			(remove_unused_layers no)
			(net "GND")
		)
		(pad "B1" thru_hole circle
			(at 0 1.4 180)
			(size 0.8128 0.8128)
			(drill 0.508)
			(layers "*.Cu" "*.Mask")
			(remove_unused_layers no)
			(net "SAS_B1_TX1N")
		)
		(pad "B2" thru_hole circle
			(at 2.000001 1.3 180)
			(size 0.8128 0.8128)
			(drill 0.508)
			(layers "*.Cu" "*.Mask")
			(remove_unused_layers no)
			(net "SAS_B1_RX3P")
		)
		(pad "B3" thru_hole circle
			(at 4 1.4 180)
			(size 0.8128 0.8128)
			(drill 0.508)
			(layers "*.Cu" "*.Mask")
			(remove_unused_layers no)
			(net "SERIAL_B1_RX1")
		)
		(pad "B4" thru_hole circle
			(at 6.000001 1.3 180)
			(size 0.8128 0.8128)
			(drill 0.508)
			(layers "*.Cu" "*.Mask")
			(remove_unused_layers no)
			(net "JBOD_B1_MATED_N")
		)
		(pad "B5" thru_hole circle
			(at 7.999999 1.4 180)
			(size 0.8128 0.8128)
			(drill 0.508)
			(layers "*.Cu" "*.Mask")
			(remove_unused_layers no)
			(net "SAS_B1_TX6N")
		)
		(pad "B6" thru_hole circle
			(at 10 1.3 180)
			(size 0.8128 0.8128)
			(drill 0.508)
			(layers "*.Cu" "*.Mask")
			(remove_unused_layers no)
			(net "SAS_B1_RX8P")
		)
		(pad "C1" thru_hole circle
			(at 0 2.799999 180)
			(size 0.8128 0.8128)
			(drill 0.508)
			(layers "*.Cu" "*.Mask")
			(remove_unused_layers no)
			(net "GND")
		)
		(pad "C2" thru_hole circle
			(at 2.000001 2.7 180)
			(size 0.8128 0.8128)
			(drill 0.508)
			(layers "*.Cu" "*.Mask")
			(remove_unused_layers no)
			(net "SAS_B1_RX3N")
		)
		(pad "C3" thru_hole circle
			(at 4 2.799999 180)
			(size 0.8128 0.8128)
			(drill 0.508)
			(layers "*.Cu" "*.Mask")
			(remove_unused_layers no)
			(net "GND")
		)
		(pad "C4" thru_hole circle
			(at 6.000001 2.7 180)
			(size 0.8128 0.8128)
			(drill 0.508)
			(layers "*.Cu" "*.Mask")
			(remove_unused_layers no)
			(net "BLADE_B1_EN1")
		)
		(pad "C5" thru_hole circle
			(at 7.999999 2.799999 180)
			(size 0.8128 0.8128)
			(drill 0.508)
			(layers "*.Cu" "*.Mask")
			(remove_unused_layers no)
			(net "GND")
		)
		(pad "C6" thru_hole circle
			(at 10 2.7 180)
			(size 0.8128 0.8128)
			(drill 0.508)
			(layers "*.Cu" "*.Mask")
			(remove_unused_layers no)
			(net "SAS_B1_RX8N")
		)
		(pad "D1" thru_hole circle
			(at 0 4.199999 180)
			(size 0.8128 0.8128)
			(drill 0.508)
			(layers "*.Cu" "*.Mask")
			(remove_unused_layers no)
			(net "SAS_B1_RX1P")
		)
		(pad "D2" thru_hole circle
			(at 2.000001 4.099999 180)
			(size 0.8128 0.8128)
			(drill 0.508)
			(layers "*.Cu" "*.Mask")
			(remove_unused_layers no)
			(net "GND")
		)
		(pad "D3" thru_hole circle
			(at 4 4.199999 180)
			(size 0.8128 0.8128)
			(drill 0.508)
			(layers "*.Cu" "*.Mask")
			(remove_unused_layers no)
			(net "SAS_B1_RX4P")
		)
		(pad "D4" thru_hole circle
			(at 6.000001 4.099999 180)
			(size 0.8128 0.8128)
			(drill 0.508)
			(layers "*.Cu" "*.Mask")
			(remove_unused_layers no)
			(net "GND")
		)
		(pad "D5" thru_hole circle
			(at 7.999999 4.199999 180)
			(size 0.8128 0.8128)
			(drill 0.508)
			(layers "*.Cu" "*.Mask")
			(remove_unused_layers no)
			(net "SAS_B1_RX6P")
		)
		(pad "D6" thru_hole circle
			(at 10 4.099999 180)
			(size 0.8128 0.8128)
			(drill 0.508)
			(layers "*.Cu" "*.Mask")
			(remove_unused_layers no)
			(net "GND")
		)
		(pad "E1" thru_hole circle
			(at 0 5.599999 180)
			(size 0.8128 0.8128)
			(drill 0.508)
			(layers "*.Cu" "*.Mask")
			(remove_unused_layers no)
			(net "SAS_B1_RX1N")
		)
		(pad "E2" thru_hole circle
			(at 2.000001 5.499999 180)
			(size 0.8128 0.8128)
			(drill 0.508)
			(layers "*.Cu" "*.Mask")
			(remove_unused_layers no)
			(net "SAS_B1_TX3P")
		)
		(pad "E3" thru_hole circle
			(at 4 5.599999 180)
			(size 0.8128 0.8128)
			(drill 0.508)
			(layers "*.Cu" "*.Mask")
			(remove_unused_layers no)
			(net "SAS_B1_RX4N")
		)
		(pad "E4" thru_hole circle
			(at 6.000001 5.499999 180)
			(size 0.8128 0.8128)
			(drill 0.508)
			(layers "*.Cu" "*.Mask")
			(remove_unused_layers no)
			(net "SAS_B1_TX5P")
		)
		(pad "E5" thru_hole circle
			(at 7.999999 5.599999 180)
			(size 0.8128 0.8128)
			(drill 0.508)
			(layers "*.Cu" "*.Mask")
			(remove_unused_layers no)
			(net "SAS_B1_RX6N")
		)
		(pad "E6" thru_hole circle
			(at 10 5.499999 180)
			(size 0.8128 0.8128)
			(drill 0.508)
			(layers "*.Cu" "*.Mask")
			(remove_unused_layers no)
			(net "SAS_B1_TX8P")
		)
		(pad "F1" thru_hole circle
			(at 0 7.000001 180)
			(size 0.8128 0.8128)
			(drill 0.508)
			(layers "*.Cu" "*.Mask")
			(remove_unused_layers no)
			(net "GND")
		)
		(pad "F2" thru_hole circle
			(at 2.000001 6.899999 180)
			(size 0.8128 0.8128)
			(drill 0.508)
			(layers "*.Cu" "*.Mask")
			(remove_unused_layers no)
			(net "SAS_B1_TX3N")
		)
		(pad "F3" thru_hole circle
			(at 4 7.000001 180)
			(size 0.8128 0.8128)
			(drill 0.508)
			(layers "*.Cu" "*.Mask")
			(remove_unused_layers no)
			(net "GND")
		)
		(pad "F4" thru_hole circle
			(at 6.000001 6.899999 180)
			(size 0.8128 0.8128)
			(drill 0.508)
			(layers "*.Cu" "*.Mask")
			(remove_unused_layers no)
			(net "SAS_B1_TX5N")
		)
		(pad "F5" thru_hole circle
			(at 7.999999 7.000001 180)
			(size 0.8128 0.8128)
			(drill 0.508)
			(layers "*.Cu" "*.Mask")
			(remove_unused_layers no)
			(net "GND")
		)
		(pad "F6" thru_hole circle
			(at 10 6.899999 180)
			(size 0.8128 0.8128)
			(drill 0.508)
			(layers "*.Cu" "*.Mask")
			(remove_unused_layers no)
			(net "SAS_B1_TX8N")
		)
		(pad "G1" thru_hole circle
			(at 0 8.400001 180)
			(size 0.8128 0.8128)
			(drill 0.508)
			(layers "*.Cu" "*.Mask")
			(remove_unused_layers no)
			(net "SAS_B1_TX2P")
		)
		(pad "G2" thru_hole circle
			(at 2.000001 8.300001 180)
			(size 0.8128 0.8128)
			(drill 0.508)
			(layers "*.Cu" "*.Mask")
			(remove_unused_layers no)
			(net "GND")
		)
		(pad "G3" thru_hole circle
			(at 4 8.400001 180)
			(size 0.8128 0.8128)
			(drill 0.508)
			(layers "*.Cu" "*.Mask")
			(remove_unused_layers no)
			(net "SAS_B1_TX4P")
		)
		(pad "G4" thru_hole circle
			(at 6.000001 8.300001 180)
			(size 0.8128 0.8128)
			(drill 0.508)
			(layers "*.Cu" "*.Mask")
			(remove_unused_layers no)
			(net "GND")
		)
		(pad "G5" thru_hole circle
			(at 7.999999 8.400001 180)
			(size 0.8128 0.8128)
			(drill 0.508)
			(layers "*.Cu" "*.Mask")
			(remove_unused_layers no)
			(net "SAS_B1_TX7P")
		)
		(pad "G6" thru_hole circle
			(at 10 8.300001 180)
			(size 0.8128 0.8128)
			(drill 0.508)
			(layers "*.Cu" "*.Mask")
			(remove_unused_layers no)
			(net "GND")
		)
		(pad "H1" thru_hole circle
			(at 0 9.800001 180)
			(size 0.8128 0.8128)
			(drill 0.508)
			(layers "*.Cu" "*.Mask")
			(remove_unused_layers no)
			(net "SAS_B1_TX2N")
		)
		(pad "H2" thru_hole circle
			(at 2.000001 9.700001 180)
			(size 0.8128 0.8128)
			(drill 0.508)
			(layers "*.Cu" "*.Mask")
			(remove_unused_layers no)
			(net "SAS_B1_RX2P")
		)
		(pad "H3" thru_hole circle
			(at 4 9.800001 180)
			(size 0.8128 0.8128)
			(drill 0.508)
			(layers "*.Cu" "*.Mask")
			(remove_unused_layers no)
			(net "SAS_B1_TX4N")
		)
		(pad "H4" thru_hole circle
			(at 6.000001 9.700001 180)
			(size 0.8128 0.8128)
			(drill 0.508)
			(layers "*.Cu" "*.Mask")
			(remove_unused_layers no)
			(net "SAS_B1_RX5P")
		)
		(pad "H5" thru_hole circle
			(at 7.999999 9.800001 180)
			(size 0.8128 0.8128)
			(drill 0.508)
			(layers "*.Cu" "*.Mask")
			(remove_unused_layers no)
			(net "SAS_B1_TX7N")
		)
		(pad "H6" thru_hole circle
			(at 10 9.700001 180)
			(size 0.8128 0.8128)
			(drill 0.508)
			(layers "*.Cu" "*.Mask")
			(remove_unused_layers no)
			(net "SAS_B1_RX7P")
		)
		(pad "I1" thru_hole circle
			(at 0 11.2 180)
			(size 0.8128 0.8128)
			(drill 0.508)
			(layers "*.Cu" "*.Mask")
			(remove_unused_layers no)
			(net "GND")
		)
		(pad "I2" thru_hole circle
			(at 2.000001 11.100001 180)
			(size 0.8128 0.8128)
			(drill 0.508)
			(layers "*.Cu" "*.Mask")
			(remove_unused_layers no)
			(net "SAS_B1_RX2N")
		)
		(pad "I3" thru_hole circle
			(at 4 11.2 180)
			(size 0.8128 0.8128)
			(drill 0.508)
			(layers "*.Cu" "*.Mask")
			(remove_unused_layers no)
			(net "GND")
		)
		(pad "I4" thru_hole circle
			(at 6.000001 11.100001 180)
			(size 0.8128 0.8128)
			(drill 0.508)
			(layers "*.Cu" "*.Mask")
			(remove_unused_layers no)
			(net "SAS_B1_RX5N")
		)
		(pad "I5" thru_hole circle
			(at 7.999999 11.2 180)
			(size 0.8128 0.8128)
			(drill 0.508)
			(layers "*.Cu" "*.Mask")
			(remove_unused_layers no)
			(net "GND")
		)
		(pad "I6" thru_hole circle
			(at 10 11.100001 180)
			(size 0.8128 0.8128)
			(drill 0.508)
			(layers "*.Cu" "*.Mask")
			(remove_unused_layers no)
			(net "SAS_B1_RX7N")
		)
		(pad "J2" thru_hole circle
			(at 2.000001 12.5 180)
			(size 0.8128 0.8128)
			(drill 0.508)
			(layers "*.Cu" "*.Mask")
			(remove_unused_layers no)
			(net "GND")
		)
		(pad "J4" thru_hole circle
			(at 6.000001 12.5 180)
			(size 0.8128 0.8128)
			(drill 0.508)
			(layers "*.Cu" "*.Mask")
			(remove_unused_layers no)
			(net "GND")
		)
		(pad "J6" thru_hole circle
			(at 10 12.5 180)
			(size 0.8128 0.8128)
			(drill 0.508)
			(layers "*.Cu" "*.Mask")
			(remove_unused_layers no)
			(net "GND")
		)
	)
	(footprint ""
		(layer "F.Cu")
		(at -44.831 2.54 180)
		(property "Reference" "R59"
			(at -3.02514 0.01016 0)
			(unlocked yes)
			(layer "F.SilkS")
			(effects
				(font
					(size 0.762 0.5334)
					(thickness 0.1016)
				)
			)
		)
		(property "Value" ""
			(at 0 0 180)
			(layer "F.Fab")
			(effects
				(font
					(size 1.27 1.27)
				)
			)
		)
		(duplicate_pad_numbers_are_jumpers no)
		(fp_line
			(start 0 -0.381)
			(end 0 0.381)
			(stroke
				(width 0.127)
				(type default)
			)
			(layer "F.SilkS")
		)
		(fp_poly
			(pts
				(xy 1.255601 0.656399) (xy -1.255601 0.656399) (xy -1.255601 -0.6564) (xy 1.255601 -0.6564)
			)
			(stroke
				(width 0)
				(type default)
			)
			(fill no)
			(layer "F.CrtYd")
		)
		(fp_line
			(start 0.800001 0.399999)
			(end 0.800001 -0.399999)
			(stroke
				(width 0.1)
				(type default)
			)
			(layer "F.Fab")
		)
		(fp_line
			(start 0.800001 -0.399999)
			(end -0.800001 -0.399999)
			(stroke
				(width 0.1)
				(type default)
			)
			(layer "F.Fab")
		)
		(fp_line
			(start -0.800001 0.399999)
			(end 0.800001 0.399999)
			(stroke
				(width 0.1)
				(type default)
			)
			(layer "F.Fab")
		)
		(fp_line
			(start -0.800001 -0.399999)
			(end -0.800001 0.399999)
			(stroke
				(width 0.1)
				(type default)
			)
			(layer "F.Fab")
		)
		(pad "1" smd rect
			(at -0.650001 0 180)
			(size 0.7112 0.8128)
			(layers "F.Cu" "F.Mask" "F.Paste")
			(net "P3V3_B2_QSFP")
		)
		(pad "2" smd rect
			(at 0.650001 0)
			(size 0.7112 0.8128)
			(layers "F.Cu" "F.Mask" "F.Paste")
			(net "P3V3_40G_B2_VCC_RX")
		)
	)
	(footprint ""
		(layer "F.Cu")
		(at -61.750001 32.059999 180)
		(property "Reference" "J18"
			(at -7.048561 -7.203321 0)
			(unlocked yes)
			(layer "F.SilkS")
			(effects
				(font
					(size 0.762 0.5334)
					(thickness 0.1016)
				)
			)
		)
		(property "Value" ""
			(at 0 0 180)
			(layer "F.Fab")
			(effects
				(font
					(size 1.27 1.27)
				)
			)
		)
		(duplicate_pad_numbers_are_jumpers no)
		(fp_line
			(start 8.099999 42.399999)
			(end 8.099999 27.999999)
			(stroke
				(width 0.127)
				(type default)
			)
			(layer "F.SilkS")
		)
		(fp_line
			(start 8.099999 23.099999)
			(end 8.099999 17.999999)
			(stroke
				(width 0.127)
				(type default)
			)
			(layer "F.SilkS")
		)
		(fp_line
			(start 8.099999 13.8)
			(end 8.099999 7.899999)
			(stroke
				(width 0.127)
				(type default)
			)
			(layer "F.SilkS")
		)
		(fp_line
			(start 8.099999 4.199999)
			(end 8.099999 -2.400001)
			(stroke
				(width 0.127)
				(type default)
			)
			(layer "F.SilkS")
		)
		(fp_line
			(start 8.099999 -5.699999)
			(end 8.099999 -6.3)
			(stroke
				(width 0.127)
				(type default)
			)
			(layer "F.SilkS")
		)
		(fp_line
			(start 8.099999 -6.3)
			(end 6.000001 -6.3)
			(stroke
				(width 0.127)
				(type default)
			)
			(layer "F.SilkS")
		)
		(fp_line
			(start -6.000001 -6.3)
			(end -8.099999 -6.3)
			(stroke
				(width 0.127)
				(type default)
			)
			(layer "F.SilkS")
		)
		(fp_line
			(start -8.099999 42.399999)
			(end 8.099999 42.399999)
			(stroke
				(width 0.127)
				(type default)
			)
			(layer "F.SilkS")
		)
		(fp_line
			(start -8.099999 32.8)
			(end -8.099999 42.399999)
			(stroke
				(width 0.127)
				(type default)
			)
			(layer "F.SilkS")
		)
		(fp_line
			(start -8.099999 22.999999)
			(end -8.099999 28.9)
			(stroke
				(width 0.127)
				(type default)
			)
			(layer "F.SilkS")
		)
		(fp_line
			(start -8.099999 12.999999)
			(end -8.099999 18.600001)
			(stroke
				(width 0.127)
				(type default)
			)
			(layer "F.SilkS")
		)
		(fp_line
			(start -8.099999 2.5)
			(end -8.099999 9.099999)
			(stroke
				(width 0.127)
				(type default)
			)
			(layer "F.SilkS")
		)
		(fp_line
			(start -8.099999 -6.3)
			(end -8.099999 -0.700002)
			(stroke
				(width 0.127)
				(type default)
			)
			(layer "F.SilkS")
		)
		(fp_poly
			(pts
				(arc
					(start 5.2054 34.950301)
					(mid 3.459364 36.043267)
					(end 1.434201 36.42)
				)
				(arc
					(start -7.124799 36.42)
					(mid -11.028153 34.803295)
					(end -12.644999 30.899999)
				)
				(xy -12.6495 30.899999) (xy -12.6495 0.9)
				(arc
					(start -12.644999 0.9)
					(mid -12.630104 0.494905)
					(end -12.585499 0.091998)
				)
				(arc
					(start -12.368601 -1.986699)
					(mid -12.153073 -3.137304)
					(end -11.6883 -4.211701)
				)
				(arc
					(start -9.540999 -8.473202)
					(mid -7.601127 -10.649546)
					(end -4.800001 -11.457801)
				)
				(arc
					(start 4.800001 -11.457801)
					(mid 6.526796 -11.166136)
					(end 8.062001 -10.3235)
				)
				(arc
					(start 10.390299 -8.5507)
					(mid 12.049188 -6.594625)
					(end 12.644999 -4.1)
				)
				(xy 12.6495 -4.1) (xy 12.6495 25.899999)
				(arc
					(start 12.644999 25.899999)
					(mid 12.153739 28.176398)
					(end 10.7674 30.0476)
				)
			)
			(stroke
				(width 0)
				(type default)
			)
			(fill no)
			(layer "B.CrtYd")
		)
		(fp_poly
			(pts
				(xy 9.1 43.399999) (xy -9.1 43.399999) (xy -9.1 -7.9) (xy 9.1 -7.9)
			)
			(stroke
				(width 0)
				(type default)
			)
			(fill no)
			(layer "F.CrtYd")
		)
		(fp_line
			(start 8.099999 42.399999)
			(end -8.099999 42.399999)
			(stroke
				(width 0.1)
				(type default)
			)
			(layer "F.Fab")
		)
		(fp_line
			(start 8.099999 -6.32)
			(end 8.099999 42.399999)
			(stroke
				(width 0.1)
				(type default)
			)
			(layer "F.Fab")
		)
		(fp_line
			(start -8.099999 42.399999)
			(end -8.099999 -6.32)
			(stroke
				(width 0.1)
				(type default)
			)
			(layer "F.Fab")
		)
		(fp_line
			(start -8.099999 -6.32)
			(end 8.099999 -6.32)
			(stroke
				(width 0.1)
				(type default)
			)
			(layer "F.Fab")
		)
		(pad "1" thru_hole circle
			(at 0 -6.2 180)
			(size 1.4732 1.4732)
			(drill 0.9652)
			(layers "*.Cu" "*.Mask")
			(remove_unused_layers no)
			(net "GND")
		)
		(pad "2" thru_hole circle
			(at -4.800001 -6.2 180)
			(size 1.4732 1.4732)
			(drill 0.9652)
			(layers "*.Cu" "*.Mask")
			(remove_unused_layers no)
			(net "GND")
		)
		(pad "3" thru_hole circle
			(at 4.800001 -6.2 180)
			(size 1.4732 1.4732)
			(drill 0.9652)
			(layers "*.Cu" "*.Mask")
			(remove_unused_layers no)
			(net "GND")
		)
		(pad "4" thru_hole rect
			(at 7.125 -4.099999 180)
			(size 2.0066 2.0066)
			(drill 1.0414)
			(layers "*.Cu" "*.Mask")
			(remove_unused_layers no)
			(net "GND")
			(padstack
				(mode front_inner_back)
				(layer "Inner"
					(shape circle)
					(size 2.0066 2.0066)
				)
				(layer "B.Cu"
					(shape rect)
					(size 2.0066 2.0066)
				)
			)
		)
		(pad "5" thru_hole circle
			(at -7.125 -1.599999 180)
			(size 1.4732 1.4732)
			(drill 0.9652)
			(layers "*.Cu" "*.Mask")
			(remove_unused_layers no)
			(net "GND")
		)
		(pad "6" thru_hole circle
			(at 7.125 -1.599999 180)
			(size 1.4732 1.4732)
			(drill 0.9652)
			(layers "*.Cu" "*.Mask")
			(remove_unused_layers no)
			(net "GND")
		)
		(pad "7" thru_hole rect
			(at -7.125 0.900001 180)
			(size 2.0066 2.0066)
			(drill 0.8382)
			(layers "*.Cu" "*.Mask")
			(remove_unused_layers no)
			(net "GND")
			(padstack
				(mode front_inner_back)
				(layer "Inner"
					(shape circle)
					(size 2.0066 2.0066)
				)
				(layer "B.Cu"
					(shape rect)
					(size 2.0066 2.0066)
				)
			)
		)
		(pad "8" thru_hole circle
			(at -7.125 3.400001 180)
			(size 1.4732 1.4732)
			(drill 0.9652)
			(layers "*.Cu" "*.Mask")
			(remove_unused_layers no)
			(net "GND")
		)
		(pad "9" thru_hole circle
			(at 7.125 3.400001 180)
			(size 1.4732 1.4732)
			(drill 0.9652)
			(layers "*.Cu" "*.Mask")
			(remove_unused_layers no)
			(net "GND")
		)
		(pad "10" thru_hole rect
			(at 7.125 5.900001 180)
			(size 2.0066 2.0066)
			(drill 1.0414)
			(layers "*.Cu" "*.Mask")
			(remove_unused_layers no)
			(net "GND")
			(padstack
				(mode front_inner_back)
				(layer "Inner"
					(shape circle)
					(size 2.0066 2.0066)
				)
				(layer "B.Cu"
					(shape rect)
					(size 2.0066 2.0066)
				)
			)
		)
		(pad "11" thru_hole circle
			(at -7.125 8.099999 180)
			(size 1.4732 1.4732)
			(drill 0.9652)
			(layers "*.Cu" "*.Mask")
			(remove_unused_layers no)
			(net "GND")
		)
		(pad "12" thru_hole circle
			(at 7.125 8.099999 180)
			(size 1.4732 1.4732)
			(drill 0.9652)
			(layers "*.Cu" "*.Mask")
			(remove_unused_layers no)
			(net "GND")
		)
		(pad "13" thru_hole rect
			(at -7.125 10.900001 180)
			(size 2.0066 2.0066)
			(drill 1.0414)
			(layers "*.Cu" "*.Mask")
			(remove_unused_layers no)
			(net "GND")
			(padstack
				(mode front_inner_back)
				(layer "Inner"
					(shape circle)
					(size 2.0066 2.0066)
				)
				(layer "B.Cu"
					(shape rect)
					(size 2.0066 2.0066)
				)
			)
		)
		(pad "14" thru_hole rect
			(at -1.445001 10.900001 180)
			(size 2.0066 2.0066)
			(drill 1.0414)
			(layers "*.Cu" "*.Mask")
			(remove_unused_layers no)
			(net "GND")
			(padstack
				(mode front_inner_back)
				(layer "Inner"
					(shape circle)
					(size 2.0066 2.0066)
				)
				(layer "B.Cu"
					(shape rect)
					(size 2.0066 2.0066)
				)
			)
		)
		(pad "15" thru_hole rect
			(at 3.955001 10.900001 180)
			(size 2.0066 2.0066)
			(drill 1.0414)
			(layers "*.Cu" "*.Mask")
			(remove_unused_layers no)
			(net "GND")
			(padstack
				(mode front_inner_back)
				(layer "Inner"
					(shape circle)
					(size 2.0066 2.0066)
				)
				(layer "B.Cu"
					(shape rect)
					(size 2.0066 2.0066)
				)
			)
		)
		(pad "16" thru_hole rect
			(at 7.125 15.900001 180)
			(size 2.0066 2.0066)
			(drill 1.0414)
			(layers "*.Cu" "*.Mask")
			(remove_unused_layers no)
			(net "GND")
			(padstack
				(mode front_inner_back)
				(layer "Inner"
					(shape circle)
					(size 2.0066 2.0066)
				)
				(layer "B.Cu"
					(shape rect)
					(size 2.0066 2.0066)
				)
			)
		)
		(pad "17" thru_hole rect
			(at -7.125 20.899999 180)
			(size 2.0066 2.0066)
			(drill 1.0414)
			(layers "*.Cu" "*.Mask")
			(remove_unused_layers no)
			(net "GND")
			(padstack
				(mode front_inner_back)
				(layer "Inner"
					(shape circle)
					(size 2.0066 2.0066)
				)
				(layer "B.Cu"
					(shape rect)
					(size 2.0066 2.0066)
				)
			)
		)
		(pad "18" thru_hole rect
			(at 7.125 25.899999 180)
			(size 2.0066 2.0066)
			(drill 1.0414)
			(layers "*.Cu" "*.Mask")
			(remove_unused_layers no)
			(net "GND")
			(padstack
				(mode front_inner_back)
				(layer "Inner"
					(shape circle)
					(size 2.0066 2.0066)
				)
				(layer "B.Cu"
					(shape rect)
					(size 2.0066 2.0066)
				)
			)
		)
		(pad "19" thru_hole rect
			(at -7.125 30.899999 180)
			(size 2.0066 2.0066)
			(drill 1.0414)
			(layers "*.Cu" "*.Mask")
			(remove_unused_layers no)
			(net "GND")
			(padstack
				(mode front_inner_back)
				(layer "Inner"
					(shape circle)
					(size 2.0066 2.0066)
				)
				(layer "B.Cu"
					(shape rect)
					(size 2.0066 2.0066)
				)
			)
		)
		(pad "20" thru_hole rect
			(at 1.455001 30.899999 180)
			(size 2.0066 2.0066)
			(drill 1.0414)
			(layers "*.Cu" "*.Mask")
			(remove_unused_layers no)
			(net "GND")
			(padstack
				(mode front_inner_back)
				(layer "Inner"
					(shape circle)
					(size 2.0066 2.0066)
				)
				(layer "B.Cu"
					(shape rect)
					(size 2.0066 2.0066)
				)
			)
		)
	)
	(footprint ""
		(layer "F.Cu")
		(at -110.8456 11.8364)
		(property "Reference" "R65"
			(at 2.6416 0.0127 0)
			(unlocked yes)
			(layer "F.SilkS")
			(effects
				(font
					(size 0.762 0.5334)
					(thickness 0.1016)
				)
			)
		)
		(property "Value" ""
			(at 0 0 0)
			(layer "F.Fab")
			(effects
				(font
					(size 1.27 1.27)
				)
			)
		)
		(duplicate_pad_numbers_are_jumpers no)
		(fp_line
			(start 0 -0.381)
			(end 0 0.381)
			(stroke
				(width 0.127)
				(type default)
			)
			(layer "F.SilkS")
		)
		(fp_poly
			(pts
				(xy 1.255601 0.6564) (xy -1.255601 0.6564) (xy -1.255601 -0.656399) (xy 1.255601 -0.656399)
			)
			(stroke
				(width 0)
				(type default)
			)
			(fill no)
			(layer "F.CrtYd")
		)
		(fp_line
			(start -0.800001 -0.399999)
			(end -0.800001 0.399999)
			(stroke
				(width 0.1)
				(type default)
			)
			(layer "F.Fab")
		)
		(fp_line
			(start -0.800001 0.399999)
			(end 0.800001 0.399999)
			(stroke
				(width 0.1)
				(type default)
			)
			(layer "F.Fab")
		)
		(fp_line
			(start 0.800001 -0.399999)
			(end -0.800001 -0.399999)
			(stroke
				(width 0.1)
				(type default)
			)
			(layer "F.Fab")
		)
		(fp_line
			(start 0.800001 0.399999)
			(end 0.800001 -0.399999)
			(stroke
				(width 0.1)
				(type default)
			)
			(layer "F.Fab")
		)
		(pad "1" smd rect
			(at -0.650001 0)
			(size 0.7112 0.8128)
			(layers "F.Cu" "F.Mask" "F.Paste")
			(net "ETH40G_B2_LPMODE")
		)
		(pad "2" smd rect
			(at 0.650001 0 180)
			(size 0.7112 0.8128)
			(layers "F.Cu" "F.Mask" "F.Paste")
			(net "GND")
		)
	)
	(footprint ""
		(layer "F.Cu")
		(at -110.8456 17.4244 180)
		(property "Reference" "R61"
			(at -2.5146 -0.0127 0)
			(unlocked yes)
			(layer "F.SilkS")
			(effects
				(font
					(size 0.762 0.5334)
					(thickness 0.1016)
				)
			)
		)
		(property "Value" ""
			(at 0 0 180)
			(layer "F.Fab")
			(effects
				(font
					(size 1.27 1.27)
				)
			)
		)
		(duplicate_pad_numbers_are_jumpers no)
		(fp_line
			(start 0 -0.381)
			(end 0 0.381)
			(stroke
				(width 0.127)
				(type default)
			)
			(layer "F.SilkS")
		)
		(fp_poly
			(pts
				(xy 1.255601 0.656399) (xy -1.255601 0.656399) (xy -1.255601 -0.6564) (xy 1.255601 -0.6564)
			)
			(stroke
				(width 0)
				(type default)
			)
			(fill no)
			(layer "F.CrtYd")
		)
		(fp_line
			(start 0.800001 0.399999)
			(end 0.800001 -0.399999)
			(stroke
				(width 0.1)
				(type default)
			)
			(layer "F.Fab")
		)
		(fp_line
			(start 0.800001 -0.399999)
			(end -0.800001 -0.399999)
			(stroke
				(width 0.1)
				(type default)
			)
			(layer "F.Fab")
		)
		(fp_line
			(start -0.800001 0.399999)
			(end 0.800001 0.399999)
			(stroke
				(width 0.1)
				(type default)
			)
			(layer "F.Fab")
		)
		(fp_line
			(start -0.800001 -0.399999)
			(end -0.800001 0.399999)
			(stroke
				(width 0.1)
				(type default)
			)
			(layer "F.Fab")
		)
		(pad "1" smd rect
			(at -0.650001 0 180)
			(size 0.7112 0.8128)
			(layers "F.Cu" "F.Mask" "F.Paste")
			(net "SKU_B2_ID2")
		)
		(pad "2" smd rect
			(at 0.650001 0)
			(size 0.7112 0.8128)
			(layers "F.Cu" "F.Mask" "F.Paste")
			(net "ETH40G_B2_RESET_N")
		)
	)
	(footprint ""
		(layer "F.Cu")
		(at -75.3618 10.9982 180)
		(property "Reference" "R56"
			(at -3.048 -0.0381 0)
			(unlocked yes)
			(layer "F.SilkS")
			(effects
				(font
					(size 0.762 0.5334)
					(thickness 0.1016)
				)
			)
		)
		(property "Value" ""
			(at 0 0 180)
			(layer "F.Fab")
			(effects
				(font
					(size 1.27 1.27)
				)
			)
		)
		(duplicate_pad_numbers_are_jumpers no)
		(fp_line
			(start 0 -0.381)
			(end 0 0.381)
			(stroke
				(width 0.127)
				(type default)
			)
			(layer "F.SilkS")
		)
		(fp_poly
			(pts
				(xy 1.255601 0.656399) (xy -1.255601 0.656399) (xy -1.255601 -0.6564) (xy 1.255601 -0.6564)
			)
			(stroke
				(width 0)
				(type default)
			)
			(fill no)
			(layer "F.CrtYd")
		)
		(fp_line
			(start 0.800001 0.399999)
			(end 0.800001 -0.399999)
			(stroke
				(width 0.1)
				(type default)
			)
			(layer "F.Fab")
		)
		(fp_line
			(start 0.800001 -0.399999)
			(end -0.800001 -0.399999)
			(stroke
				(width 0.1)
				(type default)
			)
			(layer "F.Fab")
		)
		(fp_line
			(start -0.800001 0.399999)
			(end 0.800001 0.399999)
			(stroke
				(width 0.1)
				(type default)
			)
			(layer "F.Fab")
		)
		(fp_line
			(start -0.800001 -0.399999)
			(end -0.800001 0.399999)
			(stroke
				(width 0.1)
				(type default)
			)
			(layer "F.Fab")
		)
		(pad "1" smd rect
			(at -0.650001 0 180)
			(size 0.7112 0.8128)
			(layers "F.Cu" "F.Mask" "F.Paste")
			(net "P3V3_B2_QSFP")
		)
		(pad "2" smd rect
			(at 0.650001 0)
			(size 0.7112 0.8128)
			(layers "F.Cu" "F.Mask" "F.Paste")
			(net "ETH10G_B2_SCL")
		)
	)
	(footprint ""
		(layer "F.Cu")
		(at -266.192 2.54 180)
		(property "Reference" "R73"
			(at -3.175 -0.1651 0)
			(unlocked yes)
			(layer "F.SilkS")
			(effects
				(font
					(size 0.762 0.5334)
					(thickness 0.1016)
				)
			)
		)
		(property "Value" ""
			(at 0 0 180)
			(layer "F.Fab")
			(effects
				(font
					(size 1.27 1.27)
				)
			)
		)
		(duplicate_pad_numbers_are_jumpers no)
		(fp_line
			(start 0 -0.381)
			(end 0 0.381)
			(stroke
				(width 0.127)
				(type default)
			)
			(layer "F.SilkS")
		)
		(fp_poly
			(pts
				(xy 1.255601 0.656399) (xy -1.255601 0.656399) (xy -1.255601 -0.6564) (xy 1.255601 -0.6564)
			)
			(stroke
				(width 0)
				(type default)
			)
			(fill no)
			(layer "F.CrtYd")
		)
		(fp_line
			(start 0.800001 0.399999)
			(end 0.800001 -0.399999)
			(stroke
				(width 0.1)
				(type default)
			)
			(layer "F.Fab")
		)
		(fp_line
			(start 0.800001 -0.399999)
			(end -0.800001 -0.399999)
			(stroke
				(width 0.1)
				(type default)
			)
			(layer "F.Fab")
		)
		(fp_line
			(start -0.800001 0.399999)
			(end 0.800001 0.399999)
			(stroke
				(width 0.1)
				(type default)
			)
			(layer "F.Fab")
		)
		(fp_line
			(start -0.800001 -0.399999)
			(end -0.800001 0.399999)
			(stroke
				(width 0.1)
				(type default)
			)
			(layer "F.Fab")
		)
		(pad "1" smd rect
			(at -0.650001 0 180)
			(size 0.7112 0.8128)
			(layers "F.Cu" "F.Mask" "F.Paste")
			(net "P3V3_B1_QSFP")
		)
		(pad "2" smd rect
			(at 0.650001 0)
			(size 0.7112 0.8128)
			(layers "F.Cu" "F.Mask" "F.Paste")
			(net "P3V3_40G_B1_VCC_RX")
		)
	)
	(footprint ""
		(layer "F.Cu")
		(at -267.774001 11.646002 90)
		(property "Reference" "FB10"
			(at 0.558902 -3.624999 0)
			(unlocked yes)
			(layer "F.SilkS")
			(effects
				(font
					(size 0.762 0.5334)
					(thickness 0.1016)
				)
				(justify left)
			)
		)
		(property "Value" ""
			(at 0 0 90)
			(layer "F.Fab")
			(effects
				(font
					(size 1.27 1.27)
				)
			)
		)
		(duplicate_pad_numbers_are_jumpers no)
		(fp_poly
			(pts
				(xy -1.016 0.508) (xy -1.016 -0.508) (xy 1.016 -0.508) (xy 1.016 0.508)
			)
			(stroke
				(width 0)
				(type default)
			)
			(fill no)
			(layer "F.CrtYd")
		)
		(fp_line
			(start 0.508 -0.254)
			(end 0.508 0.254)
			(stroke
				(width 0.1)
				(type default)
			)
			(layer "F.Fab")
		)
		(fp_line
			(start -0.508 -0.254)
			(end 0.508 -0.254)
			(stroke
				(width 0.1)
				(type default)
			)
			(layer "F.Fab")
		)
		(fp_line
			(start 0.508 0.254)
			(end -0.508 0.254)
			(stroke
				(width 0.1)
				(type default)
			)
			(layer "F.Fab")
		)
		(fp_line
			(start -0.508 0.254)
			(end -0.508 -0.254)
			(stroke
				(width 0.1)
				(type default)
			)
			(layer "F.Fab")
		)
		(pad "1" smd rect
			(at -0.4572 0 180)
			(size 0.508 0.5842)
			(layers "F.Cu" "F.Mask" "F.Paste")
			(net "P3V3_40G_B1_VCC1")
		)
		(pad "2" smd rect
			(at 0.4572 0 180)
			(size 0.508 0.5842)
			(layers "F.Cu" "F.Mask" "F.Paste")
			(net "UNNAMED_16_FERRITE_I46_B")
		)
	)
	(footprint ""
		(layer "F.Cu")
		(at -375.079999 30.959999 90)
		(property "Reference" "J2"
			(at 17.249079 1.136119 0)
			(unlocked yes)
			(layer "F.SilkS")
			(effects
				(font
					(size 0.762 0.5334)
					(thickness 0.1016)
				)
			)
		)
		(property "Value" ""
			(at 0 0 90)
			(layer "F.Fab")
			(effects
				(font
					(size 1.27 1.27)
				)
			)
		)
		(duplicate_pad_numbers_are_jumpers no)
		(fp_line
			(start 16.0274 -5.3721)
			(end -16.0274 -5.3721)
			(stroke
				(width 0.127)
				(type default)
			)
			(layer "F.SilkS")
		)
		(fp_line
			(start -16.0274 -5.3721)
			(end -16.0274 5.3721)
			(stroke
				(width 0.127)
				(type default)
			)
			(layer "F.SilkS")
		)
		(fp_line
			(start 16.0274 5.3721)
			(end 16.0274 -5.3721)
			(stroke
				(width 0.127)
				(type default)
			)
			(layer "F.SilkS")
		)
		(fp_line
			(start -16.0274 5.3721)
			(end 16.0274 5.3721)
			(stroke
				(width 0.127)
				(type default)
			)
			(layer "F.SilkS")
		)
		(fp_rect
			(start -16.5354 5.8801)
			(end 16.5354 -5.8801)
			(stroke
				(width 0)
				(type default)
			)
			(fill no)
			(layer "F.CrtYd")
		)
		(fp_line
			(start 16.0274 -5.3721)
			(end -16.0274 -5.3721)
			(stroke
				(width 0.1)
				(type default)
			)
			(layer "F.Fab")
		)
		(fp_line
			(start -16.0274 -5.3721)
			(end -16.0274 5.3721)
			(stroke
				(width 0.1)
				(type default)
			)
			(layer "F.Fab")
		)
		(fp_line
			(start 16.0274 5.3721)
			(end 16.0274 -5.3721)
			(stroke
				(width 0.1)
				(type default)
			)
			(layer "F.Fab")
		)
		(fp_line
			(start -16.0274 5.3721)
			(end 16.0274 5.3721)
			(stroke
				(width 0.1)
				(type default)
			)
			(layer "F.Fab")
		)
		(fp_text user "153"
			(at 12.125899 -6.809001 0)
			(unlocked yes)
			(layer "F.SilkS")
			(effects
				(font
					(size 0.762 0.5334)
					(thickness 0.1016)
				)
			)
		)
		(fp_text user "*"
			(at -12.065 -6.17855 270)
			(unlocked yes)
			(layer "F.SilkS")
			(effects
				(font
					(size 0.381 0.381)
					(thickness 0.381)
				)
			)
		)
		(fp_text user "8"
			(at -12.004101 6.144999 0)
			(unlocked yes)
			(layer "F.SilkS")
			(effects
				(font
					(size 0.762 0.5334)
					(thickness 0.1016)
				)
			)
		)
		(fp_text user "160"
			(at 12.181779 6.678399 0)
			(unlocked yes)
			(layer "F.SilkS")
			(effects
				(font
					(size 0.762 0.5334)
					(thickness 0.1016)
				)
			)
		)
		(pad "" np_thru_hole circle
			(at -14.4907 -3.048 90)
			(size 0.508 0.508)
			(drill 1.27)
			(layers "*.Cu" "*.Mask")
		)
		(pad "" np_thru_hole circle
			(at 14.4907 0 90)
			(size 0.508 0.508)
			(drill 1.27)
			(layers "*.Cu" "*.Mask")
		)
		(pad "1" smd circle
			(at -12.065 -4.445 90)
			(size 0.635 0.635)
			(layers "F.Cu" "F.Mask" "F.Paste")
			(net "GND")
		)
		(pad "2" smd circle
			(at -12.065 -3.175 90)
			(size 0.635 0.635)
			(layers "F.Cu" "F.Mask" "F.Paste")
			(net "PCIE_T2B_B1_RX_DP<7>")
		)
		(pad "3" smd circle
			(at -12.065 -1.905 90)
			(size 0.635 0.635)
			(layers "F.Cu" "F.Mask" "F.Paste")
			(net "GND")
		)
		(pad "4" smd circle
			(at -12.065 -0.635 90)
			(size 0.635 0.635)
			(layers "F.Cu" "F.Mask" "F.Paste")
			(net "PCIE_T2B_B1_RX_DP<15>")
		)
		(pad "5" smd circle
			(at -12.065 0.635 90)
			(size 0.635 0.635)
			(layers "F.Cu" "F.Mask" "F.Paste")
			(net "GND")
		)
		(pad "6" smd circle
			(at -12.065 1.905 90)
			(size 0.635 0.635)
			(layers "F.Cu" "F.Mask" "F.Paste")
			(net "PCIE_B2T_B1_TX_DP<7>")
		)
		(pad "7" smd circle
			(at -12.065 3.175 90)
			(size 0.635 0.635)
			(layers "F.Cu" "F.Mask" "F.Paste")
			(net "GND")
		)
		(pad "8" smd circle
			(at -12.065 4.445 90)
			(size 0.635 0.635)
			(layers "F.Cu" "F.Mask" "F.Paste")
			(net "PCIE_B2T_B1_TX_DP<15>")
		)
		(pad "9" smd circle
			(at -10.795 -4.445 90)
			(size 0.635 0.635)
			(layers "F.Cu" "F.Mask" "F.Paste")
			(net "GND")
		)
		(pad "10" smd circle
			(at -10.795 -3.175 90)
			(size 0.635 0.635)
			(layers "F.Cu" "F.Mask" "F.Paste")
			(net "PCIE_T2B_B1_RX_DN<7>")
		)
		(pad "11" smd circle
			(at -10.795 -1.905 90)
			(size 0.635 0.635)
			(layers "F.Cu" "F.Mask" "F.Paste")
			(net "GND")
		)
		(pad "12" smd circle
			(at -10.795 -0.635 90)
			(size 0.635 0.635)
			(layers "F.Cu" "F.Mask" "F.Paste")
			(net "PCIE_T2B_B1_RX_DN<15>")
		)
		(pad "13" smd circle
			(at -10.795 0.635 90)
			(size 0.635 0.635)
			(layers "F.Cu" "F.Mask" "F.Paste")
			(net "GND")
		)
		(pad "14" smd circle
			(at -10.795 1.905 90)
			(size 0.635 0.635)
			(layers "F.Cu" "F.Mask" "F.Paste")
			(net "PCIE_B2T_B1_TX_DN<7>")
		)
		(pad "15" smd circle
			(at -10.795 3.175 90)
			(size 0.635 0.635)
			(layers "F.Cu" "F.Mask" "F.Paste")
			(net "GND")
		)
		(pad "16" smd circle
			(at -10.795 4.445 90)
			(size 0.635 0.635)
			(layers "F.Cu" "F.Mask" "F.Paste")
			(net "PCIE_B2T_B1_TX_DN<15>")
		)
		(pad "17" smd circle
			(at -9.525 -4.445 90)
			(size 0.635 0.635)
			(layers "F.Cu" "F.Mask" "F.Paste")
			(net "PCIE_T2B_B1_RX_DP<6>")
		)
		(pad "18" smd circle
			(at -9.525 -3.175 90)
			(size 0.635 0.635)
			(layers "F.Cu" "F.Mask" "F.Paste")
			(net "GND")
		)
		(pad "19" smd circle
			(at -9.525 -1.905 90)
			(size 0.635 0.635)
			(layers "F.Cu" "F.Mask" "F.Paste")
			(net "PCIE_T2B_B1_RX_DP<14>")
		)
		(pad "20" smd circle
			(at -9.525 -0.635 90)
			(size 0.635 0.635)
			(layers "F.Cu" "F.Mask" "F.Paste")
			(net "GND")
		)
		(pad "21" smd circle
			(at -9.525 0.635 90)
			(size 0.635 0.635)
			(layers "F.Cu" "F.Mask" "F.Paste")
			(net "PCIE_B2T_B1_TX_DP<6>")
		)
		(pad "22" smd circle
			(at -9.525 1.905 90)
			(size 0.635 0.635)
			(layers "F.Cu" "F.Mask" "F.Paste")
			(net "GND")
		)
		(pad "23" smd circle
			(at -9.525 3.175 90)
			(size 0.635 0.635)
			(layers "F.Cu" "F.Mask" "F.Paste")
			(net "PCIE_B2T_B1_TX_DP<14>")
		)
		(pad "24" smd circle
			(at -9.525 4.445 90)
			(size 0.635 0.635)
			(layers "F.Cu" "F.Mask" "F.Paste")
			(net "GND")
		)
		(pad "25" smd circle
			(at -8.255 -4.445 90)
			(size 0.635 0.635)
			(layers "F.Cu" "F.Mask" "F.Paste")
			(net "PCIE_T2B_B1_RX_DN<6>")
		)
		(pad "26" smd circle
			(at -8.255 -3.175 90)
			(size 0.635 0.635)
			(layers "F.Cu" "F.Mask" "F.Paste")
			(net "GND")
		)
		(pad "27" smd circle
			(at -8.255 -1.905 90)
			(size 0.635 0.635)
			(layers "F.Cu" "F.Mask" "F.Paste")
			(net "PCIE_T2B_B1_RX_DN<14>")
		)
		(pad "28" smd circle
			(at -8.255 -0.635 90)
			(size 0.635 0.635)
			(layers "F.Cu" "F.Mask" "F.Paste")
			(net "GND")
		)
		(pad "29" smd circle
			(at -8.255 0.635 90)
			(size 0.635 0.635)
			(layers "F.Cu" "F.Mask" "F.Paste")
			(net "PCIE_B2T_B1_TX_DN<6>")
		)
		(pad "30" smd circle
			(at -8.255 1.905 90)
			(size 0.635 0.635)
			(layers "F.Cu" "F.Mask" "F.Paste")
			(net "GND")
		)
		(pad "31" smd circle
			(at -8.255 3.175 90)
			(size 0.635 0.635)
			(layers "F.Cu" "F.Mask" "F.Paste")
			(net "PCIE_B2T_B1_TX_DN<14>")
		)
		(pad "32" smd circle
			(at -8.255 4.445 90)
			(size 0.635 0.635)
			(layers "F.Cu" "F.Mask" "F.Paste")
			(net "GND")
		)
		(pad "33" smd circle
			(at -6.985 -4.445 90)
			(size 0.635 0.635)
			(layers "F.Cu" "F.Mask" "F.Paste")
			(net "GND")
		)
		(pad "34" smd circle
			(at -6.985 -3.175 90)
			(size 0.635 0.635)
			(layers "F.Cu" "F.Mask" "F.Paste")
			(net "PCIE_T2B_B1_RX_DP<5>")
		)
		(pad "35" smd circle
			(at -6.985 -1.905 90)
			(size 0.635 0.635)
			(layers "F.Cu" "F.Mask" "F.Paste")
			(net "GND")
		)
		(pad "36" smd circle
			(at -6.985 -0.635 90)
			(size 0.635 0.635)
			(layers "F.Cu" "F.Mask" "F.Paste")
			(net "PCIE_T2B_B1_RX_DP<13>")
		)
		(pad "37" smd circle
			(at -6.985 0.635 90)
			(size 0.635 0.635)
			(layers "F.Cu" "F.Mask" "F.Paste")
			(net "GND")
		)
		(pad "38" smd circle
			(at -6.985 1.905 90)
			(size 0.635 0.635)
			(layers "F.Cu" "F.Mask" "F.Paste")
			(net "PCIE_B2T_B1_TX_DP<5>")
		)
		(pad "39" smd circle
			(at -6.985 3.175 90)
			(size 0.635 0.635)
			(layers "F.Cu" "F.Mask" "F.Paste")
			(net "GND")
		)
		(pad "40" smd circle
			(at -6.985 4.445 90)
			(size 0.635 0.635)
			(layers "F.Cu" "F.Mask" "F.Paste")
			(net "PCIE_B2T_B1_TX_DP<13>")
		)
		(pad "41" smd circle
			(at -5.715 -4.445 90)
			(size 0.635 0.635)
			(layers "F.Cu" "F.Mask" "F.Paste")
			(net "GND")
		)
		(pad "42" smd circle
			(at -5.715 -3.175 90)
			(size 0.635 0.635)
			(layers "F.Cu" "F.Mask" "F.Paste")
			(net "PCIE_T2B_B1_RX_DN<5>")
		)
		(pad "43" smd circle
			(at -5.715 -1.905 90)
			(size 0.635 0.635)
			(layers "F.Cu" "F.Mask" "F.Paste")
			(net "GND")
		)
		(pad "44" smd circle
			(at -5.715 -0.635 90)
			(size 0.635 0.635)
			(layers "F.Cu" "F.Mask" "F.Paste")
			(net "PCIE_T2B_B1_RX_DN<13>")
		)
		(pad "45" smd circle
			(at -5.715 0.635 90)
			(size 0.635 0.635)
			(layers "F.Cu" "F.Mask" "F.Paste")
			(net "GND")
		)
		(pad "46" smd circle
			(at -5.715 1.905 90)
			(size 0.635 0.635)
			(layers "F.Cu" "F.Mask" "F.Paste")
			(net "PCIE_B2T_B1_TX_DN<5>")
		)
		(pad "47" smd circle
			(at -5.715 3.175 90)
			(size 0.635 0.635)
			(layers "F.Cu" "F.Mask" "F.Paste")
			(net "GND")
		)
		(pad "48" smd circle
			(at -5.715 4.445 90)
			(size 0.635 0.635)
			(layers "F.Cu" "F.Mask" "F.Paste")
			(net "PCIE_B2T_B1_TX_DN<13>")
		)
		(pad "49" smd circle
			(at -4.445 -4.445 90)
			(size 0.635 0.635)
			(layers "F.Cu" "F.Mask" "F.Paste")
			(net "PCIE_T2B_B1_RX_DP<4>")
		)
		(pad "50" smd circle
			(at -4.445 -3.175 90)
			(size 0.635 0.635)
			(layers "F.Cu" "F.Mask" "F.Paste")
			(net "GND")
		)
		(pad "51" smd circle
			(at -4.445 -1.905 90)
			(size 0.635 0.635)
			(layers "F.Cu" "F.Mask" "F.Paste")
			(net "PCIE_T2B_B1_RX_DP<12>")
		)
		(pad "52" smd circle
			(at -4.445 -0.635 90)
			(size 0.635 0.635)
			(layers "F.Cu" "F.Mask" "F.Paste")
			(net "GND")
		)
		(pad "53" smd circle
			(at -4.445 0.635 90)
			(size 0.635 0.635)
			(layers "F.Cu" "F.Mask" "F.Paste")
			(net "PCIE_B2T_B1_TX_DP<4>")
		)
		(pad "54" smd circle
			(at -4.445 1.905 90)
			(size 0.635 0.635)
			(layers "F.Cu" "F.Mask" "F.Paste")
			(net "GND")
		)
		(pad "55" smd circle
			(at -4.445 3.175 90)
			(size 0.635 0.635)
			(layers "F.Cu" "F.Mask" "F.Paste")
			(net "PCIE_B2T_B1_TX_DP<12>")
		)
		(pad "56" smd circle
			(at -4.445 4.445 90)
			(size 0.635 0.635)
			(layers "F.Cu" "F.Mask" "F.Paste")
			(net "GND")
		)
		(pad "57" smd circle
			(at -3.175 -4.445 90)
			(size 0.635 0.635)
			(layers "F.Cu" "F.Mask" "F.Paste")
			(net "PCIE_T2B_B1_RX_DN<4>")
		)
		(pad "58" smd circle
			(at -3.175 -3.175 90)
			(size 0.635 0.635)
			(layers "F.Cu" "F.Mask" "F.Paste")
			(net "GND")
		)
		(pad "59" smd circle
			(at -3.175 -1.905 90)
			(size 0.635 0.635)
			(layers "F.Cu" "F.Mask" "F.Paste")
			(net "PCIE_T2B_B1_RX_DN<12>")
		)
		(pad "60" smd circle
			(at -3.175 -0.635 90)
			(size 0.635 0.635)
			(layers "F.Cu" "F.Mask" "F.Paste")
			(net "GND")
		)
		(pad "61" smd circle
			(at -3.175 0.635 90)
			(size 0.635 0.635)
			(layers "F.Cu" "F.Mask" "F.Paste")
			(net "PCIE_B2T_B1_TX_DN<4>")
		)
		(pad "62" smd circle
			(at -3.175 1.905 90)
			(size 0.635 0.635)
			(layers "F.Cu" "F.Mask" "F.Paste")
			(net "GND")
		)
		(pad "63" smd circle
			(at -3.175 3.175 90)
			(size 0.635 0.635)
			(layers "F.Cu" "F.Mask" "F.Paste")
			(net "PCIE_B2T_B1_TX_DN<12>")
		)
		(pad "64" smd circle
			(at -3.175 4.445 90)
			(size 0.635 0.635)
			(layers "F.Cu" "F.Mask" "F.Paste")
			(net "GND")
		)
		(pad "65" smd circle
			(at -1.905 -4.445 90)
			(size 0.635 0.635)
			(layers "F.Cu" "F.Mask" "F.Paste")
			(net "GND")
		)
		(pad "66" smd circle
			(at -1.905 -3.175 90)
			(size 0.635 0.635)
			(layers "F.Cu" "F.Mask" "F.Paste")
			(net "PCIE_T2B_B1_RX_DP<3>")
		)
		(pad "67" smd circle
			(at -1.905 -1.905 90)
			(size 0.635 0.635)
			(layers "F.Cu" "F.Mask" "F.Paste")
			(net "GND")
		)
		(pad "68" smd circle
			(at -1.905 -0.635 90)
			(size 0.635 0.635)
			(layers "F.Cu" "F.Mask" "F.Paste")
			(net "PCIE_T2B_B1_RX_DP<11>")
		)
		(pad "69" smd circle
			(at -1.905 0.635 90)
			(size 0.635 0.635)
			(layers "F.Cu" "F.Mask" "F.Paste")
			(net "GND")
		)
		(pad "70" smd circle
			(at -1.905 1.905 90)
			(size 0.635 0.635)
			(layers "F.Cu" "F.Mask" "F.Paste")
			(net "PCIE_B2T_B1_TX_DP<3>")
		)
		(pad "71" smd circle
			(at -1.905 3.175 90)
			(size 0.635 0.635)
			(layers "F.Cu" "F.Mask" "F.Paste")
			(net "GND")
		)
		(pad "72" smd circle
			(at -1.905 4.445 90)
			(size 0.635 0.635)
			(layers "F.Cu" "F.Mask" "F.Paste")
			(net "PCIE_B2T_B1_TX_DP<11>")
		)
		(pad "73" smd circle
			(at -0.635 -4.445 90)
			(size 0.635 0.635)
			(layers "F.Cu" "F.Mask" "F.Paste")
			(net "GND")
		)
		(pad "74" smd circle
			(at -0.635 -3.175 90)
			(size 0.635 0.635)
			(layers "F.Cu" "F.Mask" "F.Paste")
			(net "PCIE_T2B_B1_RX_DN<3>")
		)
		(pad "75" smd circle
			(at -0.635 -1.905 90)
			(size 0.635 0.635)
			(layers "F.Cu" "F.Mask" "F.Paste")
			(net "GND")
		)
		(pad "76" smd circle
			(at -0.635 -0.635 90)
			(size 0.635 0.635)
			(layers "F.Cu" "F.Mask" "F.Paste")
			(net "PCIE_T2B_B1_RX_DN<11>")
		)
		(pad "77" smd circle
			(at -0.635 0.635 90)
			(size 0.635 0.635)
			(layers "F.Cu" "F.Mask" "F.Paste")
			(net "GND")
		)
		(pad "78" smd circle
			(at -0.635 1.905 90)
			(size 0.635 0.635)
			(layers "F.Cu" "F.Mask" "F.Paste")
			(net "PCIE_B2T_B1_TX_DN<3>")
		)
		(pad "79" smd circle
			(at -0.635 3.175 90)
			(size 0.635 0.635)
			(layers "F.Cu" "F.Mask" "F.Paste")
			(net "GND")
		)
		(pad "80" smd circle
			(at -0.635 4.445 90)
			(size 0.635 0.635)
			(layers "F.Cu" "F.Mask" "F.Paste")
			(net "PCIE_B2T_B1_TX_DN<11>")
		)
		(pad "81" smd circle
			(at 0.635 -4.445 90)
			(size 0.635 0.635)
			(layers "F.Cu" "F.Mask" "F.Paste")
			(net "PCIE_T2B_B1_RX_DP<2>")
		)
		(pad "82" smd circle
			(at 0.635 -3.175 90)
			(size 0.635 0.635)
			(layers "F.Cu" "F.Mask" "F.Paste")
			(net "GND")
		)
		(pad "83" smd circle
			(at 0.635 -1.905 90)
			(size 0.635 0.635)
			(layers "F.Cu" "F.Mask" "F.Paste")
			(net "PCIE_T2B_B1_RX_DP<10>")
		)
		(pad "84" smd circle
			(at 0.635 -0.635 90)
			(size 0.635 0.635)
			(layers "F.Cu" "F.Mask" "F.Paste")
			(net "GND")
		)
		(pad "85" smd circle
			(at 0.635 0.635 90)
			(size 0.635 0.635)
			(layers "F.Cu" "F.Mask" "F.Paste")
			(net "PCIE_B2T_B1_TX_DP<2>")
		)
		(pad "86" smd circle
			(at 0.635 1.905 90)
			(size 0.635 0.635)
			(layers "F.Cu" "F.Mask" "F.Paste")
			(net "GND")
		)
		(pad "87" smd circle
			(at 0.635 3.175 90)
			(size 0.635 0.635)
			(layers "F.Cu" "F.Mask" "F.Paste")
			(net "PCIE_B2T_B1_TX_DP<10>")
		)
		(pad "88" smd circle
			(at 0.635 4.445 90)
			(size 0.635 0.635)
			(layers "F.Cu" "F.Mask" "F.Paste")
			(net "GND")
		)
		(pad "89" smd circle
			(at 1.905 -4.445 90)
			(size 0.635 0.635)
			(layers "F.Cu" "F.Mask" "F.Paste")
			(net "PCIE_T2B_B1_RX_DN<2>")
		)
		(pad "90" smd circle
			(at 1.905 -3.175 90)
			(size 0.635 0.635)
			(layers "F.Cu" "F.Mask" "F.Paste")
			(net "GND")
		)
		(pad "91" smd circle
			(at 1.905 -1.905 90)
			(size 0.635 0.635)
			(layers "F.Cu" "F.Mask" "F.Paste")
			(net "PCIE_T2B_B1_RX_DN<10>")
		)
		(pad "92" smd circle
			(at 1.905 -0.635 90)
			(size 0.635 0.635)
			(layers "F.Cu" "F.Mask" "F.Paste")
			(net "GND")
		)
		(pad "93" smd circle
			(at 1.905 0.635 90)
			(size 0.635 0.635)
			(layers "F.Cu" "F.Mask" "F.Paste")
			(net "PCIE_B2T_B1_TX_DN<2>")
		)
		(pad "94" smd circle
			(at 1.905 1.905 90)
			(size 0.635 0.635)
			(layers "F.Cu" "F.Mask" "F.Paste")
			(net "GND")
		)
		(pad "95" smd circle
			(at 1.905 3.175 90)
			(size 0.635 0.635)
			(layers "F.Cu" "F.Mask" "F.Paste")
			(net "PCIE_B2T_B1_TX_DN<10>")
		)
		(pad "96" smd circle
			(at 1.905 4.445 90)
			(size 0.635 0.635)
			(layers "F.Cu" "F.Mask" "F.Paste")
			(net "GND")
		)
		(pad "97" smd circle
			(at 3.175 -4.445 90)
			(size 0.635 0.635)
			(layers "F.Cu" "F.Mask" "F.Paste")
			(net "GND")
		)
		(pad "98" smd circle
			(at 3.175 -3.175 90)
			(size 0.635 0.635)
			(layers "F.Cu" "F.Mask" "F.Paste")
			(net "PCIE_T2B_B1_RX_DP<1>")
		)
		(pad "99" smd circle
			(at 3.175 -1.905 90)
			(size 0.635 0.635)
			(layers "F.Cu" "F.Mask" "F.Paste")
			(net "GND")
		)
		(pad "100" smd circle
			(at 3.175 -0.635 90)
			(size 0.635 0.635)
			(layers "F.Cu" "F.Mask" "F.Paste")
			(net "PCIE_T2B_B1_RX_DP<9>")
		)
		(pad "101" smd circle
			(at 3.175 0.635 90)
			(size 0.635 0.635)
			(layers "F.Cu" "F.Mask" "F.Paste")
			(net "GND")
		)
		(pad "102" smd circle
			(at 3.175 1.905 90)
			(size 0.635 0.635)
			(layers "F.Cu" "F.Mask" "F.Paste")
			(net "PCIE_B2T_B1_TX_DP<1>")
		)
		(pad "103" smd circle
			(at 3.175 3.175 90)
			(size 0.635 0.635)
			(layers "F.Cu" "F.Mask" "F.Paste")
			(net "GND")
		)
		(pad "104" smd circle
			(at 3.175 4.445 90)
			(size 0.635 0.635)
			(layers "F.Cu" "F.Mask" "F.Paste")
			(net "PCIE_B2T_B1_TX_DP<9>")
		)
		(pad "105" smd circle
			(at 4.445 -4.445 90)
			(size 0.635 0.635)
			(layers "F.Cu" "F.Mask" "F.Paste")
			(net "GND")
		)
		(pad "106" smd circle
			(at 4.445 -3.175 90)
			(size 0.635 0.635)
			(layers "F.Cu" "F.Mask" "F.Paste")
			(net "PCIE_T2B_B1_RX_DN<1>")
		)
		(pad "107" smd circle
			(at 4.445 -1.905 90)
			(size 0.635 0.635)
			(layers "F.Cu" "F.Mask" "F.Paste")
			(net "GND")
		)
		(pad "108" smd circle
			(at 4.445 -0.635 90)
			(size 0.635 0.635)
			(layers "F.Cu" "F.Mask" "F.Paste")
			(net "PCIE_T2B_B1_RX_DN<9>")
		)
		(pad "109" smd circle
			(at 4.445 0.635 90)
			(size 0.635 0.635)
			(layers "F.Cu" "F.Mask" "F.Paste")
			(net "GND")
		)
		(pad "110" smd circle
			(at 4.445 1.905 90)
			(size 0.635 0.635)
			(layers "F.Cu" "F.Mask" "F.Paste")
			(net "PCIE_B2T_B1_TX_DN<1>")
		)
		(pad "111" smd circle
			(at 4.445 3.175 90)
			(size 0.635 0.635)
			(layers "F.Cu" "F.Mask" "F.Paste")
			(net "GND")
		)
		(pad "112" smd circle
			(at 4.445 4.445 90)
			(size 0.635 0.635)
			(layers "F.Cu" "F.Mask" "F.Paste")
			(net "PCIE_B2T_B1_TX_DN<9>")
		)
		(pad "113" smd circle
			(at 5.715 -4.445 90)
			(size 0.635 0.635)
			(layers "F.Cu" "F.Mask" "F.Paste")
			(net "PCIE_T2B_B1_RX_DP<0>")
		)
		(pad "114" smd circle
			(at 5.715 -3.175 90)
			(size 0.635 0.635)
			(layers "F.Cu" "F.Mask" "F.Paste")
			(net "GND")
		)
		(pad "115" smd circle
			(at 5.715 -1.905 90)
			(size 0.635 0.635)
			(layers "F.Cu" "F.Mask" "F.Paste")
			(net "PCIE_T2B_B1_RX_DP<8>")
		)
		(pad "116" smd circle
			(at 5.715 -0.635 90)
			(size 0.635 0.635)
			(layers "F.Cu" "F.Mask" "F.Paste")
			(net "GND")
		)
		(pad "117" smd circle
			(at 5.715 0.635 90)
			(size 0.635 0.635)
			(layers "F.Cu" "F.Mask" "F.Paste")
			(net "PCIE_B2T_B1_TX_DP<0>")
		)
		(pad "118" smd circle
			(at 5.715 1.905 90)
			(size 0.635 0.635)
			(layers "F.Cu" "F.Mask" "F.Paste")
			(net "GND")
		)
		(pad "119" smd circle
			(at 5.715 3.175 90)
			(size 0.635 0.635)
			(layers "F.Cu" "F.Mask" "F.Paste")
			(net "PCIE_B2T_B1_TX_DP<8>")
		)
		(pad "120" smd circle
			(at 5.715 4.445 90)
			(size 0.635 0.635)
			(layers "F.Cu" "F.Mask" "F.Paste")
			(net "GND")
		)
		(pad "121" smd circle
			(at 6.985 -4.445 90)
			(size 0.635 0.635)
			(layers "F.Cu" "F.Mask" "F.Paste")
			(net "PCIE_T2B_B1_RX_DN<0>")
		)
		(pad "122" smd circle
			(at 6.985 -3.175 90)
			(size 0.635 0.635)
			(layers "F.Cu" "F.Mask" "F.Paste")
			(net "GND")
		)
		(pad "123" smd circle
			(at 6.985 -1.905 90)
			(size 0.635 0.635)
			(layers "F.Cu" "F.Mask" "F.Paste")
			(net "PCIE_T2B_B1_RX_DN<8>")
		)
		(pad "124" smd circle
			(at 6.985 -0.635 90)
			(size 0.635 0.635)
			(layers "F.Cu" "F.Mask" "F.Paste")
			(net "GND")
		)
		(pad "125" smd circle
			(at 6.985 0.635 90)
			(size 0.635 0.635)
			(layers "F.Cu" "F.Mask" "F.Paste")
			(net "PCIE_B2T_B1_TX_DN<0>")
		)
		(pad "126" smd circle
			(at 6.985 1.905 90)
			(size 0.635 0.635)
			(layers "F.Cu" "F.Mask" "F.Paste")
			(net "GND")
		)
		(pad "127" smd circle
			(at 6.985 3.175 90)
			(size 0.635 0.635)
			(layers "F.Cu" "F.Mask" "F.Paste")
			(net "PCIE_B2T_B1_TX_DN<8>")
		)
		(pad "128" smd circle
			(at 6.985 4.445 90)
			(size 0.635 0.635)
			(layers "F.Cu" "F.Mask" "F.Paste")
			(net "GND")
		)
		(pad "129" smd circle
			(at 8.255 -4.445 90)
			(size 0.635 0.635)
			(layers "F.Cu" "F.Mask" "F.Paste")
			(net "GND")
		)
		(pad "130" smd circle
			(at 8.255 -3.175 90)
			(size 0.635 0.635)
			(layers "F.Cu" "F.Mask" "F.Paste")
			(net "CLK_100M_B1_P<0>")
		)
		(pad "131" smd circle
			(at 8.255 -1.905 90)
			(size 0.635 0.635)
			(layers "F.Cu" "F.Mask" "F.Paste")
			(net "GND")
		)
		(pad "132" smd circle
			(at 8.255 -0.635 90)
			(size 0.635 0.635)
			(layers "F.Cu" "F.Mask" "F.Paste")
			(net "CLK_100M_B1_P<1>")
		)
		(pad "133" smd circle
			(at 8.255 0.635 90)
			(size 0.635 0.635)
			(layers "F.Cu" "F.Mask" "F.Paste")
			(net "GND")
		)
		(pad "134" smd circle
			(at 8.255 1.905 90)
			(size 0.635 0.635)
			(layers "F.Cu" "F.Mask" "F.Paste")
			(net "CLK_100M_B1_P<2>")
		)
		(pad "135" smd circle
			(at 8.255 3.175 90)
			(size 0.635 0.635)
			(layers "F.Cu" "F.Mask" "F.Paste")
			(net "GND")
		)
		(pad "136" smd circle
			(at 8.255 4.445 90)
			(size 0.635 0.635)
			(layers "F.Cu" "F.Mask" "F.Paste")
			(net "CLK_100M_B1_P<3>")
		)
		(pad "137" smd circle
			(at 9.525 -4.445 90)
			(size 0.635 0.635)
			(layers "F.Cu" "F.Mask" "F.Paste")
			(net "P12V_MEZZ_B1")
		)
		(pad "138" smd circle
			(at 9.525 -3.175 90)
			(size 0.635 0.635)
			(layers "F.Cu" "F.Mask" "F.Paste")
			(net "CLK_100M_B1_N<0>")
		)
		(pad "139" smd circle
			(at 9.525 -1.905 90)
			(size 0.635 0.635)
			(layers "F.Cu" "F.Mask" "F.Paste")
			(net "GND")
		)
		(pad "140" smd circle
			(at 9.525 -0.635 90)
			(size 0.635 0.635)
			(layers "F.Cu" "F.Mask" "F.Paste")
			(net "CLK_100M_B1_N<1>")
		)
		(pad "141" smd circle
			(at 9.525 0.635 90)
			(size 0.635 0.635)
			(layers "F.Cu" "F.Mask" "F.Paste")
			(net "GND")
		)
		(pad "142" smd circle
			(at 9.525 1.905 90)
			(size 0.635 0.635)
			(layers "F.Cu" "F.Mask" "F.Paste")
			(net "CLK_100M_B1_N<2>")
		)
		(pad "143" smd circle
			(at 9.525 3.175 90)
			(size 0.635 0.635)
			(layers "F.Cu" "F.Mask" "F.Paste")
			(net "PCIE_RESET_B1_N<2>")
		)
		(pad "144" smd circle
			(at 9.525 4.445 90)
			(size 0.635 0.635)
			(layers "F.Cu" "F.Mask" "F.Paste")
			(net "CLK_100M_B1_N<3>")
		)
		(pad "145" smd circle
			(at 10.795 -4.445 90)
			(size 0.635 0.635)
			(layers "F.Cu" "F.Mask" "F.Paste")
			(net "P12V_MEZZ_B1")
		)
		(pad "146" smd circle
			(at 10.795 -3.175 90)
			(size 0.635 0.635)
			(layers "F.Cu" "F.Mask" "F.Paste")
			(net "GND")
		)
		(pad "147" smd circle
			(at 10.795 -1.905 90)
			(size 0.635 0.635)
			(layers "F.Cu" "F.Mask" "F.Paste")
			(net "GND")
		)
		(pad "148" smd circle
			(at 10.795 -0.635 90)
			(size 0.635 0.635)
			(layers "F.Cu" "F.Mask" "F.Paste")
			(net "PCIE_CFG_B1_ID1")
		)
		(pad "149" smd circle
			(at 10.795 0.635 90)
			(size 0.635 0.635)
			(layers "F.Cu" "F.Mask" "F.Paste")
			(net "PCIE_CFG_B1_ID0")
		)
		(pad "150" smd circle
			(at 10.795 1.905 90)
			(size 0.635 0.635)
			(layers "F.Cu" "F.Mask" "F.Paste")
			(net "PCIE_RESET_B1_N<0>")
		)
		(pad "151" smd circle
			(at 10.795 3.175 90)
			(size 0.635 0.635)
			(layers "F.Cu" "F.Mask" "F.Paste")
			(net "PCIE_RESET_B1_N<1>")
		)
		(pad "152" smd circle
			(at 10.795 4.445 90)
			(size 0.635 0.635)
			(layers "F.Cu" "F.Mask" "F.Paste")
			(net "PCIE_RESET_B1_N<3>")
		)
		(pad "153" smd circle
			(at 12.065 -4.445 90)
			(size 0.635 0.635)
			(layers "F.Cu" "F.Mask" "F.Paste")
			(net "P12V_MEZZ_B1")
		)
		(pad "154" smd circle
			(at 12.065 -3.175 90)
			(size 0.635 0.635)
			(layers "F.Cu" "F.Mask" "F.Paste")
			(net "P12V_MEZZ_B1")
		)
		(pad "155" smd circle
			(at 12.065 -1.905 90)
			(size 0.635 0.635)
			(layers "F.Cu" "F.Mask" "F.Paste")
			(net "P12V_MEZZ_B1")
		)
		(pad "156" smd circle
			(at 12.065 -0.635 90)
			(size 0.635 0.635)
			(layers "F.Cu" "F.Mask" "F.Paste")
			(net "MEZZ_B1_SCL")
		)
		(pad "157" smd circle
			(at 12.065 0.635 90)
			(size 0.635 0.635)
			(layers "F.Cu" "F.Mask" "F.Paste")
			(net "MEZZ_B1_EN")
		)
		(pad "158" smd circle
			(at 12.065 1.905 90)
			(size 0.635 0.635)
			(layers "F.Cu" "F.Mask" "F.Paste")
			(net "MEZZ_B1_SDA")
		)
		(pad "159" smd circle
			(at 12.065 3.175 90)
			(size 0.635 0.635)
			(layers "F.Cu" "F.Mask" "F.Paste")
			(net "PCIE_WAKE_B1_N")
		)
		(pad "160" smd circle
			(at 12.065 4.445 90)
			(size 0.635 0.635)
			(layers "F.Cu" "F.Mask" "F.Paste")
			(net "MEZZ_PRESENT_B1_N")
		)
		(zone
			(layers "F.Cu" "B.Cu" "In1.Cu" "In2.Cu" "In3.Cu" "In4.Cu" "In5.Cu" "In6.Cu")
			(hatch none 0.5)
			(connect_pads
				(clearance 0)
			)
			(min_thickness 0.25)
			(keepout
				(tracks not_allowed)
				(vias allowed)
				(pads allowed)
				(copperpour not_allowed)
				(footprints allowed)
			)
			(placement
				(enabled no)
				(sheetname "")
			)
			(fill
				(thermal_gap 0.5)
				(thermal_bridge_width 0.5)
				(island_removal_mode 0)
			)
			(polygon
				(pts
					(arc
						(start -378.127999 44.434699)
						(mid -378.127999 46.466699)
						(end -378.127999 44.434699)
					)
				)
			)
		)
		(zone
			(layers "F.Cu" "B.Cu" "In1.Cu" "In2.Cu" "In3.Cu" "In4.Cu" "In5.Cu" "In6.Cu")
			(hatch none 0.5)
			(connect_pads
				(clearance 0)
			)
			(min_thickness 0.25)
			(keepout
				(tracks not_allowed)
				(vias allowed)
				(pads allowed)
				(copperpour not_allowed)
				(footprints allowed)
			)
			(placement
				(enabled no)
				(sheetname "")
			)
			(fill
				(thermal_gap 0.5)
				(thermal_bridge_width 0.5)
				(island_removal_mode 0)
			)
			(polygon
				(pts
					(arc
						(start -375.079999 15.453299)
						(mid -375.079999 17.485299)
						(end -375.079999 15.453299)
					)
				)
			)
		)
	)
	(footprint ""
		(layer "F.Cu")
		(at -300.9392 7.4676)
		(property "Reference" "R4"
			(at -3.6068 -0.0635 0)
			(unlocked yes)
			(layer "F.SilkS")
			(effects
				(font
					(size 0.762 0.5334)
					(thickness 0.1016)
				)
			)
		)
		(property "Value" ""
			(at 0 0 0)
			(layer "F.Fab")
			(effects
				(font
					(size 1.27 1.27)
				)
			)
		)
		(duplicate_pad_numbers_are_jumpers no)
		(fp_line
			(start 0 -0.381)
			(end 0 0.381)
			(stroke
				(width 0.127)
				(type default)
			)
			(layer "F.SilkS")
		)
		(fp_poly
			(pts
				(xy 1.255601 0.6564) (xy -1.255601 0.6564) (xy -1.255601 -0.656399) (xy 1.255601 -0.656399)
			)
			(stroke
				(width 0)
				(type default)
			)
			(fill no)
			(layer "F.CrtYd")
		)
		(fp_line
			(start -0.800001 -0.399999)
			(end -0.800001 0.399999)
			(stroke
				(width 0.1)
				(type default)
			)
			(layer "F.Fab")
		)
		(fp_line
			(start -0.800001 0.399999)
			(end 0.800001 0.399999)
			(stroke
				(width 0.1)
				(type default)
			)
			(layer "F.Fab")
		)
		(fp_line
			(start 0.800001 -0.399999)
			(end -0.800001 -0.399999)
			(stroke
				(width 0.1)
				(type default)
			)
			(layer "F.Fab")
		)
		(fp_line
			(start 0.800001 0.399999)
			(end 0.800001 -0.399999)
			(stroke
				(width 0.1)
				(type default)
			)
			(layer "F.Fab")
		)
		(pad "1" smd rect
			(at -0.650001 0)
			(size 0.7112 0.8128)
			(layers "F.Cu" "F.Mask" "F.Paste")
			(net "P3V3_B1_QSFP")
		)
		(pad "2" smd rect
			(at 0.650001 0 180)
			(size 0.7112 0.8128)
			(layers "F.Cu" "F.Mask" "F.Paste")
			(net "SKU_B1_ID1")
		)
	)
	(footprint ""
		(layer "F.Cu")
		(at -282.750001 32.059999 180)
		(property "Reference" "J6"
			(at -6.979661 -7.170301 0)
			(unlocked yes)
			(layer "F.SilkS")
			(effects
				(font
					(size 0.762 0.5334)
					(thickness 0.1016)
				)
			)
		)
		(property "Value" ""
			(at 0 0 180)
			(layer "F.Fab")
			(effects
				(font
					(size 1.27 1.27)
				)
			)
		)
		(duplicate_pad_numbers_are_jumpers no)
		(fp_line
			(start 8.099999 42.399999)
			(end 8.099999 27.999999)
			(stroke
				(width 0.127)
				(type default)
			)
			(layer "F.SilkS")
		)
		(fp_line
			(start 8.099999 23.099999)
			(end 8.099999 17.999999)
			(stroke
				(width 0.127)
				(type default)
			)
			(layer "F.SilkS")
		)
		(fp_line
			(start 8.099999 13.8)
			(end 8.099999 7.899999)
			(stroke
				(width 0.127)
				(type default)
			)
			(layer "F.SilkS")
		)
		(fp_line
			(start 8.099999 4.199999)
			(end 8.099999 -2.400001)
			(stroke
				(width 0.127)
				(type default)
			)
			(layer "F.SilkS")
		)
		(fp_line
			(start 8.099999 -5.699999)
			(end 8.099999 -6.3)
			(stroke
				(width 0.127)
				(type default)
			)
			(layer "F.SilkS")
		)
		(fp_line
			(start 8.099999 -6.3)
			(end 6.000001 -6.3)
			(stroke
				(width 0.127)
				(type default)
			)
			(layer "F.SilkS")
		)
		(fp_line
			(start -6.000001 -6.3)
			(end -8.099999 -6.3)
			(stroke
				(width 0.127)
				(type default)
			)
			(layer "F.SilkS")
		)
		(fp_line
			(start -8.099999 42.399999)
			(end 8.099999 42.399999)
			(stroke
				(width 0.127)
				(type default)
			)
			(layer "F.SilkS")
		)
		(fp_line
			(start -8.099999 32.8)
			(end -8.099999 42.399999)
			(stroke
				(width 0.127)
				(type default)
			)
			(layer "F.SilkS")
		)
		(fp_line
			(start -8.099999 22.999999)
			(end -8.099999 28.9)
			(stroke
				(width 0.127)
				(type default)
			)
			(layer "F.SilkS")
		)
		(fp_line
			(start -8.099999 12.999999)
			(end -8.099999 18.600001)
			(stroke
				(width 0.127)
				(type default)
			)
			(layer "F.SilkS")
		)
		(fp_line
			(start -8.099999 2.5)
			(end -8.099999 9.099999)
			(stroke
				(width 0.127)
				(type default)
			)
			(layer "F.SilkS")
		)
		(fp_line
			(start -8.099999 -6.3)
			(end -8.099999 -0.700002)
			(stroke
				(width 0.127)
				(type default)
			)
			(layer "F.SilkS")
		)
		(fp_poly
			(pts
				(arc
					(start 5.2054 34.950301)
					(mid 3.459364 36.043267)
					(end 1.434201 36.42)
				)
				(arc
					(start -7.124799 36.42)
					(mid -11.028153 34.803295)
					(end -12.644999 30.899999)
				)
				(xy -12.6495 30.899999) (xy -12.6495 0.9)
				(arc
					(start -12.644999 0.9)
					(mid -12.630104 0.494905)
					(end -12.585499 0.091998)
				)
				(arc
					(start -12.368601 -1.986699)
					(mid -12.153073 -3.137304)
					(end -11.6883 -4.211701)
				)
				(arc
					(start -9.541 -8.473202)
					(mid -7.601128 -10.649547)
					(end -4.800001 -11.457801)
				)
				(arc
					(start 4.8 -11.457801)
					(mid 6.526795 -11.166136)
					(end 8.062001 -10.3235)
				)
				(arc
					(start 10.390299 -8.5507)
					(mid 12.049188 -6.594625)
					(end 12.644999 -4.1)
				)
				(xy 12.6495 -4.1) (xy 12.6495 25.899999)
				(arc
					(start 12.644999 25.899999)
					(mid 12.153739 28.176398)
					(end 10.7674 30.0476)
				)
			)
			(stroke
				(width 0)
				(type default)
			)
			(fill no)
			(layer "B.CrtYd")
		)
		(fp_poly
			(pts
				(xy 9.1 43.399999) (xy -9.1 43.399999) (xy -9.1 -7.9) (xy 9.1 -7.9)
			)
			(stroke
				(width 0)
				(type default)
			)
			(fill no)
			(layer "F.CrtYd")
		)
		(fp_line
			(start 8.099999 42.399999)
			(end -8.099999 42.399999)
			(stroke
				(width 0.1)
				(type default)
			)
			(layer "F.Fab")
		)
		(fp_line
			(start 8.099999 -6.32)
			(end 8.099999 42.399999)
			(stroke
				(width 0.1)
				(type default)
			)
			(layer "F.Fab")
		)
		(fp_line
			(start -8.099999 42.399999)
			(end -8.099999 -6.32)
			(stroke
				(width 0.1)
				(type default)
			)
			(layer "F.Fab")
		)
		(fp_line
			(start -8.099999 -6.32)
			(end 8.099999 -6.32)
			(stroke
				(width 0.1)
				(type default)
			)
			(layer "F.Fab")
		)
		(pad "1" thru_hole circle
			(at 0 -6.2 180)
			(size 1.4732 1.4732)
			(drill 0.9652)
			(layers "*.Cu" "*.Mask")
			(remove_unused_layers no)
			(net "GND")
		)
		(pad "2" thru_hole circle
			(at -4.800001 -6.2 180)
			(size 1.4732 1.4732)
			(drill 0.9652)
			(layers "*.Cu" "*.Mask")
			(remove_unused_layers no)
			(net "GND")
		)
		(pad "3" thru_hole circle
			(at 4.800001 -6.2 180)
			(size 1.4732 1.4732)
			(drill 0.9652)
			(layers "*.Cu" "*.Mask")
			(remove_unused_layers no)
			(net "GND")
		)
		(pad "4" thru_hole rect
			(at 7.125 -4.099999 180)
			(size 2.0066 2.0066)
			(drill 1.0414)
			(layers "*.Cu" "*.Mask")
			(remove_unused_layers no)
			(net "GND")
			(padstack
				(mode front_inner_back)
				(layer "Inner"
					(shape circle)
					(size 2.0066 2.0066)
				)
				(layer "B.Cu"
					(shape rect)
					(size 2.0066 2.0066)
				)
			)
		)
		(pad "5" thru_hole circle
			(at -7.125 -1.599999 180)
			(size 1.4732 1.4732)
			(drill 0.9652)
			(layers "*.Cu" "*.Mask")
			(remove_unused_layers no)
			(net "GND")
		)
		(pad "6" thru_hole circle
			(at 7.125 -1.599999 180)
			(size 1.4732 1.4732)
			(drill 0.9652)
			(layers "*.Cu" "*.Mask")
			(remove_unused_layers no)
			(net "GND")
		)
		(pad "7" thru_hole rect
			(at -7.125 0.900001 180)
			(size 2.0066 2.0066)
			(drill 0.8382)
			(layers "*.Cu" "*.Mask")
			(remove_unused_layers no)
			(net "GND")
			(padstack
				(mode front_inner_back)
				(layer "Inner"
					(shape circle)
					(size 2.0066 2.0066)
				)
				(layer "B.Cu"
					(shape rect)
					(size 2.0066 2.0066)
				)
			)
		)
		(pad "8" thru_hole circle
			(at -7.125 3.400001 180)
			(size 1.4732 1.4732)
			(drill 0.9652)
			(layers "*.Cu" "*.Mask")
			(remove_unused_layers no)
			(net "GND")
		)
		(pad "9" thru_hole circle
			(at 7.125 3.400001 180)
			(size 1.4732 1.4732)
			(drill 0.9652)
			(layers "*.Cu" "*.Mask")
			(remove_unused_layers no)
			(net "GND")
		)
		(pad "10" thru_hole rect
			(at 7.125 5.900001 180)
			(size 2.0066 2.0066)
			(drill 1.0414)
			(layers "*.Cu" "*.Mask")
			(remove_unused_layers no)
			(net "GND")
			(padstack
				(mode front_inner_back)
				(layer "Inner"
					(shape circle)
					(size 2.0066 2.0066)
				)
				(layer "B.Cu"
					(shape rect)
					(size 2.0066 2.0066)
				)
			)
		)
		(pad "11" thru_hole circle
			(at -7.125 8.099999 180)
			(size 1.4732 1.4732)
			(drill 0.9652)
			(layers "*.Cu" "*.Mask")
			(remove_unused_layers no)
			(net "GND")
		)
		(pad "12" thru_hole circle
			(at 7.125 8.099999 180)
			(size 1.4732 1.4732)
			(drill 0.9652)
			(layers "*.Cu" "*.Mask")
			(remove_unused_layers no)
			(net "GND")
		)
		(pad "13" thru_hole rect
			(at -7.125 10.900001 180)
			(size 2.0066 2.0066)
			(drill 1.0414)
			(layers "*.Cu" "*.Mask")
			(remove_unused_layers no)
			(net "GND")
			(padstack
				(mode front_inner_back)
				(layer "Inner"
					(shape circle)
					(size 2.0066 2.0066)
				)
				(layer "B.Cu"
					(shape rect)
					(size 2.0066 2.0066)
				)
			)
		)
		(pad "14" thru_hole rect
			(at -1.445001 10.900001 180)
			(size 2.0066 2.0066)
			(drill 1.0414)
			(layers "*.Cu" "*.Mask")
			(remove_unused_layers no)
			(net "GND")
			(padstack
				(mode front_inner_back)
				(layer "Inner"
					(shape circle)
					(size 2.0066 2.0066)
				)
				(layer "B.Cu"
					(shape rect)
					(size 2.0066 2.0066)
				)
			)
		)
		(pad "15" thru_hole rect
			(at 3.955001 10.900001 180)
			(size 2.0066 2.0066)
			(drill 1.0414)
			(layers "*.Cu" "*.Mask")
			(remove_unused_layers no)
			(net "GND")
			(padstack
				(mode front_inner_back)
				(layer "Inner"
					(shape circle)
					(size 2.0066 2.0066)
				)
				(layer "B.Cu"
					(shape rect)
					(size 2.0066 2.0066)
				)
			)
		)
		(pad "16" thru_hole rect
			(at 7.125 15.900001 180)
			(size 2.0066 2.0066)
			(drill 1.0414)
			(layers "*.Cu" "*.Mask")
			(remove_unused_layers no)
			(net "GND")
			(padstack
				(mode front_inner_back)
				(layer "Inner"
					(shape circle)
					(size 2.0066 2.0066)
				)
				(layer "B.Cu"
					(shape rect)
					(size 2.0066 2.0066)
				)
			)
		)
		(pad "17" thru_hole rect
			(at -7.125 20.899999 180)
			(size 2.0066 2.0066)
			(drill 1.0414)
			(layers "*.Cu" "*.Mask")
			(remove_unused_layers no)
			(net "GND")
			(padstack
				(mode front_inner_back)
				(layer "Inner"
					(shape circle)
					(size 2.0066 2.0066)
				)
				(layer "B.Cu"
					(shape rect)
					(size 2.0066 2.0066)
				)
			)
		)
		(pad "18" thru_hole rect
			(at 7.125 25.899999 180)
			(size 2.0066 2.0066)
			(drill 1.0414)
			(layers "*.Cu" "*.Mask")
			(remove_unused_layers no)
			(net "GND")
			(padstack
				(mode front_inner_back)
				(layer "Inner"
					(shape circle)
					(size 2.0066 2.0066)
				)
				(layer "B.Cu"
					(shape rect)
					(size 2.0066 2.0066)
				)
			)
		)
		(pad "19" thru_hole rect
			(at -7.125 30.899999 180)
			(size 2.0066 2.0066)
			(drill 1.0414)
			(layers "*.Cu" "*.Mask")
			(remove_unused_layers no)
			(net "GND")
			(padstack
				(mode front_inner_back)
				(layer "Inner"
					(shape circle)
					(size 2.0066 2.0066)
				)
				(layer "B.Cu"
					(shape rect)
					(size 2.0066 2.0066)
				)
			)
		)
		(pad "20" thru_hole rect
			(at 1.455001 30.899999 180)
			(size 2.0066 2.0066)
			(drill 1.0414)
			(layers "*.Cu" "*.Mask")
			(remove_unused_layers no)
			(net "GND")
			(padstack
				(mode front_inner_back)
				(layer "Inner"
					(shape circle)
					(size 2.0066 2.0066)
				)
				(layer "B.Cu"
					(shape rect)
					(size 2.0066 2.0066)
				)
			)
		)
	)
	(footprint ""
		(layer "F.Cu")
		(at -60.388401 44.869202 -90)
		(property "Reference" "R45"
			(at -4.102202 0.025499 90)
			(unlocked yes)
			(layer "F.SilkS")
			(effects
				(font
					(size 0.762 0.5334)
					(thickness 0.1016)
				)
			)
		)
		(property "Value" ""
			(at 0 0 270)
			(layer "F.Fab")
			(effects
				(font
					(size 1.27 1.27)
				)
			)
		)
		(duplicate_pad_numbers_are_jumpers no)
		(fp_line
			(start 0 -0.381)
			(end 0 0.381)
			(stroke
				(width 0.127)
				(type default)
			)
			(layer "F.SilkS")
		)
		(fp_poly
			(pts
				(xy 1.2556 0.656399) (xy -1.255601 0.656399) (xy -1.255601 -0.6564) (xy 1.2556 -0.6564)
			)
			(stroke
				(width 0)
				(type default)
			)
			(fill no)
			(layer "F.CrtYd")
		)
		(fp_line
			(start -0.800001 0.399999)
			(end 0.800001 0.399999)
			(stroke
				(width 0.1)
				(type default)
			)
			(layer "F.Fab")
		)
		(fp_line
			(start 0.800001 0.399999)
			(end 0.800001 -0.399999)
			(stroke
				(width 0.1)
				(type default)
			)
			(layer "F.Fab")
		)
		(fp_line
			(start -0.800001 -0.399999)
			(end -0.800001 0.399999)
			(stroke
				(width 0.1)
				(type default)
			)
			(layer "F.Fab")
		)
		(fp_line
			(start 0.800001 -0.399999)
			(end -0.800001 -0.399999)
			(stroke
				(width 0.1)
				(type default)
			)
			(layer "F.Fab")
		)
		(pad "1" smd rect
			(at -0.650001 0 270)
			(size 0.7112 0.8128)
			(layers "F.Cu" "F.Mask" "F.Paste")
			(net "P3V3_10G_B2_VCCT")
		)
		(pad "2" smd rect
			(at 0.650001 0 90)
			(size 0.7112 0.8128)
			(layers "F.Cu" "F.Mask" "F.Paste")
			(net "P3V3_B2_QSFP")
		)
	)
	(footprint ""
		(layer "F.Cu")
		(at -392.46 45.260001 180)
		(property "Reference" "J1"
			(at 9 24.584899 0)
			(unlocked yes)
			(layer "F.SilkS")
			(effects
				(font
					(size 0.762 0.5334)
					(thickness 0.1016)
				)
			)
		)
		(property "Value" ""
			(at 0 0 180)
			(layer "F.Fab")
			(effects
				(font
					(size 1.27 1.27)
				)
			)
		)
		(duplicate_pad_numbers_are_jumpers no)
		(fp_line
			(start 18.95 23.700001)
			(end -0.950001 23.700001)
			(stroke
				(width 0.127)
				(type default)
			)
			(layer "F.SilkS")
		)
		(fp_line
			(start 18.95 -12.100001)
			(end 18.95 23.700001)
			(stroke
				(width 0.127)
				(type default)
			)
			(layer "F.SilkS")
		)
		(fp_line
			(start -0.950001 23.700001)
			(end -0.950001 -12.100001)
			(stroke
				(width 0.127)
				(type default)
			)
			(layer "F.SilkS")
		)
		(fp_line
			(start -0.950001 -12.100001)
			(end 18.95 -12.100001)
			(stroke
				(width 0.127)
				(type default)
			)
			(layer "F.SilkS")
		)
		(fp_poly
			(pts
				(arc
					(start 0 25.4)
					(mid -3.592102 23.912102)
					(end -5.08 20.32)
				)
				(arc
					(start -5.08 -0.1)
					(mid -3.592102 -3.692102)
					(end 0 -5.18)
				)
				(arc
					(start 18 -5.18)
					(mid 21.592102 -3.692102)
					(end 23.08 -0.1)
				)
				(arc
					(start 23.08 20.32)
					(mid 21.592102 23.912102)
					(end 18 25.4)
				)
			)
			(stroke
				(width 0)
				(type default)
			)
			(fill no)
			(layer "B.CrtYd")
		)
		(fp_rect
			(start -1.950001 24.699999)
			(end 19.950001 -13.099999)
			(stroke
				(width 0)
				(type default)
			)
			(fill no)
			(layer "F.CrtYd")
		)
		(fp_line
			(start 18.95 23.700001)
			(end -0.950001 23.700001)
			(stroke
				(width 0.1)
				(type default)
			)
			(layer "F.Fab")
		)
		(fp_line
			(start 18.95 -12.100001)
			(end 18.95 23.700001)
			(stroke
				(width 0.1)
				(type default)
			)
			(layer "F.Fab")
		)
		(fp_line
			(start -0.950001 23.700001)
			(end -0.950001 -12.100001)
			(stroke
				(width 0.1)
				(type default)
			)
			(layer "F.Fab")
		)
		(fp_line
			(start -0.950001 -12.100001)
			(end 18.95 -12.100001)
			(stroke
				(width 0.1)
				(type default)
			)
			(layer "F.Fab")
		)
		(fp_text user "P10"
			(at 20.29 21.345901 0)
			(unlocked yes)
			(layer "F.SilkS")
			(effects
				(font
					(size 0.762 0.5334)
					(thickness 0.1016)
				)
			)
		)
		(fp_text user "J10"
			(at 20.18904 12.4936 0)
			(unlocked yes)
			(layer "F.SilkS")
			(effects
				(font
					(size 0.762 0.5334)
					(thickness 0.1016)
				)
			)
		)
		(fp_text user "E10"
			(at 20.18904 5.493601 0)
			(unlocked yes)
			(layer "F.SilkS")
			(effects
				(font
					(size 0.762 0.5334)
					(thickness 0.1016)
				)
			)
		)
		(fp_text user "A10"
			(at 20.18904 -0.106401 0)
			(unlocked yes)
			(layer "F.SilkS")
			(effects
				(font
					(size 0.762 0.5334)
					(thickness 0.1016)
				)
			)
		)
		(fp_text user "*"
			(at -1.5 -1.328549 0)
			(unlocked yes)
			(layer "F.SilkS")
			(effects
				(font
					(size 0.381 0.381)
					(thickness 0.381)
				)
			)
		)
		(fp_text user "O1"
			(at -1.810959 19.493601 0)
			(unlocked yes)
			(layer "F.SilkS")
			(effects
				(font
					(size 0.762 0.5334)
					(thickness 0.1016)
				)
			)
		)
		(fp_text user "J1"
			(at -1.810959 12.4936 0)
			(unlocked yes)
			(layer "F.SilkS")
			(effects
				(font
					(size 0.762 0.5334)
					(thickness 0.1016)
				)
			)
		)
		(fp_text user "A1"
			(at -1.810959 -0.106401 0)
			(unlocked yes)
			(layer "F.SilkS")
			(effects
				(font
					(size 0.762 0.5334)
					(thickness 0.1016)
				)
			)
		)
		(pad "A1" thru_hole rect
			(at 0 0 180)
			(size 0.8128 0.8128)
			(drill 0.508)
			(layers "*.Cu" "*.Mask")
			(remove_unused_layers no)
			(net "PCIE_T2B_B1_RX_DP<7>")
			(padstack
				(mode front_inner_back)
				(layer "Inner"
					(shape circle)
					(size 0.8128 0.8128)
				)
				(layer "B.Cu"
					(shape rect)
					(size 0.8128 0.8128)
				)
			)
		)
		(pad "A2" thru_hole circle
			(at 2.000001 -0.1 180)
			(size 0.8128 0.8128)
			(drill 0.508)
			(layers "*.Cu" "*.Mask")
			(remove_unused_layers no)
			(net "GND")
		)
		(pad "A3" thru_hole circle
			(at 4 0 180)
			(size 0.8128 0.8128)
			(drill 0.508)
			(layers "*.Cu" "*.Mask")
			(remove_unused_layers no)
			(net "PCIE_T2B_B1_RX_DP<5>")
		)
		(pad "A4" thru_hole circle
			(at 6.000001 -0.1 180)
			(size 0.8128 0.8128)
			(drill 0.508)
			(layers "*.Cu" "*.Mask")
			(remove_unused_layers no)
			(net "GND")
		)
		(pad "A5" thru_hole circle
			(at 7.999999 0 180)
			(size 0.8128 0.8128)
			(drill 0.508)
			(layers "*.Cu" "*.Mask")
			(remove_unused_layers no)
			(net "PCIE_T2B_B1_RX_DP<3>")
		)
		(pad "A6" thru_hole circle
			(at 10 -0.1 180)
			(size 0.8128 0.8128)
			(drill 0.508)
			(layers "*.Cu" "*.Mask")
			(remove_unused_layers no)
			(net "GND")
		)
		(pad "A7" thru_hole circle
			(at 11.999999 0 180)
			(size 0.8128 0.8128)
			(drill 0.508)
			(layers "*.Cu" "*.Mask")
			(remove_unused_layers no)
			(net "PCIE_T2B_B1_RX_DP<1>")
		)
		(pad "A8" thru_hole circle
			(at 14 -0.1 180)
			(size 0.8128 0.8128)
			(drill 0.508)
			(layers "*.Cu" "*.Mask")
			(remove_unused_layers no)
			(net "GND")
		)
		(pad "A9" thru_hole circle
			(at 16.000001 0 180)
			(size 0.8128 0.8128)
			(drill 0.508)
			(layers "*.Cu" "*.Mask")
			(remove_unused_layers no)
			(net "CLK_100M_B1_P<0>")
		)
		(pad "A10" thru_hole circle
			(at 18 -0.1 180)
			(size 0.8128 0.8128)
			(drill 0.508)
			(layers "*.Cu" "*.Mask")
			(remove_unused_layers no)
			(net "GND")
		)
		(pad "B1" thru_hole circle
			(at 0 1.4 180)
			(size 0.8128 0.8128)
			(drill 0.508)
			(layers "*.Cu" "*.Mask")
			(remove_unused_layers no)
			(net "PCIE_T2B_B1_RX_DN<7>")
		)
		(pad "B2" thru_hole circle
			(at 2.000001 1.3 180)
			(size 0.8128 0.8128)
			(drill 0.508)
			(layers "*.Cu" "*.Mask")
			(remove_unused_layers no)
			(net "PCIE_T2B_B1_RX_DP<6>")
		)
		(pad "B3" thru_hole circle
			(at 4 1.4 180)
			(size 0.8128 0.8128)
			(drill 0.508)
			(layers "*.Cu" "*.Mask")
			(remove_unused_layers no)
			(net "PCIE_T2B_B1_RX_DN<5>")
		)
		(pad "B4" thru_hole circle
			(at 6.000001 1.3 180)
			(size 0.8128 0.8128)
			(drill 0.508)
			(layers "*.Cu" "*.Mask")
			(remove_unused_layers no)
			(net "PCIE_T2B_B1_RX_DP<4>")
		)
		(pad "B5" thru_hole circle
			(at 7.999999 1.4 180)
			(size 0.8128 0.8128)
			(drill 0.508)
			(layers "*.Cu" "*.Mask")
			(remove_unused_layers no)
			(net "PCIE_T2B_B1_RX_DN<3>")
		)
		(pad "B6" thru_hole circle
			(at 10 1.3 180)
			(size 0.8128 0.8128)
			(drill 0.508)
			(layers "*.Cu" "*.Mask")
			(remove_unused_layers no)
			(net "PCIE_T2B_B1_RX_DP<2>")
		)
		(pad "B7" thru_hole circle
			(at 11.999999 1.4 180)
			(size 0.8128 0.8128)
			(drill 0.508)
			(layers "*.Cu" "*.Mask")
			(remove_unused_layers no)
			(net "PCIE_T2B_B1_RX_DN<1>")
		)
		(pad "B8" thru_hole circle
			(at 14 1.3 180)
			(size 0.8128 0.8128)
			(drill 0.508)
			(layers "*.Cu" "*.Mask")
			(remove_unused_layers no)
			(net "PCIE_T2B_B1_RX_DP<0>")
		)
		(pad "B9" thru_hole circle
			(at 16.000001 1.4 180)
			(size 0.8128 0.8128)
			(drill 0.508)
			(layers "*.Cu" "*.Mask")
			(remove_unused_layers no)
			(net "CLK_100M_B1_N<0>")
		)
		(pad "B10" thru_hole circle
			(at 18 1.3 180)
			(size 0.8128 0.8128)
			(drill 0.508)
			(layers "*.Cu" "*.Mask")
			(remove_unused_layers no)
			(net "USB_B1_P")
		)
		(pad "C1" thru_hole circle
			(at 0 2.799999 180)
			(size 0.8128 0.8128)
			(drill 0.508)
			(layers "*.Cu" "*.Mask")
			(remove_unused_layers no)
			(net "GND")
		)
		(pad "C2" thru_hole circle
			(at 2.000001 2.7 180)
			(size 0.8128 0.8128)
			(drill 0.508)
			(layers "*.Cu" "*.Mask")
			(remove_unused_layers no)
			(net "PCIE_T2B_B1_RX_DN<6>")
		)
		(pad "C3" thru_hole circle
			(at 4 2.799999 180)
			(size 0.8128 0.8128)
			(drill 0.508)
			(layers "*.Cu" "*.Mask")
			(remove_unused_layers no)
			(net "GND")
		)
		(pad "C4" thru_hole circle
			(at 6.000001 2.7 180)
			(size 0.8128 0.8128)
			(drill 0.508)
			(layers "*.Cu" "*.Mask")
			(remove_unused_layers no)
			(net "PCIE_T2B_B1_RX_DN<4>")
		)
		(pad "C5" thru_hole circle
			(at 7.999999 2.799999 180)
			(size 0.8128 0.8128)
			(drill 0.508)
			(layers "*.Cu" "*.Mask")
			(remove_unused_layers no)
			(net "GND")
		)
		(pad "C6" thru_hole circle
			(at 10 2.7 180)
			(size 0.8128 0.8128)
			(drill 0.508)
			(layers "*.Cu" "*.Mask")
			(remove_unused_layers no)
			(net "PCIE_T2B_B1_RX_DN<2>")
		)
		(pad "C7" thru_hole circle
			(at 11.999999 2.799999 180)
			(size 0.8128 0.8128)
			(drill 0.508)
			(layers "*.Cu" "*.Mask")
			(remove_unused_layers no)
			(net "GND")
		)
		(pad "C8" thru_hole circle
			(at 14 2.7 180)
			(size 0.8128 0.8128)
			(drill 0.508)
			(layers "*.Cu" "*.Mask")
			(remove_unused_layers no)
			(net "PCIE_T2B_B1_RX_DN<0>")
		)
		(pad "C9" thru_hole circle
			(at 16.000001 2.799999 180)
			(size 0.8128 0.8128)
			(drill 0.508)
			(layers "*.Cu" "*.Mask")
			(remove_unused_layers no)
			(net "GND")
		)
		(pad "C10" thru_hole circle
			(at 18 2.7 180)
			(size 0.8128 0.8128)
			(drill 0.508)
			(layers "*.Cu" "*.Mask")
			(remove_unused_layers no)
			(net "USB_B1_N")
		)
		(pad "D1" thru_hole circle
			(at 0 4.199999 180)
			(size 0.8128 0.8128)
			(drill 0.508)
			(layers "*.Cu" "*.Mask")
			(remove_unused_layers no)
			(net "PCIE_T2B_B1_RX_DP<15>")
		)
		(pad "D2" thru_hole circle
			(at 2.000001 4.099999 180)
			(size 0.8128 0.8128)
			(drill 0.508)
			(layers "*.Cu" "*.Mask")
			(remove_unused_layers no)
			(net "GND")
		)
		(pad "D3" thru_hole circle
			(at 4 4.199999 180)
			(size 0.8128 0.8128)
			(drill 0.508)
			(layers "*.Cu" "*.Mask")
			(remove_unused_layers no)
			(net "PCIE_T2B_B1_RX_DP<13>")
		)
		(pad "D4" thru_hole circle
			(at 6.000001 4.099999 180)
			(size 0.8128 0.8128)
			(drill 0.508)
			(layers "*.Cu" "*.Mask")
			(remove_unused_layers no)
			(net "GND")
		)
		(pad "D5" thru_hole circle
			(at 7.999999 4.199999 180)
			(size 0.8128 0.8128)
			(drill 0.508)
			(layers "*.Cu" "*.Mask")
			(remove_unused_layers no)
			(net "PCIE_T2B_B1_RX_DP<11>")
		)
		(pad "D6" thru_hole circle
			(at 10 4.099999 180)
			(size 0.8128 0.8128)
			(drill 0.508)
			(layers "*.Cu" "*.Mask")
			(remove_unused_layers no)
			(net "GND")
		)
		(pad "D7" thru_hole circle
			(at 11.999999 4.199999 180)
			(size 0.8128 0.8128)
			(drill 0.508)
			(layers "*.Cu" "*.Mask")
			(remove_unused_layers no)
			(net "PCIE_T2B_B1_RX_DP<9>")
		)
		(pad "D8" thru_hole circle
			(at 14 4.099999 180)
			(size 0.8128 0.8128)
			(drill 0.508)
			(layers "*.Cu" "*.Mask")
			(remove_unused_layers no)
			(net "GND")
		)
		(pad "D9" thru_hole circle
			(at 16.000001 4.199999 180)
			(size 0.8128 0.8128)
			(drill 0.508)
			(layers "*.Cu" "*.Mask")
			(remove_unused_layers no)
			(net "CLK_100M_B1_P<1>")
		)
		(pad "D10" thru_hole circle
			(at 18 4.099999 180)
			(size 0.8128 0.8128)
			(drill 0.508)
			(layers "*.Cu" "*.Mask")
			(remove_unused_layers no)
			(net "GND")
		)
		(pad "E1" thru_hole circle
			(at 0 5.599999 180)
			(size 0.8128 0.8128)
			(drill 0.508)
			(layers "*.Cu" "*.Mask")
			(remove_unused_layers no)
			(net "PCIE_T2B_B1_RX_DN<15>")
		)
		(pad "E2" thru_hole circle
			(at 2.000001 5.499999 180)
			(size 0.8128 0.8128)
			(drill 0.508)
			(layers "*.Cu" "*.Mask")
			(remove_unused_layers no)
			(net "PCIE_T2B_B1_RX_DP<14>")
		)
		(pad "E3" thru_hole circle
			(at 4 5.599999 180)
			(size 0.8128 0.8128)
			(drill 0.508)
			(layers "*.Cu" "*.Mask")
			(remove_unused_layers no)
			(net "PCIE_T2B_B1_RX_DN<13>")
		)
		(pad "E4" thru_hole circle
			(at 6.000001 5.499999 180)
			(size 0.8128 0.8128)
			(drill 0.508)
			(layers "*.Cu" "*.Mask")
			(remove_unused_layers no)
			(net "PCIE_T2B_B1_RX_DP<12>")
		)
		(pad "E5" thru_hole circle
			(at 7.999999 5.599999 180)
			(size 0.8128 0.8128)
			(drill 0.508)
			(layers "*.Cu" "*.Mask")
			(remove_unused_layers no)
			(net "PCIE_T2B_B1_RX_DN<11>")
		)
		(pad "E6" thru_hole circle
			(at 10 5.499999 180)
			(size 0.8128 0.8128)
			(drill 0.508)
			(layers "*.Cu" "*.Mask")
			(remove_unused_layers no)
			(net "PCIE_T2B_B1_RX_DP<10>")
		)
		(pad "E7" thru_hole circle
			(at 11.999999 5.599999 180)
			(size 0.8128 0.8128)
			(drill 0.508)
			(layers "*.Cu" "*.Mask")
			(remove_unused_layers no)
			(net "PCIE_T2B_B1_RX_DN<9>")
		)
		(pad "E8" thru_hole circle
			(at 14 5.499999 180)
			(size 0.8128 0.8128)
			(drill 0.508)
			(layers "*.Cu" "*.Mask")
			(remove_unused_layers no)
			(net "PCIE_T2B_B1_RX_DP<8>")
		)
		(pad "E9" thru_hole circle
			(at 16.000001 5.599999 180)
			(size 0.8128 0.8128)
			(drill 0.508)
			(layers "*.Cu" "*.Mask")
			(remove_unused_layers no)
			(net "CLK_100M_B1_N<1>")
		)
		(pad "E10" thru_hole circle
			(at 18 5.499999 180)
			(size 0.8128 0.8128)
			(drill 0.508)
			(layers "*.Cu" "*.Mask")
			(remove_unused_layers no)
			(net "P5V_USB_B1")
		)
		(pad "F1" thru_hole circle
			(at 0 7.000001 180)
			(size 0.8128 0.8128)
			(drill 0.508)
			(layers "*.Cu" "*.Mask")
			(remove_unused_layers no)
			(net "GND")
		)
		(pad "F2" thru_hole circle
			(at 2.000001 6.899999 180)
			(size 0.8128 0.8128)
			(drill 0.508)
			(layers "*.Cu" "*.Mask")
			(remove_unused_layers no)
			(net "PCIE_T2B_B1_RX_DN<14>")
		)
		(pad "F3" thru_hole circle
			(at 4 7.000001 180)
			(size 0.8128 0.8128)
			(drill 0.508)
			(layers "*.Cu" "*.Mask")
			(remove_unused_layers no)
			(net "GND")
		)
		(pad "F4" thru_hole circle
			(at 6.000001 6.899999 180)
			(size 0.8128 0.8128)
			(drill 0.508)
			(layers "*.Cu" "*.Mask")
			(remove_unused_layers no)
			(net "PCIE_T2B_B1_RX_DN<12>")
		)
		(pad "F5" thru_hole circle
			(at 7.999999 7.000001 180)
			(size 0.8128 0.8128)
			(drill 0.508)
			(layers "*.Cu" "*.Mask")
			(remove_unused_layers no)
			(net "GND")
		)
		(pad "F6" thru_hole circle
			(at 10 6.899999 180)
			(size 0.8128 0.8128)
			(drill 0.508)
			(layers "*.Cu" "*.Mask")
			(remove_unused_layers no)
			(net "PCIE_T2B_B1_RX_DN<10>")
		)
		(pad "F7" thru_hole circle
			(at 11.999999 7.000001 180)
			(size 0.8128 0.8128)
			(drill 0.508)
			(layers "*.Cu" "*.Mask")
			(remove_unused_layers no)
			(net "GND")
		)
		(pad "F8" thru_hole circle
			(at 14 6.899999 180)
			(size 0.8128 0.8128)
			(drill 0.508)
			(layers "*.Cu" "*.Mask")
			(remove_unused_layers no)
			(net "PCIE_T2B_B1_RX_DN<8>")
		)
		(pad "F9" thru_hole circle
			(at 16.000001 7.000001 180)
			(size 0.8128 0.8128)
			(drill 0.508)
			(layers "*.Cu" "*.Mask")
			(remove_unused_layers no)
			(net "GND")
		)
		(pad "F10" thru_hole circle
			(at 18 6.899999 180)
			(size 0.8128 0.8128)
			(drill 0.508)
			(layers "*.Cu" "*.Mask")
			(remove_unused_layers no)
			(net "GND")
		)
		(pad "G1" thru_hole circle
			(at 0 8.400001 180)
			(size 0.8128 0.8128)
			(drill 0.508)
			(layers "*.Cu" "*.Mask")
			(remove_unused_layers no)
			(net "PCIE_RESET_B1_N<3>")
		)
		(pad "G2" thru_hole circle
			(at 2.000001 8.300001 180)
			(size 0.8128 0.8128)
			(drill 0.508)
			(layers "*.Cu" "*.Mask")
			(remove_unused_layers no)
			(net "GND")
		)
		(pad "G3" thru_hole circle
			(at 4 8.400001 180)
			(size 0.8128 0.8128)
			(drill 0.508)
			(layers "*.Cu" "*.Mask")
			(remove_unused_layers no)
			(net "PCIE_CFG_B1_ID0")
		)
		(pad "G4" thru_hole circle
			(at 6.000001 8.300001 180)
			(size 0.8128 0.8128)
			(drill 0.508)
			(layers "*.Cu" "*.Mask")
			(remove_unused_layers no)
			(net "GND")
		)
		(pad "G5" thru_hole circle
			(at 7.999999 8.400001 180)
			(size 0.8128 0.8128)
			(drill 0.508)
			(layers "*.Cu" "*.Mask")
			(remove_unused_layers no)
			(net "MEZZ_B1_SCL")
		)
		(pad "G6" thru_hole circle
			(at 10 8.300001 180)
			(size 0.8128 0.8128)
			(drill 0.508)
			(layers "*.Cu" "*.Mask")
			(remove_unused_layers no)
			(net "GND")
		)
		(pad "G7" thru_hole circle
			(at 11.999999 8.400001 180)
			(size 0.8128 0.8128)
			(drill 0.508)
			(layers "*.Cu" "*.Mask")
			(remove_unused_layers no)
			(net "Net_3")
		)
		(pad "G8" thru_hole circle
			(at 14 8.300001 180)
			(size 0.8128 0.8128)
			(drill 0.508)
			(layers "*.Cu" "*.Mask")
			(remove_unused_layers no)
			(net "GND")
		)
		(pad "G9" thru_hole circle
			(at 16.000001 8.400001 180)
			(size 0.8128 0.8128)
			(drill 0.508)
			(layers "*.Cu" "*.Mask")
			(remove_unused_layers no)
			(net "CLK_100M_B1_P<2>")
		)
		(pad "G10" thru_hole circle
			(at 18 8.300001 180)
			(size 0.8128 0.8128)
			(drill 0.508)
			(layers "*.Cu" "*.Mask")
			(remove_unused_layers no)
			(net "GND")
		)
		(pad "H1" thru_hole circle
			(at 0 9.800001 180)
			(size 0.8128 0.8128)
			(drill 0.508)
			(layers "*.Cu" "*.Mask")
			(remove_unused_layers no)
			(net "PCIE_RESET_B1_N<2>")
		)
		(pad "H2" thru_hole circle
			(at 2.000001 9.700001 180)
			(size 0.8128 0.8128)
			(drill 0.508)
			(layers "*.Cu" "*.Mask")
			(remove_unused_layers no)
			(net "PCIE_RESET_B1_N<1>")
		)
		(pad "H3" thru_hole circle
			(at 4 9.800001 180)
			(size 0.8128 0.8128)
			(drill 0.508)
			(layers "*.Cu" "*.Mask")
			(remove_unused_layers no)
			(net "PCIE_CFG_B1_ID1")
		)
		(pad "H4" thru_hole circle
			(at 6.000001 9.700001 180)
			(size 0.8128 0.8128)
			(drill 0.508)
			(layers "*.Cu" "*.Mask")
			(remove_unused_layers no)
			(net "PCIE_WAKE_B1_N")
		)
		(pad "H5" thru_hole circle
			(at 7.999999 9.800001 180)
			(size 0.8128 0.8128)
			(drill 0.508)
			(layers "*.Cu" "*.Mask")
			(remove_unused_layers no)
			(net "MEZZ_B1_EN")
		)
		(pad "H6" thru_hole circle
			(at 10 9.700001 180)
			(size 0.8128 0.8128)
			(drill 0.508)
			(layers "*.Cu" "*.Mask")
			(remove_unused_layers no)
			(net "MEZZ_PRESENT_B1_N")
		)
		(pad "H7" thru_hole circle
			(at 11.999999 9.800001 180)
			(size 0.8128 0.8128)
			(drill 0.508)
			(layers "*.Cu" "*.Mask")
			(remove_unused_layers no)
			(net "PSU_B1_ALERT_N")
		)
		(pad "H8" thru_hole circle
			(at 14 9.700001 180)
			(size 0.8128 0.8128)
			(drill 0.508)
			(layers "*.Cu" "*.Mask")
			(remove_unused_layers no)
			(net "SERIAL_B1_TX2")
		)
		(pad "H9" thru_hole circle
			(at 16.000001 9.800001 180)
			(size 0.8128 0.8128)
			(drill 0.508)
			(layers "*.Cu" "*.Mask")
			(remove_unused_layers no)
			(net "CLK_100M_B1_N<2>")
		)
		(pad "H10" thru_hole circle
			(at 18 9.700001 180)
			(size 0.8128 0.8128)
			(drill 0.508)
			(layers "*.Cu" "*.Mask")
			(remove_unused_layers no)
			(net "GND")
		)
		(pad "I1" thru_hole circle
			(at 0 11.2 180)
			(size 0.8128 0.8128)
			(drill 0.508)
			(layers "*.Cu" "*.Mask")
			(remove_unused_layers no)
			(net "GND")
		)
		(pad "I2" thru_hole circle
			(at 2.000001 11.100001 180)
			(size 0.8128 0.8128)
			(drill 0.508)
			(layers "*.Cu" "*.Mask")
			(remove_unused_layers no)
			(net "PCIE_RESET_B1_N<0>")
		)
		(pad "I3" thru_hole circle
			(at 4 11.2 180)
			(size 0.8128 0.8128)
			(drill 0.508)
			(layers "*.Cu" "*.Mask")
			(remove_unused_layers no)
			(net "GND")
		)
		(pad "I4" thru_hole circle
			(at 6.000001 11.100001 180)
			(size 0.8128 0.8128)
			(drill 0.508)
			(layers "*.Cu" "*.Mask")
			(remove_unused_layers no)
			(net "MEZZ_B1_SDA")
		)
		(pad "I5" thru_hole circle
			(at 7.999999 11.2 180)
			(size 0.8128 0.8128)
			(drill 0.508)
			(layers "*.Cu" "*.Mask")
			(remove_unused_layers no)
			(net "GND")
		)
		(pad "I6" thru_hole circle
			(at 10 11.100001 180)
			(size 0.8128 0.8128)
			(drill 0.508)
			(layers "*.Cu" "*.Mask")
			(remove_unused_layers no)
			(net "BLADE_MATED_B1_N<0>")
		)
		(pad "I7" thru_hole circle
			(at 11.999999 11.2 180)
			(size 0.8128 0.8128)
			(drill 0.508)
			(layers "*.Cu" "*.Mask")
			(remove_unused_layers no)
			(net "GND")
		)
		(pad "I8" thru_hole circle
			(at 14 11.100001 180)
			(size 0.8128 0.8128)
			(drill 0.508)
			(layers "*.Cu" "*.Mask")
			(remove_unused_layers no)
			(net "SERIAL_B1_RX2")
		)
		(pad "I9" thru_hole circle
			(at 16.000001 11.2 180)
			(size 0.8128 0.8128)
			(drill 0.508)
			(layers "*.Cu" "*.Mask")
			(remove_unused_layers no)
			(net "GND")
		)
		(pad "I10" thru_hole circle
			(at 18 11.100001 180)
			(size 0.8128 0.8128)
			(drill 0.508)
			(layers "*.Cu" "*.Mask")
			(remove_unused_layers no)
			(net "P12V_MEZZ_B1")
		)
		(pad "J1" thru_hole circle
			(at 0 12.6 180)
			(size 0.8128 0.8128)
			(drill 0.508)
			(layers "*.Cu" "*.Mask")
			(remove_unused_layers no)
			(net "PCIE_B2T_B1_TX_DP<7>")
		)
		(pad "J2" thru_hole circle
			(at 2.000001 12.5 180)
			(size 0.8128 0.8128)
			(drill 0.508)
			(layers "*.Cu" "*.Mask")
			(remove_unused_layers no)
			(net "GND")
		)
		(pad "J3" thru_hole circle
			(at 4 12.6 180)
			(size 0.8128 0.8128)
			(drill 0.508)
			(layers "*.Cu" "*.Mask")
			(remove_unused_layers no)
			(net "PCIE_B2T_B1_TX_DP<5>")
		)
		(pad "J4" thru_hole circle
			(at 6.000001 12.5 180)
			(size 0.8128 0.8128)
			(drill 0.508)
			(layers "*.Cu" "*.Mask")
			(remove_unused_layers no)
			(net "GND")
		)
		(pad "J5" thru_hole circle
			(at 7.999999 12.6 180)
			(size 0.8128 0.8128)
			(drill 0.508)
			(layers "*.Cu" "*.Mask")
			(remove_unused_layers no)
			(net "PCIE_B2T_B1_TX_DP<3>")
		)
		(pad "J6" thru_hole circle
			(at 10 12.5 180)
			(size 0.8128 0.8128)
			(drill 0.508)
			(layers "*.Cu" "*.Mask")
			(remove_unused_layers no)
			(net "GND")
		)
		(pad "J7" thru_hole circle
			(at 11.999999 12.6 180)
			(size 0.8128 0.8128)
			(drill 0.508)
			(layers "*.Cu" "*.Mask")
			(remove_unused_layers no)
			(net "PCIE_B2T_B1_TX_DP<1>")
		)
		(pad "J8" thru_hole circle
			(at 14 12.5 180)
			(size 0.8128 0.8128)
			(drill 0.508)
			(layers "*.Cu" "*.Mask")
			(remove_unused_layers no)
			(net "GND")
		)
		(pad "J9" thru_hole circle
			(at 16.000001 12.6 180)
			(size 0.8128 0.8128)
			(drill 0.508)
			(layers "*.Cu" "*.Mask")
			(remove_unused_layers no)
			(net "CLK_100M_B1_P<3>")
		)
		(pad "J10" thru_hole circle
			(at 18 12.5 180)
			(size 0.8128 0.8128)
			(drill 0.508)
			(layers "*.Cu" "*.Mask")
			(remove_unused_layers no)
			(net "P12V_MEZZ_B1")
		)
		(pad "K1" thru_hole circle
			(at 0 14 180)
			(size 0.8128 0.8128)
			(drill 0.508)
			(layers "*.Cu" "*.Mask")
			(remove_unused_layers no)
			(net "PCIE_B2T_B1_TX_DN<7>")
		)
		(pad "K2" thru_hole circle
			(at 2.000001 13.9 180)
			(size 0.8128 0.8128)
			(drill 0.508)
			(layers "*.Cu" "*.Mask")
			(remove_unused_layers no)
			(net "PCIE_B2T_B1_TX_DP<6>")
		)
		(pad "K3" thru_hole circle
			(at 4 14 180)
			(size 0.8128 0.8128)
			(drill 0.508)
			(layers "*.Cu" "*.Mask")
			(remove_unused_layers no)
			(net "PCIE_B2T_B1_TX_DN<5>")
		)
		(pad "K4" thru_hole circle
			(at 6.000001 13.9 180)
			(size 0.8128 0.8128)
			(drill 0.508)
			(layers "*.Cu" "*.Mask")
			(remove_unused_layers no)
			(net "PCIE_B2T_B1_TX_DP<4>")
		)
		(pad "K5" thru_hole circle
			(at 7.999999 14 180)
			(size 0.8128 0.8128)
			(drill 0.508)
			(layers "*.Cu" "*.Mask")
			(remove_unused_layers no)
			(net "PCIE_B2T_B1_TX_DN<3>")
		)
		(pad "K6" thru_hole circle
			(at 10 13.9 180)
			(size 0.8128 0.8128)
			(drill 0.508)
			(layers "*.Cu" "*.Mask")
			(remove_unused_layers no)
			(net "PCIE_B2T_B1_TX_DP<2>")
		)
		(pad "K7" thru_hole circle
			(at 11.999999 14 180)
			(size 0.8128 0.8128)
			(drill 0.508)
			(layers "*.Cu" "*.Mask")
			(remove_unused_layers no)
			(net "PCIE_B2T_B1_TX_DN<1>")
		)
		(pad "K8" thru_hole circle
			(at 14 13.9 180)
			(size 0.8128 0.8128)
			(drill 0.508)
			(layers "*.Cu" "*.Mask")
			(remove_unused_layers no)
			(net "PCIE_B2T_B1_TX_DP<0>")
		)
		(pad "K9" thru_hole circle
			(at 16.000001 14 180)
			(size 0.8128 0.8128)
			(drill 0.508)
			(layers "*.Cu" "*.Mask")
			(remove_unused_layers no)
			(net "CLK_100M_B1_N<3>")
		)
		(pad "K10" thru_hole circle
			(at 18 13.9 180)
			(size 0.8128 0.8128)
			(drill 0.508)
			(layers "*.Cu" "*.Mask")
			(remove_unused_layers no)
			(net "P12V_MEZZ_B1")
		)
		(pad "L1" thru_hole circle
			(at 0 15.4 180)
			(size 0.8128 0.8128)
			(drill 0.508)
			(layers "*.Cu" "*.Mask")
			(remove_unused_layers no)
			(net "GND")
		)
		(pad "L2" thru_hole circle
			(at 2.000001 15.3 180)
			(size 0.8128 0.8128)
			(drill 0.508)
			(layers "*.Cu" "*.Mask")
			(remove_unused_layers no)
			(net "PCIE_B2T_B1_TX_DN<6>")
		)
		(pad "L3" thru_hole circle
			(at 4 15.4 180)
			(size 0.8128 0.8128)
			(drill 0.508)
			(layers "*.Cu" "*.Mask")
			(remove_unused_layers no)
			(net "GND")
		)
		(pad "L4" thru_hole circle
			(at 6.000001 15.3 180)
			(size 0.8128 0.8128)
			(drill 0.508)
			(layers "*.Cu" "*.Mask")
			(remove_unused_layers no)
			(net "PCIE_B2T_B1_TX_DN<4>")
		)
		(pad "L5" thru_hole circle
			(at 7.999999 15.4 180)
			(size 0.8128 0.8128)
			(drill 0.508)
			(layers "*.Cu" "*.Mask")
			(remove_unused_layers no)
			(net "GND")
		)
		(pad "L6" thru_hole circle
			(at 10 15.3 180)
			(size 0.8128 0.8128)
			(drill 0.508)
			(layers "*.Cu" "*.Mask")
			(remove_unused_layers no)
			(net "PCIE_B2T_B1_TX_DN<2>")
		)
		(pad "L7" thru_hole circle
			(at 11.999999 15.4 180)
			(size 0.8128 0.8128)
			(drill 0.508)
			(layers "*.Cu" "*.Mask")
			(remove_unused_layers no)
			(net "GND")
		)
		(pad "L8" thru_hole circle
			(at 14 15.3 180)
			(size 0.8128 0.8128)
			(drill 0.508)
			(layers "*.Cu" "*.Mask")
			(remove_unused_layers no)
			(net "PCIE_B2T_B1_TX_DN<0>")
		)
		(pad "L9" thru_hole circle
			(at 16.000001 15.4 180)
			(size 0.8128 0.8128)
			(drill 0.508)
			(layers "*.Cu" "*.Mask")
			(remove_unused_layers no)
			(net "GND")
		)
		(pad "L10" thru_hole circle
			(at 18 15.3 180)
			(size 0.8128 0.8128)
			(drill 0.508)
			(layers "*.Cu" "*.Mask")
			(remove_unused_layers no)
			(net "P12V_MEZZ_B1")
		)
		(pad "M1" thru_hole circle
			(at 0 16.799999 180)
			(size 0.8128 0.8128)
			(drill 0.508)
			(layers "*.Cu" "*.Mask")
			(remove_unused_layers no)
			(net "PCIE_B2T_B1_TX_DP<15>")
		)
		(pad "M2" thru_hole circle
			(at 2.000001 16.7 180)
			(size 0.8128 0.8128)
			(drill 0.508)
			(layers "*.Cu" "*.Mask")
			(remove_unused_layers no)
			(net "GND")
		)
		(pad "M3" thru_hole circle
			(at 4 16.799999 180)
			(size 0.8128 0.8128)
			(drill 0.508)
			(layers "*.Cu" "*.Mask")
			(remove_unused_layers no)
			(net "PCIE_B2T_B1_TX_DP<13>")
		)
		(pad "M4" thru_hole circle
			(at 6.000001 16.7 180)
			(size 0.8128 0.8128)
			(drill 0.508)
			(layers "*.Cu" "*.Mask")
			(remove_unused_layers no)
			(net "GND")
		)
		(pad "M5" thru_hole circle
			(at 7.999999 16.799999 180)
			(size 0.8128 0.8128)
			(drill 0.508)
			(layers "*.Cu" "*.Mask")
			(remove_unused_layers no)
			(net "PCIE_B2T_B1_TX_DP<11>")
		)
		(pad "M6" thru_hole circle
			(at 10 16.7 180)
			(size 0.8128 0.8128)
			(drill 0.508)
			(layers "*.Cu" "*.Mask")
			(remove_unused_layers no)
			(net "GND")
		)
		(pad "M7" thru_hole circle
			(at 11.999999 16.799999 180)
			(size 0.8128 0.8128)
			(drill 0.508)
			(layers "*.Cu" "*.Mask")
			(remove_unused_layers no)
			(net "PCIE_B2T_B1_TX_DP<9>")
		)
		(pad "M8" thru_hole circle
			(at 14 16.7 180)
			(size 0.8128 0.8128)
			(drill 0.508)
			(layers "*.Cu" "*.Mask")
			(remove_unused_layers no)
			(net "GND")
		)
		(pad "M9" thru_hole circle
			(at 16.000001 16.799999 180)
			(size 0.8128 0.8128)
			(drill 0.508)
			(layers "*.Cu" "*.Mask")
			(remove_unused_layers no)
			(net "GND")
		)
		(pad "M10" thru_hole circle
			(at 18 16.7 180)
			(size 0.8128 0.8128)
			(drill 0.508)
			(layers "*.Cu" "*.Mask")
			(remove_unused_layers no)
			(net "GND")
		)
		(pad "N1" thru_hole circle
			(at 0 18.199999 180)
			(size 0.8128 0.8128)
			(drill 0.508)
			(layers "*.Cu" "*.Mask")
			(remove_unused_layers no)
			(net "PCIE_B2T_B1_TX_DN<15>")
		)
		(pad "N2" thru_hole circle
			(at 2.000001 18.099999 180)
			(size 0.8128 0.8128)
			(drill 0.508)
			(layers "*.Cu" "*.Mask")
			(remove_unused_layers no)
			(net "PCIE_B2T_B1_TX_DP<14>")
		)
		(pad "N3" thru_hole circle
			(at 4 18.199999 180)
			(size 0.8128 0.8128)
			(drill 0.508)
			(layers "*.Cu" "*.Mask")
			(remove_unused_layers no)
			(net "PCIE_B2T_B1_TX_DN<13>")
		)
		(pad "N4" thru_hole circle
			(at 6.000001 18.099999 180)
			(size 0.8128 0.8128)
			(drill 0.508)
			(layers "*.Cu" "*.Mask")
			(remove_unused_layers no)
			(net "PCIE_B2T_B1_TX_DP<12>")
		)
		(pad "N5" thru_hole circle
			(at 7.999999 18.199999 180)
			(size 0.8128 0.8128)
			(drill 0.508)
			(layers "*.Cu" "*.Mask")
			(remove_unused_layers no)
			(net "PCIE_B2T_B1_TX_DN<11>")
		)
		(pad "N6" thru_hole circle
			(at 10 18.099999 180)
			(size 0.8128 0.8128)
			(drill 0.508)
			(layers "*.Cu" "*.Mask")
			(remove_unused_layers no)
			(net "PCIE_B2T_B1_TX_DP<10>")
		)
		(pad "N7" thru_hole circle
			(at 11.999999 18.199999 180)
			(size 0.8128 0.8128)
			(drill 0.508)
			(layers "*.Cu" "*.Mask")
			(remove_unused_layers no)
			(net "PCIE_B2T_B1_TX_DN<9>")
		)
		(pad "N8" thru_hole circle
			(at 14 18.099999 180)
			(size 0.8128 0.8128)
			(drill 0.508)
			(layers "*.Cu" "*.Mask")
			(remove_unused_layers no)
			(net "PCIE_B2T_B1_TX_DP<8>")
		)
		(pad "N9" thru_hole circle
			(at 16.000001 18.199999 180)
			(size 0.8128 0.8128)
			(drill 0.508)
			(layers "*.Cu" "*.Mask")
			(remove_unused_layers no)
			(net "GND")
		)
		(pad "N10" thru_hole circle
			(at 18 18.099999 180)
			(size 0.8128 0.8128)
			(drill 0.508)
			(layers "*.Cu" "*.Mask")
			(remove_unused_layers no)
			(net "P12V_MEZZ_B1")
		)
		(pad "O1" thru_hole circle
			(at 0 19.599999 180)
			(size 0.8128 0.8128)
			(drill 0.508)
			(layers "*.Cu" "*.Mask")
			(remove_unused_layers no)
			(net "GND")
		)
		(pad "O2" thru_hole circle
			(at 2.000001 19.499999 180)
			(size 0.8128 0.8128)
			(drill 0.508)
			(layers "*.Cu" "*.Mask")
			(remove_unused_layers no)
			(net "PCIE_B2T_B1_TX_DN<14>")
		)
		(pad "O3" thru_hole circle
			(at 4 19.599999 180)
			(size 0.8128 0.8128)
			(drill 0.508)
			(layers "*.Cu" "*.Mask")
			(remove_unused_layers no)
			(net "GND")
		)
		(pad "O4" thru_hole circle
			(at 6.000001 19.499999 180)
			(size 0.8128 0.8128)
			(drill 0.508)
			(layers "*.Cu" "*.Mask")
			(remove_unused_layers no)
			(net "PCIE_B2T_B1_TX_DN<12>")
		)
		(pad "O5" thru_hole circle
			(at 7.999999 19.599999 180)
			(size 0.8128 0.8128)
			(drill 0.508)
			(layers "*.Cu" "*.Mask")
			(remove_unused_layers no)
			(net "GND")
		)
		(pad "O6" thru_hole circle
			(at 10 19.499999 180)
			(size 0.8128 0.8128)
			(drill 0.508)
			(layers "*.Cu" "*.Mask")
			(remove_unused_layers no)
			(net "PCIE_B2T_B1_TX_DN<10>")
		)
		(pad "O7" thru_hole circle
			(at 11.999999 19.599999 180)
			(size 0.8128 0.8128)
			(drill 0.508)
			(layers "*.Cu" "*.Mask")
			(remove_unused_layers no)
			(net "GND")
		)
		(pad "O8" thru_hole circle
			(at 14 19.499999 180)
			(size 0.8128 0.8128)
			(drill 0.508)
			(layers "*.Cu" "*.Mask")
			(remove_unused_layers no)
			(net "PCIE_B2T_B1_TX_DN<8>")
		)
		(pad "O9" thru_hole circle
			(at 16.000001 19.599999 180)
			(size 0.8128 0.8128)
			(drill 0.508)
			(layers "*.Cu" "*.Mask")
			(remove_unused_layers no)
			(net "GND")
		)
		(pad "O10" thru_hole circle
			(at 18 19.499999 180)
			(size 0.8128 0.8128)
			(drill 0.508)
			(layers "*.Cu" "*.Mask")
			(remove_unused_layers no)
			(net "P12V_MEZZ_B1")
		)
		(pad "P2" thru_hole circle
			(at 2.000001 20.899999 180)
			(size 0.8128 0.8128)
			(drill 0.508)
			(layers "*.Cu" "*.Mask")
			(remove_unused_layers no)
			(net "GND")
		)
		(pad "P4" thru_hole circle
			(at 6.000001 20.899999 180)
			(size 0.8128 0.8128)
			(drill 0.508)
			(layers "*.Cu" "*.Mask")
			(remove_unused_layers no)
			(net "GND")
		)
		(pad "P6" thru_hole circle
			(at 10 20.899999 180)
			(size 0.8128 0.8128)
			(drill 0.508)
			(layers "*.Cu" "*.Mask")
			(remove_unused_layers no)
			(net "GND")
		)
		(pad "P8" thru_hole circle
			(at 14 20.899999 180)
			(size 0.8128 0.8128)
			(drill 0.508)
			(layers "*.Cu" "*.Mask")
			(remove_unused_layers no)
			(net "GND")
		)
		(pad "P10" thru_hole circle
			(at 18 20.899999 180)
			(size 0.8128 0.8128)
			(drill 0.508)
			(layers "*.Cu" "*.Mask")
			(remove_unused_layers no)
			(net "GND")
		)
	)
	(footprint ""
		(layer "F.Cu")
		(at -48.3616 2.8702 -90)
		(property "Reference" "C24"
			(at 0.00254 1.20396 90)
			(unlocked yes)
			(layer "F.SilkS")
			(effects
				(font
					(size 0.762 0.5334)
					(thickness 0.1016)
				)
			)
		)
		(property "Value" ""
			(at 0 0 270)
			(layer "F.Fab")
			(effects
				(font
					(size 1.27 1.27)
				)
			)
		)
		(duplicate_pad_numbers_are_jumpers no)
		(fp_line
			(start 0 -0.381)
			(end 0 0.381)
			(stroke
				(width 0.127)
				(type default)
			)
			(layer "F.SilkS")
		)
		(fp_poly
			(pts
				(xy 1.2533 0.6564) (xy -1.253299 0.6564) (xy -1.253299 -0.656399) (xy 1.2533 -0.656399)
			)
			(stroke
				(width 0)
				(type default)
			)
			(fill no)
			(layer "F.CrtYd")
		)
		(fp_line
			(start -0.762 0.381)
			(end 0.762 0.381)
			(stroke
				(width 0.1)
				(type default)
			)
			(layer "F.Fab")
		)
		(fp_line
			(start 0.762 0.381)
			(end 0.762 -0.381)
			(stroke
				(width 0.1)
				(type default)
			)
			(layer "F.Fab")
		)
		(fp_line
			(start -0.762 -0.381)
			(end -0.762 0.381)
			(stroke
				(width 0.1)
				(type default)
			)
			(layer "F.Fab")
		)
		(fp_line
			(start 0.762 -0.381)
			(end -0.762 -0.381)
			(stroke
				(width 0.1)
				(type default)
			)
			(layer "F.Fab")
		)
		(pad "1" smd rect
			(at -0.6477 0 270)
			(size 0.7112 0.8128)
			(layers "F.Cu" "F.Mask" "F.Paste")
			(net "P3V3_40G_B2_VCC_RX")
		)
		(pad "2" smd rect
			(at 0.6477 0 90)
			(size 0.7112 0.8128)
			(layers "F.Cu" "F.Mask" "F.Paste")
			(net "GND")
		)
	)
	(footprint ""
		(layer "F.Cu")
		(at -282.785401 44.869202 90)
		(property "Reference" "R13"
			(at 4.102202 -0.005499 90)
			(unlocked yes)
			(layer "F.SilkS")
			(effects
				(font
					(size 0.762 0.5334)
					(thickness 0.1016)
				)
			)
		)
		(property "Value" ""
			(at 0 0 90)
			(layer "F.Fab")
			(effects
				(font
					(size 1.27 1.27)
				)
			)
		)
		(duplicate_pad_numbers_are_jumpers no)
		(fp_line
			(start 0 -0.381)
			(end 0 0.381)
			(stroke
				(width 0.127)
				(type default)
			)
			(layer "F.SilkS")
		)
		(fp_poly
			(pts
				(xy 1.255601 0.6564) (xy -1.2556 0.6564) (xy -1.2556 -0.656399) (xy 1.255601 -0.656399)
			)
			(stroke
				(width 0)
				(type default)
			)
			(fill no)
			(layer "F.CrtYd")
		)
		(fp_line
			(start 0.800001 -0.399999)
			(end -0.800001 -0.399999)
			(stroke
				(width 0.1)
				(type default)
			)
			(layer "F.Fab")
		)
		(fp_line
			(start -0.800001 -0.399999)
			(end -0.800001 0.399999)
			(stroke
				(width 0.1)
				(type default)
			)
			(layer "F.Fab")
		)
		(fp_line
			(start 0.800001 0.399999)
			(end 0.800001 -0.399999)
			(stroke
				(width 0.1)
				(type default)
			)
			(layer "F.Fab")
		)
		(fp_line
			(start -0.800001 0.399999)
			(end 0.800001 0.399999)
			(stroke
				(width 0.1)
				(type default)
			)
			(layer "F.Fab")
		)
		(pad "1" smd rect
			(at -0.650001 0 90)
			(size 0.7112 0.8128)
			(layers "F.Cu" "F.Mask" "F.Paste")
			(net "P3V3_B1_QSFP")
		)
		(pad "2" smd rect
			(at 0.650001 0 270)
			(size 0.7112 0.8128)
			(layers "F.Cu" "F.Mask" "F.Paste")
			(net "P3V3_10G_B1_VCCR")
		)
	)
	(footprint ""
		(layer "F.Cu")
		(at -114.0714 16.8656 -90)
		(property "Reference" "R70"
			(at -2.8956 -0.0635 90)
			(unlocked yes)
			(layer "F.SilkS")
			(effects
				(font
					(size 0.762 0.5334)
					(thickness 0.1016)
				)
			)
		)
		(property "Value" ""
			(at 0 0 270)
			(layer "F.Fab")
			(effects
				(font
					(size 1.27 1.27)
				)
			)
		)
		(duplicate_pad_numbers_are_jumpers no)
		(fp_line
			(start 0 -0.381)
			(end 0 0.381)
			(stroke
				(width 0.127)
				(type default)
			)
			(layer "F.SilkS")
		)
		(fp_poly
			(pts
				(xy 1.255601 0.6564) (xy -1.255601 0.6564) (xy -1.255601 -0.656399) (xy 1.255601 -0.656399)
			)
			(stroke
				(width 0)
				(type default)
			)
			(fill no)
			(layer "F.CrtYd")
		)
		(fp_line
			(start -0.800001 0.399999)
			(end 0.800001 0.399999)
			(stroke
				(width 0.1)
				(type default)
			)
			(layer "F.Fab")
		)
		(fp_line
			(start 0.800001 0.399999)
			(end 0.800001 -0.399999)
			(stroke
				(width 0.1)
				(type default)
			)
			(layer "F.Fab")
		)
		(fp_line
			(start -0.800001 -0.399999)
			(end -0.800001 0.399999)
			(stroke
				(width 0.1)
				(type default)
			)
			(layer "F.Fab")
		)
		(fp_line
			(start 0.800001 -0.399999)
			(end -0.800001 -0.399999)
			(stroke
				(width 0.1)
				(type default)
			)
			(layer "F.Fab")
		)
		(pad "1" smd rect
			(at -0.650001 0 270)
			(size 0.7112 0.8128)
			(layers "F.Cu" "F.Mask" "F.Paste")
			(net "P3V3_B2_QSFP")
		)
		(pad "2" smd rect
			(at 0.650001 0 90)
			(size 0.7112 0.8128)
			(layers "F.Cu" "F.Mask" "F.Paste")
			(net "ETH40G_B2_LPMODE")
		)
	)
	(footprint ""
		(layer "F.Cu")
		(at -110.8456 14.6304)
		(property "Reference" "R68"
			(at 3.2766 0.0127 0)
			(unlocked yes)
			(layer "F.SilkS")
			(effects
				(font
					(size 0.762 0.5334)
					(thickness 0.1016)
				)
			)
		)
		(property "Value" ""
			(at 0 0 0)
			(layer "F.Fab")
			(effects
				(font
					(size 1.27 1.27)
				)
			)
		)
		(duplicate_pad_numbers_are_jumpers no)
		(fp_line
			(start 0 -0.381)
			(end 0 0.381)
			(stroke
				(width 0.127)
				(type default)
			)
			(layer "F.SilkS")
		)
		(fp_poly
			(pts
				(xy 1.255601 0.6564) (xy -1.255601 0.6564) (xy -1.255601 -0.656399) (xy 1.255601 -0.656399)
			)
			(stroke
				(width 0)
				(type default)
			)
			(fill no)
			(layer "F.CrtYd")
		)
		(fp_line
			(start -0.800001 -0.399999)
			(end -0.800001 0.399999)
			(stroke
				(width 0.1)
				(type default)
			)
			(layer "F.Fab")
		)
		(fp_line
			(start -0.800001 0.399999)
			(end 0.800001 0.399999)
			(stroke
				(width 0.1)
				(type default)
			)
			(layer "F.Fab")
		)
		(fp_line
			(start 0.800001 -0.399999)
			(end -0.800001 -0.399999)
			(stroke
				(width 0.1)
				(type default)
			)
			(layer "F.Fab")
		)
		(fp_line
			(start 0.800001 0.399999)
			(end 0.800001 -0.399999)
			(stroke
				(width 0.1)
				(type default)
			)
			(layer "F.Fab")
		)
		(pad "1" smd rect
			(at -0.650001 0)
			(size 0.7112 0.8128)
			(layers "F.Cu" "F.Mask" "F.Paste")
			(net "P3V3_B2_QSFP")
		)
		(pad "2" smd rect
			(at 0.650001 0 180)
			(size 0.7112 0.8128)
			(layers "F.Cu" "F.Mask" "F.Paste")
			(net "ETH40G_B2_SCL")
		)
	)
	(footprint ""
		(layer "F.Cu")
		(at -75.3618 12.3952 180)
		(property "Reference" "R54"
			(at -2.413 -0.0381 0)
			(unlocked yes)
			(layer "F.SilkS")
			(effects
				(font
					(size 0.762 0.5334)
					(thickness 0.1016)
				)
			)
		)
		(property "Value" ""
			(at 0 0 180)
			(layer "F.Fab")
			(effects
				(font
					(size 1.27 1.27)
				)
			)
		)
		(duplicate_pad_numbers_are_jumpers no)
		(fp_line
			(start 0 -0.381)
			(end 0 0.381)
			(stroke
				(width 0.127)
				(type default)
			)
			(layer "F.SilkS")
		)
		(fp_poly
			(pts
				(xy 1.255601 0.656399) (xy -1.255601 0.656399) (xy -1.255601 -0.6564) (xy 1.255601 -0.6564)
			)
			(stroke
				(width 0)
				(type default)
			)
			(fill no)
			(layer "F.CrtYd")
		)
		(fp_line
			(start 0.800001 0.399999)
			(end 0.800001 -0.399999)
			(stroke
				(width 0.1)
				(type default)
			)
			(layer "F.Fab")
		)
		(fp_line
			(start 0.800001 -0.399999)
			(end -0.800001 -0.399999)
			(stroke
				(width 0.1)
				(type default)
			)
			(layer "F.Fab")
		)
		(fp_line
			(start -0.800001 0.399999)
			(end 0.800001 0.399999)
			(stroke
				(width 0.1)
				(type default)
			)
			(layer "F.Fab")
		)
		(fp_line
			(start -0.800001 -0.399999)
			(end -0.800001 0.399999)
			(stroke
				(width 0.1)
				(type default)
			)
			(layer "F.Fab")
		)
		(pad "1" smd rect
			(at -0.650001 0 180)
			(size 0.7112 0.8128)
			(layers "F.Cu" "F.Mask" "F.Paste")
			(net "P3V3_B2_QSFP")
		)
		(pad "2" smd rect
			(at 0.650001 0)
			(size 0.7112 0.8128)
			(layers "F.Cu" "F.Mask" "F.Paste")
			(net "ETH10G_B2_SDA")
		)
	)
	(footprint ""
		(layer "F.Cu")
		(at -282.750001 32.059999 180)
		(property "Reference" "J5"
			(at 7.391659 -7.216021 0)
			(unlocked yes)
			(layer "F.SilkS")
			(effects
				(font
					(size 0.762 0.5334)
					(thickness 0.1016)
				)
			)
		)
		(property "Value" ""
			(at 0 0 180)
			(layer "F.Fab")
			(effects
				(font
					(size 1.27 1.27)
				)
			)
		)
		(duplicate_pad_numbers_are_jumpers no)
		(fp_line
			(start 5.499999 3.85)
			(end 4.500001 3.85)
			(stroke
				(width 0.127)
				(type default)
			)
			(layer "F.SilkS")
		)
		(fp_line
			(start 5.499999 1.499999)
			(end 5.499999 3.85)
			(stroke
				(width 0.127)
				(type default)
			)
			(layer "F.SilkS")
		)
		(fp_line
			(start 5.499999 -1.5)
			(end 5.499999 -3.85)
			(stroke
				(width 0.127)
				(type default)
			)
			(layer "F.SilkS")
		)
		(fp_line
			(start 5.499999 -3.85)
			(end 4 -3.85)
			(stroke
				(width 0.127)
				(type default)
			)
			(layer "F.SilkS")
		)
		(fp_line
			(start -4 3.85)
			(end -5.499999 3.85)
			(stroke
				(width 0.127)
				(type default)
			)
			(layer "F.SilkS")
		)
		(fp_line
			(start -5.499999 3.85)
			(end -5.499999 1.499999)
			(stroke
				(width 0.127)
				(type default)
			)
			(layer "F.SilkS")
		)
		(fp_line
			(start -5.499999 -1.5)
			(end -5.499999 -2.85)
			(stroke
				(width 0.127)
				(type default)
			)
			(layer "F.SilkS")
		)
		(fp_line
			(start -5.499999 -2.85)
			(end -4.500001 -3.85)
			(stroke
				(width 0.127)
				(type default)
			)
			(layer "F.SilkS")
		)
		(fp_poly
			(pts
				(xy -4.154 5.603301) (xy -4.154 4.349999) (xy -6.000001 4.349999) (xy -6.000001 -4.349999) (xy -4.553999 -4.349999)
				(xy -4.553999 -5.603301) (xy 4.154 -5.603301) (xy 4.154 -4.349999) (xy 6.000001 -4.349999) (xy 6.000001 4.349999)
				(xy 4.553999 4.349999) (xy 4.553999 5.603301)
			)
			(stroke
				(width 0)
				(type default)
			)
			(fill no)
			(layer "F.CrtYd")
		)
		(fp_line
			(start 5.499999 3.85)
			(end -5.499999 3.85)
			(stroke
				(width 0.1)
				(type default)
			)
			(layer "F.Fab")
		)
		(fp_line
			(start 5.499999 -3.85)
			(end 5.499999 3.85)
			(stroke
				(width 0.1)
				(type default)
			)
			(layer "F.Fab")
		)
		(fp_line
			(start -4.500001 -3.85)
			(end 5.499999 -3.85)
			(stroke
				(width 0.1)
				(type default)
			)
			(layer "F.Fab")
		)
		(fp_line
			(start -5.499999 3.85)
			(end -5.499999 -2.85)
			(stroke
				(width 0.1)
				(type default)
			)
			(layer "F.Fab")
		)
		(fp_line
			(start -5.499999 -2.85)
			(end -4.500001 -3.85)
			(stroke
				(width 0.1)
				(type default)
			)
			(layer "F.Fab")
		)
		(fp_text user "10"
			(at 5.057399 4.582279 0)
			(unlocked yes)
			(layer "F.SilkS")
			(effects
				(font
					(size 0.762 0.5334)
					(thickness 0.1016)
				)
			)
		)
		(fp_text user "11"
			(at 4.811019 -4.620141 0)
			(unlocked yes)
			(layer "F.SilkS")
			(effects
				(font
					(size 0.762 0.5334)
					(thickness 0.1016)
				)
			)
		)
		(fp_text user "*"
			(at -4.658101 5.741789 0)
			(unlocked yes)
			(layer "F.SilkS")
			(effects
				(font
					(size 0.381 0.381)
					(thickness 0.381)
				)
			)
		)
		(fp_text user "20"
			(at -5.211821 -4.538861 0)
			(unlocked yes)
			(layer "F.SilkS")
			(effects
				(font
					(size 0.762 0.5334)
					(thickness 0.1016)
				)
			)
		)
		(pad "" np_thru_hole circle
			(at -4.800001 0 180)
			(size 1.27 1.27)
			(drill 1.6002)
			(layers "*.Cu" "*.Mask")
		)
		(pad "" np_thru_hole circle
			(at 4.800001 0 180)
			(size 1.27 1.27)
			(drill 1.6002)
			(layers "*.Cu" "*.Mask")
		)
		(pad "1" smd oval
			(at -3.400001 4.099999 180)
			(size 0.508 2.0066)
			(layers "F.Cu" "F.Mask" "F.Paste")
			(net "GND")
		)
		(pad "2" smd oval
			(at -2.6 4.099999 180)
			(size 0.508 2.0066)
			(layers "F.Cu" "F.Mask" "F.Paste")
			(net "ETH10G_B1_TX_FAULT")
		)
		(pad "3" smd oval
			(at -1.799999 4.099999 180)
			(size 0.508 2.0066)
			(layers "F.Cu" "F.Mask" "F.Paste")
			(net "ETH10G_B1_TX_DIS")
		)
		(pad "4" smd oval
			(at -1.000001 4.099999 180)
			(size 0.508 2.0066)
			(layers "F.Cu" "F.Mask" "F.Paste")
			(net "ETH10G_B1_SDA")
		)
		(pad "5" smd oval
			(at -0.2 4.099999 180)
			(size 0.508 2.0066)
			(layers "F.Cu" "F.Mask" "F.Paste")
			(net "ETH10G_B1_SCL")
		)
		(pad "6" smd oval
			(at 0.599999 4.099999 180)
			(size 0.508 2.0066)
			(layers "F.Cu" "F.Mask" "F.Paste")
			(net "ETH10G_B1_MOD_ABS")
		)
		(pad "7" smd oval
			(at 1.4 4.099999 180)
			(size 0.508 2.0066)
			(layers "F.Cu" "F.Mask" "F.Paste")
			(net "ETH10G_B1_RS0")
		)
		(pad "8" smd oval
			(at 2.200001 4.099999 180)
			(size 0.508 2.0066)
			(layers "F.Cu" "F.Mask" "F.Paste")
			(net "ETH10G_B1_RX_LOS")
		)
		(pad "9" smd oval
			(at 2.999999 4.099999 180)
			(size 0.508 2.0066)
			(layers "F.Cu" "F.Mask" "F.Paste")
			(net "ETH10G_B1_RS1")
		)
		(pad "10" smd oval
			(at 3.8 4.099999 180)
			(size 0.508 2.0066)
			(layers "F.Cu" "F.Mask" "F.Paste")
			(net "GND")
		)
		(pad "11" smd oval
			(at 3.400001 -4.099999 180)
			(size 0.508 2.0066)
			(layers "F.Cu" "F.Mask" "F.Paste")
			(net "GND")
		)
		(pad "12" smd oval
			(at 2.6 -4.099999 180)
			(size 0.508 2.0066)
			(layers "F.Cu" "F.Mask" "F.Paste")
			(net "ETH10G_B1_RXN")
		)
		(pad "13" smd oval
			(at 1.799999 -4.099999 180)
			(size 0.508 2.0066)
			(layers "F.Cu" "F.Mask" "F.Paste")
			(net "ETH10G_B1_RXP")
		)
		(pad "14" smd oval
			(at 1.000001 -4.099999 180)
			(size 0.508 2.0066)
			(layers "F.Cu" "F.Mask" "F.Paste")
			(net "GND")
		)
		(pad "15" smd oval
			(at 0.2 -4.099999 180)
			(size 0.508 2.0066)
			(layers "F.Cu" "F.Mask" "F.Paste")
			(net "P3V3_10G_B1_VCCR")
		)
		(pad "16" smd oval
			(at -0.599999 -4.099999 180)
			(size 0.508 2.0066)
			(layers "F.Cu" "F.Mask" "F.Paste")
			(net "P3V3_10G_B1_VCCT")
		)
		(pad "17" smd oval
			(at -1.4 -4.099999 180)
			(size 0.508 2.0066)
			(layers "F.Cu" "F.Mask" "F.Paste")
			(net "GND")
		)
		(pad "18" smd oval
			(at -2.200001 -4.099999 180)
			(size 0.508 2.0066)
			(layers "F.Cu" "F.Mask" "F.Paste")
			(net "ETH10G_B1_TXP")
		)
		(pad "19" smd oval
			(at -2.999999 -4.099999 180)
			(size 0.508 2.0066)
			(layers "F.Cu" "F.Mask" "F.Paste")
			(net "ETH10G_B1_TXN")
		)
		(pad "20" smd oval
			(at -3.8 -4.099999 180)
			(size 0.508 2.0066)
			(layers "F.Cu" "F.Mask" "F.Paste")
			(net "GND")
		)
		(zone
			(layers "F.Cu" "B.Cu" "In1.Cu" "In2.Cu" "In3.Cu" "In4.Cu" "In5.Cu" "In6.Cu")
			(hatch none 0.5)
			(connect_pads
				(clearance 0)
			)
			(min_thickness 0.25)
			(keepout
				(tracks not_allowed)
				(vias allowed)
				(pads allowed)
				(copperpour not_allowed)
				(footprints allowed)
			)
			(placement
				(enabled no)
				(sheetname "")
			)
			(fill
				(thermal_gap 0.5)
				(thermal_bridge_width 0.5)
				(island_removal_mode 0)
			)
			(polygon
				(pts
					(arc
						(start -288.730002 32.059999)
						(mid -286.37 32.059999)
						(end -288.730002 32.059999)
					)
				)
			)
		)
		(zone
			(layers "F.Cu" "B.Cu" "In1.Cu" "In2.Cu" "In3.Cu" "In4.Cu" "In5.Cu" "In6.Cu")
			(hatch none 0.5)
			(connect_pads
				(clearance 0)
			)
			(min_thickness 0.25)
			(keepout
				(tracks not_allowed)
				(vias allowed)
				(pads allowed)
				(copperpour not_allowed)
				(footprints allowed)
			)
			(placement
				(enabled no)
				(sheetname "")
			)
			(fill
				(thermal_gap 0.5)
				(thermal_bridge_width 0.5)
				(island_removal_mode 0)
			)
			(polygon
				(pts
					(arc
						(start -279.130001 32.059999)
						(mid -276.769999 32.059999)
						(end -279.130001 32.059999)
					)
				)
			)
		)
	)
	(gr_poly
		(pts
			(xy -227.020717 47.460002) (xy -229.560717 47.460002) (xy -229.560717 46.952002) (xy -227.020717 46.952002)
		)
		(stroke
			(width 0)
			(type solid)
		)
		(fill yes)
		(layer "F.Cu")
		(net "Net_373")
	)
	(gr_poly
		(pts
			(xy -279.80608 45.974) (xy -280.563 45.974) (xy -280.563 45.212) (xy -281.198 44.577) (xy -281.8203 44.58462)
			(xy -281.8203 42.02176) (xy -281.50534 41.7068) (xy -279.80608 41.7068)
		)
		(stroke
			(width 0)
			(type solid)
		)
		(fill yes)
		(layer "F.Cu")
		(net "P3V3_10G_B1_VCCT")
	)
	(gr_poly
		(pts
			(xy -58.80608 45.974) (xy -59.563 45.974) (xy -59.563 45.212) (xy -60.198 44.577) (xy -60.8203 44.58462)
			(xy -60.8203 42.02176) (xy -60.50534 41.7068) (xy -58.80608 41.7068)
		)
		(stroke
			(width 0)
			(type solid)
		)
		(fill yes)
		(layer "F.Cu")
		(net "P3V3_10G_B2_VCCT")
	)
	(gr_poly
		(pts
			(xy -282.40704 42.0116) (xy -282.40704 44.57446) (xy -283.48908 44.57446) (xy -283.484 45.212) (xy -283.738 45.466)
			(xy -283.738 45.974) (xy -284.4238 45.974) (xy -284.421257 41.69664) (xy -282.722 41.69664)
		)
		(stroke
			(width 0)
			(type solid)
		)
		(fill yes)
		(layer "F.Cu")
		(net "P3V3_10G_B1_VCCR")
	)
	(gr_poly
		(pts
			(xy -61.40704 42.0116) (xy -61.40704 44.57446) (xy -62.48908 44.57446) (xy -62.484 45.212) (xy -62.738 45.466)
			(xy -62.738 45.974) (xy -63.4238 45.974) (xy -63.421257 41.69664) (xy -61.722 41.69664)
		)
		(stroke
			(width 0)
			(type solid)
		)
		(fill yes)
		(layer "F.Cu")
		(net "P3V3_10G_B2_VCCR")
	)
	(gr_poly
		(pts
			(arc
				(start -421.948724 40.929989)
				(mid -417.189719 38.53189)
				(end -413.8422 42.67835)
			)
			(arc
				(start -413.8422 42.67835)
				(mid -417.189719 46.824809)
				(end -421.948724 44.426711)
			)
		)
		(stroke
			(width 0)
			(type solid)
		)
		(fill yes)
		(layer "F.Cu")
		(net "GND")
	)
	(gr_poly
		(pts
			(arc
				(start -382.693885 40.520882)
				(mid -391.014802 39.357405)
				(end -382.693885 38.193924)
			)
		)
		(stroke
			(width 0)
			(type solid)
		)
		(fill yes)
		(layer "F.Cu")
		(net "GND")
	)
	(gr_poly
		(pts
			(arc
				(start 4.4704 45.8978)
				(mid -2.406567 42.427278)
				(end 4.826 39.7764)
			)
			(xy 4.826 45.2374)
		)
		(stroke
			(width 0)
			(type solid)
		)
		(fill yes)
		(layer "B.Cu")
		(net "GND")
	)
	(gr_poly
		(pts
			(arc
				(start -421.925808 40.914038)
				(mid -417.167005 38.513264)
				(end -413.8182 42.660001)
			)
			(arc
				(start -413.8182 42.660001)
				(mid -417.167006 46.806737)
				(end -421.925808 44.405964)
			)
		)
		(stroke
			(width 0)
			(type solid)
		)
		(fill yes)
		(layer "B.Cu")
		(net "GND")
	)
	(gr_poly
		(pts
			(arc
				(start -169.849117 38.193924)
				(mid -161.5282 39.357405)
				(end -169.849117 40.520882)
			)
		)
		(stroke
			(width 0)
			(type solid)
		)
		(fill yes)
		(layer "B.Cu")
		(net "GND")
	)
	(gr_poly
		(pts
			(arc
				(start -382.531201 39.357399)
				(mid -391.014801 39.357399)
				(end -382.531201 39.357399)
			)
		)
		(stroke
			(width 0)
			(type solid)
		)
		(fill yes)
		(layer "B.Cu")
		(net "GND")
	)
	(gr_poly
		(pts
			(arc
				(start -261.867899 20.000001)
				(mid -270.351499 20.000001)
				(end -261.867899 20.000001)
			)
		)
		(stroke
			(width 0)
			(type solid)
		)
		(fill yes)
		(layer "B.Cu")
		(net "GND")
	)
	(gr_poly
		(pts
			(arc
				(start -40.867902 20.000001)
				(mid -49.351502 20.000001)
				(end -40.867902 20.000001)
			)
		)
		(stroke
			(width 0)
			(type solid)
		)
		(fill yes)
		(layer "B.Cu")
		(net "GND")
	)
	(gr_poly
		(pts
			(xy -226.005136 47.4599) (xy -229.053136 47.4599) (xy -229.561136 47.4599) (xy -229.561136 46.9519)
			(xy -229.053136 46.9519) (xy -226.005136 46.9519)
		)
		(stroke
			(width 0)
			(type solid)
		)
		(fill yes)
		(layer "In1.Cu")
		(net "Net_374")
	)
	(gr_poly
		(pts
			(xy -224.988717 47.460002) (xy -228.544717 47.460002) (xy -229.560717 47.460002) (xy -229.560717 46.952002)
			(xy -228.544717 46.952002) (xy -224.988717 46.952002)
		)
		(stroke
			(width 0)
			(type solid)
		)
		(fill yes)
		(layer "In2.Cu")
		(net "Net_375")
	)
	(gr_poly
		(pts
			(xy -223.973136 47.4599) (xy -228.037136 47.4599) (xy -229.561136 47.4599) (xy -229.561136 46.9519)
			(xy -228.037136 46.9519) (xy -223.973136 46.9519)
		)
		(stroke
			(width 0)
			(type solid)
		)
		(fill yes)
		(layer "In3.Cu")
		(net "Net_376")
	)
	(gr_poly
		(pts
			(xy -222.957136 47.4599) (xy -227.529136 47.4599) (xy -229.561136 47.4599) (xy -229.561136 46.9519)
			(xy -227.529136 46.9519) (xy -222.957136 46.9519)
		)
		(stroke
			(width 0)
			(type solid)
		)
		(fill yes)
		(layer "In4.Cu")
		(net "Net_377")
	)
	(gr_poly
		(pts
			(xy -221.940717 47.460002) (xy -227.020717 47.460002) (xy -229.560717 47.460002) (xy -229.560717 46.952002)
			(xy -227.020717 46.952002) (xy -221.940717 46.952002)
		)
		(stroke
			(width 0)
			(type solid)
		)
		(fill yes)
		(layer "In5.Cu")
		(net "Net_372")
	)
	(gr_line
		(start -422.460001 -4.339999)
		(end -422.460001 45.96)
		(stroke
			(width 0.05)
			(type default)
		)
		(layer "Edge.Cuts")
	)
	(gr_line
		(start -421.46 -5.339999)
		(end -422.460001 -4.339999)
		(stroke
			(width 0.05)
			(type default)
		)
		(layer "Edge.Cuts")
	)
	(gr_arc
		(start -420.959999 47.459999)
		(mid -422.02066 47.020661)
		(end -422.460001 45.96)
		(stroke
			(width 0.05)
			(type default)
		)
		(layer "Edge.Cuts")
	)
	(gr_line
		(start -420.959999 47.459999)
		(end -325.325001 47.459999)
		(stroke
			(width 0.05)
			(type default)
		)
		(layer "Edge.Cuts")
	)
	(gr_arc
		(start -419.16 15.471841)
		(mid -417.460002 9.999999)
		(end -415.759999 15.471841)
		(stroke
			(width 0.05)
			(type default)
		)
		(layer "Edge.Cuts")
	)
	(gr_line
		(start -419.16 19)
		(end -419.16 15.471841)
		(stroke
			(width 0.05)
			(type default)
		)
		(layer "Edge.Cuts")
	)
	(gr_line
		(start -415.759999 15.471841)
		(end -415.759999 19)
		(stroke
			(width 0.05)
			(type default)
		)
		(layer "Edge.Cuts")
	)
	(gr_arc
		(start -415.759999 19)
		(mid -417.460001 20.700002)
		(end -419.16 19)
		(stroke
			(width 0.05)
			(type default)
		)
		(layer "Edge.Cuts")
	)
	(gr_line
		(start -413.009999 -5.339999)
		(end -421.46 -5.339999)
		(stroke
			(width 0.05)
			(type default)
		)
		(layer "Edge.Cuts")
	)
	(gr_line
		(start -412.009999 -4.339999)
		(end -413.009999 -5.339999)
		(stroke
			(width 0.05)
			(type default)
		)
		(layer "Edge.Cuts")
	)
	(gr_line
		(start -412.009999 4.810001)
		(end -412.009999 -4.339999)
		(stroke
			(width 0.05)
			(type default)
		)
		(layer "Edge.Cuts")
	)
	(gr_line
		(start -411.31 -4.339999)
		(end -411.31 4.810001)
		(stroke
			(width 0.05)
			(type default)
		)
		(layer "Edge.Cuts")
	)
	(gr_arc
		(start -411.31 4.810001)
		(mid -411.66 5.160001)
		(end -412.009999 4.810001)
		(stroke
			(width 0.05)
			(type default)
		)
		(layer "Edge.Cuts")
	)
	(gr_line
		(start -410.31 -5.339999)
		(end -411.31 -4.339999)
		(stroke
			(width 0.05)
			(type default)
		)
		(layer "Edge.Cuts")
	)
	(gr_line
		(start -371.379999 -5.339999)
		(end -410.31 -5.339999)
		(stroke
			(width 0.05)
			(type default)
		)
		(layer "Edge.Cuts")
	)
	(gr_line
		(start -370.380001 -4.339999)
		(end -371.379999 -5.339999)
		(stroke
			(width 0.05)
			(type default)
		)
		(layer "Edge.Cuts")
	)
	(gr_line
		(start -370.380001 3.66)
		(end -370.380001 -4.339999)
		(stroke
			(width 0.05)
			(type default)
		)
		(layer "Edge.Cuts")
	)
	(gr_arc
		(start -368.879999 5.16)
		(mid -369.94066 4.720661)
		(end -370.380001 3.66)
		(stroke
			(width 0.05)
			(type default)
		)
		(layer "Edge.Cuts")
	)
	(gr_line
		(start -367.880001 5.16)
		(end -368.879999 5.16)
		(stroke
			(width 0.05)
			(type default)
		)
		(layer "Edge.Cuts")
	)
	(gr_line
		(start -366.379999 -2.34)
		(end -366.379999 3.66)
		(stroke
			(width 0.05)
			(type default)
		)
		(layer "Edge.Cuts")
	)
	(gr_arc
		(start -366.379999 -2.34)
		(mid -365.647767 -4.107766)
		(end -363.880001 -4.84)
		(stroke
			(width 0.05)
			(type default)
		)
		(layer "Edge.Cuts")
	)
	(gr_arc
		(start -366.379999 3.66)
		(mid -366.81934 4.720661)
		(end -367.880001 5.16)
		(stroke
			(width 0.05)
			(type default)
		)
		(layer "Edge.Cuts")
	)
	(gr_arc
		(start -363.16 33.471841)
		(mid -361.460002 27.999999)
		(end -359.759999 33.471841)
		(stroke
			(width 0.05)
			(type default)
		)
		(layer "Edge.Cuts")
	)
	(gr_line
		(start -363.16 37)
		(end -363.16 33.471841)
		(stroke
			(width 0.05)
			(type default)
		)
		(layer "Edge.Cuts")
	)
	(gr_line
		(start -359.759999 33.471841)
		(end -359.759999 37)
		(stroke
			(width 0.05)
			(type default)
		)
		(layer "Edge.Cuts")
	)
	(gr_arc
		(start -359.759999 37)
		(mid -361.460001 38.700002)
		(end -363.16 37)
		(stroke
			(width 0.05)
			(type default)
		)
		(layer "Edge.Cuts")
	)
	(gr_arc
		(start -325.325001 47.459999)
		(mid -324.971446 47.606446)
		(end -324.824999 47.960001)
		(stroke
			(width 0.05)
			(type default)
		)
		(layer "Edge.Cuts")
	)
	(gr_line
		(start -324.824999 47.960001)
		(end -324.824999 49.5)
		(stroke
			(width 0.05)
			(type default)
		)
		(layer "Edge.Cuts")
	)
	(gr_arc
		(start -324.325 49.999999)
		(mid -324.678553 49.853553)
		(end -324.824999 49.5)
		(stroke
			(width 0.05)
			(type default)
		)
		(layer "Edge.Cuts")
	)
	(gr_line
		(start -324.325 49.999999)
		(end -307.174999 49.999999)
		(stroke
			(width 0.05)
			(type default)
		)
		(layer "Edge.Cuts")
	)
	(gr_arc
		(start -306.675 47.960001)
		(mid -306.528554 47.606448)
		(end -306.175001 47.459999)
		(stroke
			(width 0.05)
			(type default)
		)
		(layer "Edge.Cuts")
	)
	(gr_arc
		(start -306.675 49.5)
		(mid -306.821446 49.853553)
		(end -307.174999 49.999999)
		(stroke
			(width 0.05)
			(type default)
		)
		(layer "Edge.Cuts")
	)
	(gr_line
		(start -306.675 49.5)
		(end -306.675 47.960001)
		(stroke
			(width 0.05)
			(type default)
		)
		(layer "Edge.Cuts")
	)
	(gr_line
		(start -306.175001 47.459999)
		(end -104.325001 47.459999)
		(stroke
			(width 0.05)
			(type default)
		)
		(layer "Edge.Cuts")
	)
	(gr_arc
		(start -301.16 19.93184)
		(mid -299.460002 14.459998)
		(end -297.759999 19.93184)
		(stroke
			(width 0.05)
			(type default)
		)
		(layer "Edge.Cuts")
	)
	(gr_line
		(start -301.16 23.459999)
		(end -301.16 19.93184)
		(stroke
			(width 0.05)
			(type default)
		)
		(layer "Edge.Cuts")
	)
	(gr_line
		(start -297.759999 19.93184)
		(end -297.759999 23.459999)
		(stroke
			(width 0.05)
			(type default)
		)
		(layer "Edge.Cuts")
	)
	(gr_arc
		(start -297.759999 23.459999)
		(mid -299.460001 25.160001)
		(end -301.16 23.459999)
		(stroke
			(width 0.05)
			(type default)
		)
		(layer "Edge.Cuts")
	)
	(gr_arc
		(start -144.160001 25.93184)
		(mid -142.460003 20.46)
		(end -140.76 25.93184)
		(stroke
			(width 0.05)
			(type default)
		)
		(layer "Edge.Cuts")
	)
	(gr_line
		(start -144.160001 29.46)
		(end -144.160001 25.93184)
		(stroke
			(width 0.05)
			(type default)
		)
		(layer "Edge.Cuts")
	)
	(gr_line
		(start -140.76 25.93184)
		(end -140.76 29.46)
		(stroke
			(width 0.05)
			(type default)
		)
		(layer "Edge.Cuts")
	)
	(gr_arc
		(start -140.76 29.46)
		(mid -142.460002 31.160002)
		(end -144.160001 29.46)
		(stroke
			(width 0.05)
			(type default)
		)
		(layer "Edge.Cuts")
	)
	(gr_arc
		(start -104.325001 47.459999)
		(mid -103.971446 47.606446)
		(end -103.824999 47.960001)
		(stroke
			(width 0.05)
			(type default)
		)
		(layer "Edge.Cuts")
	)
	(gr_line
		(start -103.824999 47.960001)
		(end -103.824999 49.5)
		(stroke
			(width 0.05)
			(type default)
		)
		(layer "Edge.Cuts")
	)
	(gr_arc
		(start -103.325 49.999999)
		(mid -103.678553 49.853553)
		(end -103.824999 49.5)
		(stroke
			(width 0.05)
			(type default)
		)
		(layer "Edge.Cuts")
	)
	(gr_line
		(start -103.325 49.999999)
		(end -86.174999 49.999999)
		(stroke
			(width 0.05)
			(type default)
		)
		(layer "Edge.Cuts")
	)
	(gr_arc
		(start -85.675 47.960001)
		(mid -85.528554 47.606448)
		(end -85.175001 47.459999)
		(stroke
			(width 0.05)
			(type default)
		)
		(layer "Edge.Cuts")
	)
	(gr_arc
		(start -85.675 49.5)
		(mid -85.821446 49.853553)
		(end -86.174999 49.999999)
		(stroke
			(width 0.05)
			(type default)
		)
		(layer "Edge.Cuts")
	)
	(gr_line
		(start -85.675 49.5)
		(end -85.675 47.960001)
		(stroke
			(width 0.05)
			(type default)
		)
		(layer "Edge.Cuts")
	)
	(gr_line
		(start -85.175001 47.459999)
		(end 2.54 47.459999)
		(stroke
			(width 0.05)
			(type default)
		)
		(layer "Edge.Cuts")
	)
	(gr_arc
		(start -79.159999 19.93184)
		(mid -77.46 14.459998)
		(end -75.760001 19.93184)
		(stroke
			(width 0.05)
			(type default)
		)
		(layer "Edge.Cuts")
	)
	(gr_line
		(start -79.159999 23.459999)
		(end -79.159999 19.93184)
		(stroke
			(width 0.05)
			(type default)
		)
		(layer "Edge.Cuts")
	)
	(gr_line
		(start -75.760001 19.93184)
		(end -75.760001 23.459999)
		(stroke
			(width 0.05)
			(type default)
		)
		(layer "Edge.Cuts")
	)
	(gr_arc
		(start -75.760001 23.459999)
		(mid -77.46 25.159998)
		(end -79.159999 23.459999)
		(stroke
			(width 0.05)
			(type default)
		)
		(layer "Edge.Cuts")
	)
	(gr_arc
		(start -10.01 29.331841)
		(mid -8.310002 23.860001)
		(end -6.609999 29.331841)
		(stroke
			(width 0.05)
			(type default)
		)
		(layer "Edge.Cuts")
	)
	(gr_line
		(start -10.01 32.86)
		(end -10.01 29.331841)
		(stroke
			(width 0.05)
			(type default)
		)
		(layer "Edge.Cuts")
	)
	(gr_line
		(start -6.609999 29.331841)
		(end -6.609999 32.86)
		(stroke
			(width 0.05)
			(type default)
		)
		(layer "Edge.Cuts")
	)
	(gr_arc
		(start -6.609999 32.86)
		(mid -8.310001 34.560002)
		(end -10.01 32.86)
		(stroke
			(width 0.05)
			(type default)
		)
		(layer "Edge.Cuts")
	)
	(gr_line
		(start 1.38 -4.84)
		(end -363.880001 -4.84)
		(stroke
			(width 0.05)
			(type default)
		)
		(layer "Edge.Cuts")
	)
	(gr_arc
		(start 1.38 -4.84)
		(mid 3.501321 -3.96132)
		(end 4.379999 -1.839999)
		(stroke
			(width 0.05)
			(type default)
		)
		(layer "Edge.Cuts")
	)
	(gr_line
		(start 4.379999 34.5)
		(end 4.379999 -1.839999)
		(stroke
			(width 0.05)
			(type default)
		)
		(layer "Edge.Cuts")
	)
	(gr_arc
		(start 4.88 35.000001)
		(mid 4.526446 34.853554)
		(end 4.379999 34.5)
		(stroke
			(width 0.05)
			(type default)
		)
		(layer "Edge.Cuts")
	)
	(gr_line
		(start 5.04 35.000001)
		(end 4.88 35.000001)
		(stroke
			(width 0.05)
			(type default)
		)
		(layer "Edge.Cuts")
	)
	(gr_arc
		(start 5.04 35.000001)
		(mid 5.393553 35.146447)
		(end 5.539999 35.5)
		(stroke
			(width 0.05)
			(type default)
		)
		(layer "Edge.Cuts")
	)
	(gr_arc
		(start 5.539999 44.46)
		(mid 4.66132 46.58132)
		(end 2.54 47.459999)
		(stroke
			(width 0.05)
			(type default)
		)
		(layer "Edge.Cuts")
	)
	(gr_line
		(start 5.539999 44.46)
		(end 5.539999 35.5)
		(stroke
			(width 0.05)
			(type default)
		)
		(layer "Edge.Cuts")
	)
	(gr_text "X887571-005"
		(at -235.712 37.90315 0)
		(layer "F.Cu")
		(effects
			(font
				(size 2.413 1.7018)
				(thickness 0.254)
			)
			(justify left)
		)
	)
	(gr_text "X887571-005"
		(at -210.634461 37.816521 0)
		(layer "B.Cu")
		(effects
			(font
				(size 2.413 1.7018)
				(thickness 0.254)
			)
			(justify left mirror)
		)
	)
	(segment
		(start -80.391 28.829)
		(end -78.0542 31.1658)
		(width 0.1016)
		(layer "F.Cu")
		(net "SERIAL_B2_TX2")
	)
	(segment
		(start -78.713 35.66)
		(end -79.040002 35.66)
		(width 0.1016)
		(layer "F.Cu")
		(net "SERIAL_B2_TX2")
	)
	(segment
		(start -78.0542 35.0012)
		(end -78.713 35.66)
		(width 0.1016)
		(layer "F.Cu")
		(net "SERIAL_B2_TX2")
	)
	(segment
		(start -78.0542 31.1658)
		(end -78.0542 35.0012)
		(width 0.1016)
		(layer "F.Cu")
		(net "SERIAL_B2_TX2")
	)
	(via
		(at -418.97 6.9596)
		(size 0.5588)
		(drill 0.254)
		(layers "F.Cu" "B.Cu")
		(net "SERIAL_B2_TX2")
	)
	(via
		(at -80.391 28.829)
		(size 0.5588)
		(drill 0.254)
		(layers "F.Cu" "B.Cu")
		(net "SERIAL_B2_TX2")
	)
	(via
		(at -367.9952 17.1958)
		(size 0.5588)
		(drill 0.254)
		(layers "F.Cu" "B.Cu")
		(net "SERIAL_B2_TX2")
	)
	(segment
		(start -109.91281 27.34879)
		(end -114.5286 22.733)
		(width 0.1016)
		(layer "B.Cu")
		(net "SERIAL_B2_TX2")
	)
	(segment
		(start -114.5286 22.733)
		(end -114.5286 21.844)
		(width 0.1016)
		(layer "B.Cu")
		(net "SERIAL_B2_TX2")
	)
	(segment
		(start -156.21 -2.2098)
		(end -324.86346 -2.2098)
		(width 0.1016)
		(layer "B.Cu")
		(net "SERIAL_B2_TX2")
	)
	(segment
		(start -82.55 26.9748)
		(end -94.082616 26.9748)
		(width 0.1016)
		(layer "B.Cu")
		(net "SERIAL_B2_TX2")
	)
	(segment
		(start -114.8588 21.5138)
		(end -114.8588 20.8788)
		(width 0.1016)
		(layer "B.Cu")
		(net "SERIAL_B2_TX2")
	)
	(segment
		(start -80.391 28.829)
		(end -80.6958 28.829)
		(width 0.1016)
		(layer "B.Cu")
		(net "SERIAL_B2_TX2")
	)
	(segment
		(start -115.6208 8.4582)
		(end -114.7572 7.5946)
		(width 0.1016)
		(layer "B.Cu")
		(net "SERIAL_B2_TX2")
	)
	(segment
		(start -80.6958 28.829)
		(end -82.55 26.9748)
		(width 0.1016)
		(layer "B.Cu")
		(net "SERIAL_B2_TX2")
	)
	(segment
		(start -336.95894 10.84834)
		(end -342.46312 16.35252)
		(width 0.1016)
		(layer "B.Cu")
		(net "SERIAL_B2_TX2")
	)
	(segment
		(start -342.46312 16.35252)
		(end -366.59312 16.35252)
		(width 0.1016)
		(layer "B.Cu")
		(net "SERIAL_B2_TX2")
	)
	(segment
		(start -367.9698 17.1704)
		(end -367.9952 17.1958)
		(width 0.1016)
		(layer "B.Cu")
		(net "SERIAL_B2_TX2")
	)
	(segment
		(start -324.86346 -2.2098)
		(end -336.95894 9.88568)
		(width 0.1016)
		(layer "B.Cu")
		(net "SERIAL_B2_TX2")
	)
	(segment
		(start -367.411 17.1704)
		(end -367.9698 17.1704)
		(width 0.1016)
		(layer "B.Cu")
		(net "SERIAL_B2_TX2")
	)
	(segment
		(start -366.59312 16.35252)
		(end -367.411 17.1704)
		(width 0.1016)
		(layer "B.Cu")
		(net "SERIAL_B2_TX2")
	)
	(segment
		(start -114.7572 3.2004)
		(end -118.6434 -0.6858)
		(width 0.1016)
		(layer "B.Cu")
		(net "SERIAL_B2_TX2")
	)
	(segment
		(start -94.456606 27.34879)
		(end -109.91281 27.34879)
		(width 0.1016)
		(layer "B.Cu")
		(net "SERIAL_B2_TX2")
	)
	(segment
		(start -114.7572 7.5946)
		(end -114.7572 3.2004)
		(width 0.1016)
		(layer "B.Cu")
		(net "SERIAL_B2_TX2")
	)
	(segment
		(start -118.6434 -0.6858)
		(end -154.686 -0.6858)
		(width 0.1016)
		(layer "B.Cu")
		(net "SERIAL_B2_TX2")
	)
	(segment
		(start -94.082616 26.9748)
		(end -94.456606 27.34879)
		(width 0.1016)
		(layer "B.Cu")
		(net "SERIAL_B2_TX2")
	)
	(segment
		(start -154.686 -0.6858)
		(end -156.21 -2.2098)
		(width 0.1016)
		(layer "B.Cu")
		(net "SERIAL_B2_TX2")
	)
	(segment
		(start -114.5286 21.844)
		(end -114.8588 21.5138)
		(width 0.1016)
		(layer "B.Cu")
		(net "SERIAL_B2_TX2")
	)
	(segment
		(start -115.6208 20.1168)
		(end -115.6208 8.4582)
		(width 0.1016)
		(layer "B.Cu")
		(net "SERIAL_B2_TX2")
	)
	(segment
		(start -114.8588 20.8788)
		(end -115.6208 20.1168)
		(width 0.1016)
		(layer "B.Cu")
		(net "SERIAL_B2_TX2")
	)
	(segment
		(start -336.95894 9.88568)
		(end -336.95894 10.84834)
		(width 0.1016)
		(layer "B.Cu")
		(net "SERIAL_B2_TX2")
	)
	(segment
		(start -418.97 -1.840001)
		(end -418.97 6.9596)
		(width 0.1016)
		(layer "B.Cu")
		(net "SERIAL_B2_TX2")
	)
	(segment
		(start -415.417 8.1534)
		(end -409.31084 14.25956)
		(width 0.12954)
		(layer "In2.Cu")
		(net "SERIAL_B2_TX2")
	)
	(segment
		(start -417.7762 8.1534)
		(end -415.417 8.1534)
		(width 0.12954)
		(layer "In2.Cu")
		(net "SERIAL_B2_TX2")
	)
	(segment
		(start -369.189 17.1958)
		(end -367.9952 17.1958)
		(width 0.12954)
		(layer "In2.Cu")
		(net "SERIAL_B2_TX2")
	)
	(segment
		(start -418.97 6.9596)
		(end -417.7762 8.1534)
		(width 0.12954)
		(layer "In2.Cu")
		(net "SERIAL_B2_TX2")
	)
	(segment
		(start -409.31084 14.25956)
		(end -372.12524 14.25956)
		(width 0.12954)
		(layer "In2.Cu")
		(net "SERIAL_B2_TX2")
	)
	(segment
		(start -372.12524 14.25956)
		(end -369.189 17.1958)
		(width 0.12954)
		(layer "In2.Cu")
		(net "SERIAL_B2_TX2")
	)
	(segment
		(start -80.772 28.829)
		(end -82.7532 26.8478)
		(width 0.12954)
		(layer "In5.Cu")
		(net "SERIAL_B2_TX2")
	)
	(segment
		(start -148.92782 44.36618)
		(end -157.89148 44.36618)
		(width 0.12954)
		(layer "In5.Cu")
		(net "SERIAL_B2_TX2")
	)
	(segment
		(start -104.03332 38.30574)
		(end -104.03332 42.291)
		(width 0.12954)
		(layer "In5.Cu")
		(net "SERIAL_B2_TX2")
	)
	(segment
		(start -159.9057 46.3804)
		(end -183.9849 46.3804)
		(width 0.12954)
		(layer "In5.Cu")
		(net "SERIAL_B2_TX2")
	)
	(segment
		(start -102.31882 36.59124)
		(end -104.03332 38.30574)
		(width 0.12954)
		(layer "In5.Cu")
		(net "SERIAL_B2_TX2")
	)
	(segment
		(start -80.391 28.829)
		(end -80.772 28.829)
		(width 0.12954)
		(layer "In5.Cu")
		(net "SERIAL_B2_TX2")
	)
	(segment
		(start -103.53548 44.26712)
		(end -105.29316 46.0248)
		(width 0.12954)
		(layer "In5.Cu")
		(net "SERIAL_B2_TX2")
	)
	(segment
		(start -102.31882 36.18992)
		(end -102.31882 36.59124)
		(width 0.12954)
		(layer "In5.Cu")
		(net "SERIAL_B2_TX2")
	)
	(segment
		(start -184.4548 36.5652)
		(end -185.46 35.56)
		(width 0.12954)
		(layer "In5.Cu")
		(net "SERIAL_B2_TX2")
	)
	(segment
		(start -94.82328 33.62706)
		(end -99.75596 33.62706)
		(width 0.12954)
		(layer "In5.Cu")
		(net "SERIAL_B2_TX2")
	)
	(segment
		(start -147.2692 46.0248)
		(end -148.92782 44.36618)
		(width 0.12954)
		(layer "In5.Cu")
		(net "SERIAL_B2_TX2")
	)
	(segment
		(start -88.04402 26.8478)
		(end -94.82328 33.62706)
		(width 0.12954)
		(layer "In5.Cu")
		(net "SERIAL_B2_TX2")
	)
	(segment
		(start -104.03332 42.291)
		(end -103.53548 42.78884)
		(width 0.12954)
		(layer "In5.Cu")
		(net "SERIAL_B2_TX2")
	)
	(segment
		(start -105.29316 46.0248)
		(end -147.2692 46.0248)
		(width 0.12954)
		(layer "In5.Cu")
		(net "SERIAL_B2_TX2")
	)
	(segment
		(start -103.53548 42.78884)
		(end -103.53548 44.26712)
		(width 0.12954)
		(layer "In5.Cu")
		(net "SERIAL_B2_TX2")
	)
	(segment
		(start -157.89148 44.36618)
		(end -159.9057 46.3804)
		(width 0.12954)
		(layer "In5.Cu")
		(net "SERIAL_B2_TX2")
	)
	(segment
		(start -82.7532 26.8478)
		(end -88.04402 26.8478)
		(width 0.12954)
		(layer "In5.Cu")
		(net "SERIAL_B2_TX2")
	)
	(segment
		(start -99.75596 33.62706)
		(end -102.31882 36.18992)
		(width 0.12954)
		(layer "In5.Cu")
		(net "SERIAL_B2_TX2")
	)
	(segment
		(start -184.4548 45.9105)
		(end -184.4548 36.5652)
		(width 0.12954)
		(layer "In5.Cu")
		(net "SERIAL_B2_TX2")
	)
	(segment
		(start -183.9849 46.3804)
		(end -184.4548 45.9105)
		(width 0.12954)
		(layer "In5.Cu")
		(net "SERIAL_B2_TX2")
	)
	(segment
		(start -38.7096 31.7627)
		(end -38.5953 31.6484)
		(width 0.1016)
		(layer "F.Cu")
		(net "SERIAL_B2_TX1")
	)
	(segment
		(start -31.84176 44.19824)
		(end -30.68 45.360001)
		(width 0.1016)
		(layer "F.Cu")
		(net "SERIAL_B2_TX1")
	)
	(segment
		(start -32.343291 32.0472)
		(end -31.867201 32.52329)
		(width 0.1016)
		(layer "F.Cu")
		(net "SERIAL_B2_TX1")
	)
	(segment
		(start -31.84176 32.550354)
		(end -31.84176 44.19824)
		(width 0.1016)
		(layer "F.Cu")
		(net "SERIAL_B2_TX1")
	)
	(segment
		(start -38.5953 31.6484)
		(end -32.743714 31.6484)
		(width 0.1016)
		(layer "F.Cu")
		(net "SERIAL_B2_TX1")
	)
	(segment
		(start -31.867201 32.524913)
		(end -31.84176 32.550354)
		(width 0.1016)
		(layer "F.Cu")
		(net "SERIAL_B2_TX1")
	)
	(segment
		(start -31.867201 32.52329)
		(end -31.867201 32.524913)
		(width 0.1016)
		(layer "F.Cu")
		(net "SERIAL_B2_TX1")
	)
	(segment
		(start -32.743714 31.6484)
		(end -32.344914 32.0472)
		(width 0.1016)
		(layer "F.Cu")
		(net "SERIAL_B2_TX1")
	)
	(segment
		(start -32.344914 32.0472)
		(end -32.343291 32.0472)
		(width 0.1016)
		(layer "F.Cu")
		(net "SERIAL_B2_TX1")
	)
	(via
		(at -413.89 7.0358)
		(size 0.5588)
		(drill 0.254)
		(layers "F.Cu" "B.Cu")
		(net "SERIAL_B2_TX1")
	)
	(via
		(at -75.2856 28.829)
		(size 0.5588)
		(drill 0.254)
		(layers "F.Cu" "B.Cu")
		(net "SERIAL_B2_TX1")
	)
	(via
		(at -38.7096 31.7627)
		(size 0.5588)
		(drill 0.254)
		(layers "F.Cu" "B.Cu")
		(net "SERIAL_B2_TX1")
	)
	(via
		(at -367.9698 15.2146)
		(size 0.5588)
		(drill 0.254)
		(layers "F.Cu" "B.Cu")
		(net "SERIAL_B2_TX1")
	)
	(segment
		(start -68.3514 22.2758)
		(end -69.85 22.2758)
		(width 0.1016)
		(layer "B.Cu")
		(net "SERIAL_B2_TX1")
	)
	(segment
		(start -75.2856 28.829)
		(end -75.3618 28.829)
		(width 0.1016)
		(layer "B.Cu")
		(net "SERIAL_B2_TX1")
	)
	(segment
		(start -66.1416 24.4856)
		(end -68.3514 22.2758)
		(width 0.1016)
		(layer "B.Cu")
		(net "SERIAL_B2_TX1")
	)
	(segment
		(start -366.9792 14.5796)
		(end -367.665 15.2654)
		(width 0.1016)
		(layer "B.Cu")
		(net "SERIAL_B2_TX1")
	)
	(segment
		(start -109.22 22.606)
		(end -110.0582 22.606)
		(width 0.1016)
		(layer "B.Cu")
		(net "SERIAL_B2_TX1")
	)
	(segment
		(start -58.039 24.4856)
		(end -66.1416 24.4856)
		(width 0.1016)
		(layer "B.Cu")
		(net "SERIAL_B2_TX1")
	)
	(segment
		(start -110.5408 22.1234)
		(end -110.5408 2.7686)
		(width 0.1016)
		(layer "B.Cu")
		(net "SERIAL_B2_TX1")
	)
	(segment
		(start -38.7096 31.7627)
		(end -40.5257 33.5788)
		(width 0.1016)
		(layer "B.Cu")
		(net "SERIAL_B2_TX1")
	)
	(segment
		(start -75.2856 28.8544)
		(end -75.2856 28.829)
		(width 0.1016)
		(layer "B.Cu")
		(net "SERIAL_B2_TX1")
	)
	(segment
		(start -40.5257 33.5788)
		(end -41.7322 33.5788)
		(width 0.1016)
		(layer "B.Cu")
		(net "SERIAL_B2_TX1")
	)
	(segment
		(start -154.178 -2.54)
		(end -154.8638 -3.2258)
		(width 0.1016)
		(layer "B.Cu")
		(net "SERIAL_B2_TX1")
	)
	(segment
		(start -110.0582 22.606)
		(end -110.5408 22.1234)
		(width 0.1016)
		(layer "B.Cu")
		(net "SERIAL_B2_TX1")
	)
	(segment
		(start -69.85 22.2758)
		(end -70.8406 23.2664)
		(width 0.1016)
		(layer "B.Cu")
		(net "SERIAL_B2_TX1")
	)
	(segment
		(start -76.10856 28.08224)
		(end -79.53756 28.08224)
		(width 0.1016)
		(layer "B.Cu")
		(net "SERIAL_B2_TX1")
	)
	(segment
		(start -103.7082 22.479)
		(end -106.299 22.479)
		(width 0.1016)
		(layer "B.Cu")
		(net "SERIAL_B2_TX1")
	)
	(segment
		(start -106.68 22.098)
		(end -108.712 22.098)
		(width 0.1016)
		(layer "B.Cu")
		(net "SERIAL_B2_TX1")
	)
	(segment
		(start -44.3738 26.8732)
		(end -55.6514 26.8732)
		(width 0.1016)
		(layer "B.Cu")
		(net "SERIAL_B2_TX1")
	)
	(segment
		(start -81.7626 25.8572)
		(end -100.33 25.8572)
		(width 0.1016)
		(layer "B.Cu")
		(net "SERIAL_B2_TX1")
	)
	(segment
		(start -41.7322 33.5788)
		(end -42.2656 33.0454)
		(width 0.1016)
		(layer "B.Cu")
		(net "SERIAL_B2_TX1")
	)
	(segment
		(start -106.299 22.479)
		(end -106.68 22.098)
		(width 0.1016)
		(layer "B.Cu")
		(net "SERIAL_B2_TX1")
	)
	(segment
		(start -71.374 30.226)
		(end -73.914 30.226)
		(width 0.1016)
		(layer "B.Cu")
		(net "SERIAL_B2_TX1")
	)
	(segment
		(start -367.919 15.2654)
		(end -367.9698 15.2146)
		(width 0.1016)
		(layer "B.Cu")
		(net "SERIAL_B2_TX1")
	)
	(segment
		(start -100.33 25.8572)
		(end -103.7082 22.479)
		(width 0.1016)
		(layer "B.Cu")
		(net "SERIAL_B2_TX1")
	)
	(segment
		(start -70.8406 29.6926)
		(end -71.374 30.226)
		(width 0.1016)
		(layer "B.Cu")
		(net "SERIAL_B2_TX1")
	)
	(segment
		(start -42.2656 33.0454)
		(end -42.2656 28.9814)
		(width 0.1016)
		(layer "B.Cu")
		(net "SERIAL_B2_TX1")
	)
	(segment
		(start -110.5408 2.7686)
		(end -115.8494 -2.54)
		(width 0.1016)
		(layer "B.Cu")
		(net "SERIAL_B2_TX1")
	)
	(segment
		(start -79.53756 28.08224)
		(end -81.7626 25.8572)
		(width 0.1016)
		(layer "B.Cu")
		(net "SERIAL_B2_TX1")
	)
	(segment
		(start -108.712 22.098)
		(end -109.22 22.606)
		(width 0.1016)
		(layer "B.Cu")
		(net "SERIAL_B2_TX1")
	)
	(segment
		(start -367.665 15.2654)
		(end -367.919 15.2654)
		(width 0.1016)
		(layer "B.Cu")
		(net "SERIAL_B2_TX1")
	)
	(segment
		(start -75.3618 28.829)
		(end -76.10856 28.08224)
		(width 0.1016)
		(layer "B.Cu")
		(net "SERIAL_B2_TX1")
	)
	(segment
		(start -70.8406 23.2664)
		(end -70.8406 29.6926)
		(width 0.1016)
		(layer "B.Cu")
		(net "SERIAL_B2_TX1")
	)
	(segment
		(start -325.501 -3.2258)
		(end -343.3064 14.5796)
		(width 0.1016)
		(layer "B.Cu")
		(net "SERIAL_B2_TX1")
	)
	(segment
		(start -42.2656 28.9814)
		(end -44.3738 26.8732)
		(width 0.1016)
		(layer "B.Cu")
		(net "SERIAL_B2_TX1")
	)
	(segment
		(start -343.3064 14.5796)
		(end -366.9792 14.5796)
		(width 0.1016)
		(layer "B.Cu")
		(net "SERIAL_B2_TX1")
	)
	(segment
		(start -154.8638 -3.2258)
		(end -325.501 -3.2258)
		(width 0.1016)
		(layer "B.Cu")
		(net "SERIAL_B2_TX1")
	)
	(segment
		(start -73.914 30.226)
		(end -75.2856 28.8544)
		(width 0.1016)
		(layer "B.Cu")
		(net "SERIAL_B2_TX1")
	)
	(segment
		(start -55.6514 26.8732)
		(end -58.039 24.4856)
		(width 0.1016)
		(layer "B.Cu")
		(net "SERIAL_B2_TX1")
	)
	(segment
		(start -413.89 7.0358)
		(end -413.89 -1.840001)
		(width 0.1016)
		(layer "B.Cu")
		(net "SERIAL_B2_TX1")
	)
	(segment
		(start -115.8494 -2.54)
		(end -154.178 -2.54)
		(width 0.1016)
		(layer "B.Cu")
		(net "SERIAL_B2_TX1")
	)
	(segment
		(start -77.040001 35.56)
		(end -77.7748 34.825201)
		(width 0.12954)
		(layer "In2.Cu")
		(net "SERIAL_B2_TX1")
	)
	(segment
		(start -412.8262 8.0996)
		(end -413.89 7.0358)
		(width 0.12954)
		(layer "In2.Cu")
		(net "SERIAL_B2_TX1")
	)
	(segment
		(start -77.7748 31.8516)
		(end -75.2856 29.3624)
		(width 0.12954)
		(layer "In2.Cu")
		(net "SERIAL_B2_TX1")
	)
	(segment
		(start -368.5032 15.2146)
		(end -370.586 13.1318)
		(width 0.12954)
		(layer "In2.Cu")
		(net "SERIAL_B2_TX1")
	)
	(segment
		(start -77.7748 34.825201)
		(end -77.7748 31.8516)
		(width 0.12954)
		(layer "In2.Cu")
		(net "SERIAL_B2_TX1")
	)
	(segment
		(start -75.2856 29.3624)
		(end -75.2856 28.829)
		(width 0.12954)
		(layer "In2.Cu")
		(net "SERIAL_B2_TX1")
	)
	(segment
		(start -370.586 13.1318)
		(end -408.7876 13.1318)
		(width 0.12954)
		(layer "In2.Cu")
		(net "SERIAL_B2_TX1")
	)
	(segment
		(start -408.7876 13.1318)
		(end -412.8262 9.0932)
		(width 0.12954)
		(layer "In2.Cu")
		(net "SERIAL_B2_TX1")
	)
	(segment
		(start -412.8262 9.0932)
		(end -412.8262 8.0996)
		(width 0.12954)
		(layer "In2.Cu")
		(net "SERIAL_B2_TX1")
	)
	(segment
		(start -367.9698 15.2146)
		(end -368.5032 15.2146)
		(width 0.12954)
		(layer "In2.Cu")
		(net "SERIAL_B2_TX1")
	)
	(segment
		(start -81.6864 28.829)
		(end -81.6864 32.385)
		(width 0.1016)
		(layer "F.Cu")
		(net "SERIAL_B2_RX2")
	)
	(segment
		(start -80.01 34.0614)
		(end -80.01 36.090001)
		(width 0.1016)
		(layer "F.Cu")
		(net "SERIAL_B2_RX2")
	)
	(segment
		(start -81.6864 32.385)
		(end -80.01 34.0614)
		(width 0.1016)
		(layer "F.Cu")
		(net "SERIAL_B2_RX2")
	)
	(segment
		(start -80.01 36.090001)
		(end -79.040002 37.06)
		(width 0.1016)
		(layer "F.Cu")
		(net "SERIAL_B2_RX2")
	)
	(via
		(at -81.6864 28.829)
		(size 0.5588)
		(drill 0.254)
		(layers "F.Cu" "B.Cu")
		(net "SERIAL_B2_RX2")
	)
	(via
		(at -368.7572 17.6784)
		(size 0.5588)
		(drill 0.254)
		(layers "F.Cu" "B.Cu")
		(net "SERIAL_B2_RX2")
	)
	(via
		(at -150.1648 45.6438)
		(size 0.5588)
		(drill 0.254)
		(layers "F.Cu" "B.Cu")
		(net "SERIAL_B2_RX2")
	)
	(via
		(at -420.24 6.9342)
		(size 0.5588)
		(drill 0.254)
		(layers "F.Cu" "B.Cu")
		(net "SERIAL_B2_RX2")
	)
	(segment
		(start -184.6072 34.9758)
		(end -185.423 34.16)
		(width 0.1016)
		(layer "B.Cu")
		(net "SERIAL_B2_RX2")
	)
	(segment
		(start -158.0134 44.196)
		(end -160.1343 46.3169)
		(width 0.1016)
		(layer "B.Cu")
		(net "SERIAL_B2_RX2")
	)
	(segment
		(start -118.783011 0.901789)
		(end -153.631811 0.901789)
		(width 0.1016)
		(layer "B.Cu")
		(net "SERIAL_B2_RX2")
	)
	(segment
		(start -116.2812 3.4036)
		(end -118.783011 0.901789)
		(width 0.1016)
		(layer "B.Cu")
		(net "SERIAL_B2_RX2")
	)
	(segment
		(start -94.03475 27.664804)
		(end -110.790596 27.664804)
		(width 0.1016)
		(layer "B.Cu")
		(net "SERIAL_B2_RX2")
	)
	(segment
		(start -336.677 11.0744)
		(end -342.23452 16.63192)
		(width 0.1016)
		(layer "B.Cu")
		(net "SERIAL_B2_RX2")
	)
	(segment
		(start -116.6622 21.7932)
		(end -116.6622 20.4724)
		(width 0.1016)
		(layer "B.Cu")
		(net "SERIAL_B2_RX2")
	)
	(segment
		(start -324.70598 -1.9558)
		(end -336.677 10.01522)
		(width 0.1016)
		(layer "B.Cu")
		(net "SERIAL_B2_RX2")
	)
	(segment
		(start -160.1343 46.3169)
		(end -184.1881 46.3169)
		(width 0.1016)
		(layer "B.Cu")
		(net "SERIAL_B2_RX2")
	)
	(segment
		(start -93.725746 27.3558)
		(end -94.03475 27.664804)
		(width 0.1016)
		(layer "B.Cu")
		(net "SERIAL_B2_RX2")
	)
	(segment
		(start -82.169 28.829)
		(end -83.6422 27.3558)
		(width 0.1016)
		(layer "B.Cu")
		(net "SERIAL_B2_RX2")
	)
	(segment
		(start -116.2812 20.0914)
		(end -116.2812 3.4036)
		(width 0.1016)
		(layer "B.Cu")
		(net "SERIAL_B2_RX2")
	)
	(segment
		(start -81.6864 28.829)
		(end -82.169 28.829)
		(width 0.1016)
		(layer "B.Cu")
		(net "SERIAL_B2_RX2")
	)
	(segment
		(start -110.790596 27.664804)
		(end -116.6622 21.7932)
		(width 0.1016)
		(layer "B.Cu")
		(net "SERIAL_B2_RX2")
	)
	(segment
		(start -154.7368 44.196)
		(end -158.0134 44.196)
		(width 0.1016)
		(layer "B.Cu")
		(net "SERIAL_B2_RX2")
	)
	(segment
		(start -153.289 45.6438)
		(end -154.7368 44.196)
		(width 0.1016)
		(layer "B.Cu")
		(net "SERIAL_B2_RX2")
	)
	(segment
		(start -184.1881 46.3169)
		(end -184.6072 45.8978)
		(width 0.1016)
		(layer "B.Cu")
		(net "SERIAL_B2_RX2")
	)
	(segment
		(start -185.423 34.16)
		(end -185.46 34.16)
		(width 0.1016)
		(layer "B.Cu")
		(net "SERIAL_B2_RX2")
	)
	(segment
		(start -342.23452 16.63192)
		(end -366.36452 16.63192)
		(width 0.1016)
		(layer "B.Cu")
		(net "SERIAL_B2_RX2")
	)
	(segment
		(start -184.6072 45.8978)
		(end -184.6072 34.9758)
		(width 0.1016)
		(layer "B.Cu")
		(net "SERIAL_B2_RX2")
	)
	(segment
		(start -366.36452 16.63192)
		(end -367.411 17.6784)
		(width 0.1016)
		(layer "B.Cu")
		(net "SERIAL_B2_RX2")
	)
	(segment
		(start -116.6622 20.4724)
		(end -116.2812 20.0914)
		(width 0.1016)
		(layer "B.Cu")
		(net "SERIAL_B2_RX2")
	)
	(segment
		(start -153.631811 0.901789)
		(end -156.4894 -1.9558)
		(width 0.1016)
		(layer "B.Cu")
		(net "SERIAL_B2_RX2")
	)
	(segment
		(start -150.1648 45.6438)
		(end -153.289 45.6438)
		(width 0.1016)
		(layer "B.Cu")
		(net "SERIAL_B2_RX2")
	)
	(segment
		(start -336.677 10.01522)
		(end -336.677 11.0744)
		(width 0.1016)
		(layer "B.Cu")
		(net "SERIAL_B2_RX2")
	)
	(segment
		(start -367.411 17.6784)
		(end -368.7572 17.6784)
		(width 0.1016)
		(layer "B.Cu")
		(net "SERIAL_B2_RX2")
	)
	(segment
		(start -156.4894 -1.9558)
		(end -324.70598 -1.9558)
		(width 0.1016)
		(layer "B.Cu")
		(net "SERIAL_B2_RX2")
	)
	(segment
		(start -83.6422 27.3558)
		(end -93.725746 27.3558)
		(width 0.1016)
		(layer "B.Cu")
		(net "SERIAL_B2_RX2")
	)
	(segment
		(start -420.24 6.9342)
		(end -420.24 -1.840001)
		(width 0.1016)
		(layer "B.Cu")
		(net "SERIAL_B2_RX2")
	)
	(segment
		(start -418.70838 8.46582)
		(end -415.61258 8.46582)
		(width 0.12954)
		(layer "In2.Cu")
		(net "SERIAL_B2_RX2")
	)
	(segment
		(start -372.3513 14.5415)
		(end -369.2144 17.6784)
		(width 0.12954)
		(layer "In2.Cu")
		(net "SERIAL_B2_RX2")
	)
	(segment
		(start -409.5369 14.5415)
		(end -372.3513 14.5415)
		(width 0.12954)
		(layer "In2.Cu")
		(net "SERIAL_B2_RX2")
	)
	(segment
		(start -415.61258 8.46582)
		(end -409.5369 14.5415)
		(width 0.12954)
		(layer "In2.Cu")
		(net "SERIAL_B2_RX2")
	)
	(segment
		(start -369.2144 17.6784)
		(end -368.7572 17.6784)
		(width 0.12954)
		(layer "In2.Cu")
		(net "SERIAL_B2_RX2")
	)
	(segment
		(start -420.24 6.9342)
		(end -418.70838 8.46582)
		(width 0.12954)
		(layer "In2.Cu")
		(net "SERIAL_B2_RX2")
	)
	(segment
		(start -103.16464 42.25798)
		(end -103.16464 44.38142)
		(width 0.12954)
		(layer "In5.Cu")
		(net "SERIAL_B2_RX2")
	)
	(segment
		(start -99.32162 34.17316)
		(end -103.5558 38.40734)
		(width 0.12954)
		(layer "In5.Cu")
		(net "SERIAL_B2_RX2")
	)
	(segment
		(start -94.7166 34.17316)
		(end -99.32162 34.17316)
		(width 0.12954)
		(layer "In5.Cu")
		(net "SERIAL_B2_RX2")
	)
	(segment
		(start -103.5558 38.40734)
		(end -103.5558 41.86682)
		(width 0.12954)
		(layer "In5.Cu")
		(net "SERIAL_B2_RX2")
	)
	(segment
		(start -103.5558 41.86682)
		(end -103.16464 42.25798)
		(width 0.12954)
		(layer "In5.Cu")
		(net "SERIAL_B2_RX2")
	)
	(segment
		(start -148.6154 45.6438)
		(end -150.1648 45.6438)
		(width 0.12954)
		(layer "In5.Cu")
		(net "SERIAL_B2_RX2")
	)
	(segment
		(start -84.3534 27.3304)
		(end -87.87384 27.3304)
		(width 0.12954)
		(layer "In5.Cu")
		(net "SERIAL_B2_RX2")
	)
	(segment
		(start -147.701 46.5582)
		(end -148.6154 45.6438)
		(width 0.12954)
		(layer "In5.Cu")
		(net "SERIAL_B2_RX2")
	)
	(segment
		(start -87.87384 27.3304)
		(end -94.7166 34.17316)
		(width 0.12954)
		(layer "In5.Cu")
		(net "SERIAL_B2_RX2")
	)
	(segment
		(start -82.8548 28.829)
		(end -84.3534 27.3304)
		(width 0.12954)
		(layer "In5.Cu")
		(net "SERIAL_B2_RX2")
	)
	(segment
		(start -103.16464 44.38142)
		(end -105.34142 46.5582)
		(width 0.12954)
		(layer "In5.Cu")
		(net "SERIAL_B2_RX2")
	)
	(segment
		(start -105.34142 46.5582)
		(end -147.701 46.5582)
		(width 0.12954)
		(layer "In5.Cu")
		(net "SERIAL_B2_RX2")
	)
	(segment
		(start -81.6864 28.829)
		(end -82.8548 28.829)
		(width 0.12954)
		(layer "In5.Cu")
		(net "SERIAL_B2_RX2")
	)
	(segment
		(start -37.7825 31.3055)
		(end -32.610618 31.3055)
		(width 0.1016)
		(layer "F.Cu")
		(net "SERIAL_B2_RX1")
	)
	(segment
		(start -38.3286 30.7594)
		(end -37.7825 31.3055)
		(width 0.1016)
		(layer "F.Cu")
		(net "SERIAL_B2_RX1")
	)
	(segment
		(start -32.610618 31.3055)
		(end -31.528832 32.387286)
		(width 0.1016)
		(layer "F.Cu")
		(net "SERIAL_B2_RX1")
	)
	(segment
		(start -31.528832 32.387286)
		(end -31.528832 43.111169)
		(width 0.1016)
		(layer "F.Cu")
		(net "SERIAL_B2_RX1")
	)
	(segment
		(start -31.528832 43.111169)
		(end -30.68 43.960001)
		(width 0.1016)
		(layer "F.Cu")
		(net "SERIAL_B2_RX1")
	)
	(via
		(at -368.681 15.6972)
		(size 0.5588)
		(drill 0.254)
		(layers "F.Cu" "B.Cu")
		(net "SERIAL_B2_RX1")
	)
	(via
		(at -415.16 7.0104)
		(size 0.5588)
		(drill 0.254)
		(layers "F.Cu" "B.Cu")
		(net "SERIAL_B2_RX1")
	)
	(via
		(at -38.3286 30.7594)
		(size 0.5588)
		(drill 0.254)
		(layers "F.Cu" "B.Cu")
		(net "SERIAL_B2_RX1")
	)
	(segment
		(start -42.9006 33.4518)
		(end -42.9006 29.3878)
		(width 0.1016)
		(layer "B.Cu")
		(net "SERIAL_B2_RX1")
	)
	(segment
		(start -100.7618 26.162)
		(end -104.1068 22.817)
		(width 0.1016)
		(layer "B.Cu")
		(net "SERIAL_B2_RX1")
	)
	(segment
		(start -108.712 22.86)
		(end -110.3122 22.86)
		(width 0.1016)
		(layer "B.Cu")
		(net "SERIAL_B2_RX1")
	)
	(segment
		(start -368.6302 15.748)
		(end -368.681 15.6972)
		(width 0.1016)
		(layer "B.Cu")
		(net "SERIAL_B2_RX1")
	)
	(segment
		(start -42.9006 29.3878)
		(end -44.9326 27.3558)
		(width 0.1016)
		(layer "B.Cu")
		(net "SERIAL_B2_RX1")
	)
	(segment
		(start -58.4454 25.019)
		(end -66.1924 25.019)
		(width 0.1016)
		(layer "B.Cu")
		(net "SERIAL_B2_RX1")
	)
	(segment
		(start -76.1492 30.099)
		(end -76.1492 36.7568)
		(width 0.1016)
		(layer "B.Cu")
		(net "SERIAL_B2_RX1")
	)
	(segment
		(start -367.4872 15.748)
		(end -368.6302 15.748)
		(width 0.1016)
		(layer "B.Cu")
		(net "SERIAL_B2_RX1")
	)
	(segment
		(start -71.2216 30.7086)
		(end -75.5396 30.7086)
		(width 0.1016)
		(layer "B.Cu")
		(net "SERIAL_B2_RX1")
	)
	(segment
		(start -110.9472 3.048)
		(end -116.2304 -2.2352)
		(width 0.1016)
		(layer "B.Cu")
		(net "SERIAL_B2_RX1")
	)
	(segment
		(start -38.3286 31.1912)
		(end -37.973 31.5468)
		(width 0.1016)
		(layer "B.Cu")
		(net "SERIAL_B2_RX1")
	)
	(segment
		(start -106.68 22.479)
		(end -108.331 22.479)
		(width 0.1016)
		(layer "B.Cu")
		(net "SERIAL_B2_RX1")
	)
	(segment
		(start -76.1492 29.400462)
		(end -77.188022 28.36164)
		(width 0.1016)
		(layer "B.Cu")
		(net "SERIAL_B2_RX1")
	)
	(segment
		(start -155.1178 -2.9718)
		(end -325.32574 -2.9718)
		(width 0.1016)
		(layer "B.Cu")
		(net "SERIAL_B2_RX1")
	)
	(segment
		(start -75.5396 30.7086)
		(end -76.1492 30.099)
		(width 0.1016)
		(layer "B.Cu")
		(net "SERIAL_B2_RX1")
	)
	(segment
		(start -325.32574 -2.9718)
		(end -343.13114 14.8336)
		(width 0.1016)
		(layer "B.Cu")
		(net "SERIAL_B2_RX1")
	)
	(segment
		(start -104.1068 22.817)
		(end -106.342 22.817)
		(width 0.1016)
		(layer "B.Cu")
		(net "SERIAL_B2_RX1")
	)
	(segment
		(start -56.1086 27.3558)
		(end -58.4454 25.019)
		(width 0.1016)
		(layer "B.Cu")
		(net "SERIAL_B2_RX1")
	)
	(segment
		(start -38.3286 30.7594)
		(end -38.3286 31.1912)
		(width 0.1016)
		(layer "B.Cu")
		(net "SERIAL_B2_RX1")
	)
	(segment
		(start -81.94548 26.162)
		(end -100.7618 26.162)
		(width 0.1016)
		(layer "B.Cu")
		(net "SERIAL_B2_RX1")
	)
	(segment
		(start -68.453 22.7584)
		(end -69.7484 22.7584)
		(width 0.1016)
		(layer "B.Cu")
		(net "SERIAL_B2_RX1")
	)
	(segment
		(start -70.485 29.972)
		(end -71.2216 30.7086)
		(width 0.1016)
		(layer "B.Cu")
		(net "SERIAL_B2_RX1")
	)
	(segment
		(start -77.188022 28.36164)
		(end -79.74584 28.36164)
		(width 0.1016)
		(layer "B.Cu")
		(net "SERIAL_B2_RX1")
	)
	(segment
		(start -41.8846 34.4678)
		(end -42.9006 33.4518)
		(width 0.1016)
		(layer "B.Cu")
		(net "SERIAL_B2_RX1")
	)
	(segment
		(start -40.132 34.4678)
		(end -41.8846 34.4678)
		(width 0.1016)
		(layer "B.Cu")
		(net "SERIAL_B2_RX1")
	)
	(segment
		(start -76.1492 30.099)
		(end -76.1492 29.400462)
		(width 0.1016)
		(layer "B.Cu")
		(net "SERIAL_B2_RX1")
	)
	(segment
		(start -66.1924 25.019)
		(end -68.453 22.7584)
		(width 0.1016)
		(layer "B.Cu")
		(net "SERIAL_B2_RX1")
	)
	(segment
		(start -343.13114 14.8336)
		(end -366.5728 14.8336)
		(width 0.1016)
		(layer "B.Cu")
		(net "SERIAL_B2_RX1")
	)
	(segment
		(start -106.342 22.817)
		(end -106.68 22.479)
		(width 0.1016)
		(layer "B.Cu")
		(net "SERIAL_B2_RX1")
	)
	(segment
		(start -116.2304 -2.2352)
		(end -154.3812 -2.2352)
		(width 0.1016)
		(layer "B.Cu")
		(net "SERIAL_B2_RX1")
	)
	(segment
		(start -37.973 31.5468)
		(end -37.973 32.3088)
		(width 0.1016)
		(layer "B.Cu")
		(net "SERIAL_B2_RX1")
	)
	(segment
		(start -110.3122 22.86)
		(end -110.9472 22.225)
		(width 0.1016)
		(layer "B.Cu")
		(net "SERIAL_B2_RX1")
	)
	(segment
		(start -366.5728 14.8336)
		(end -367.4872 15.748)
		(width 0.1016)
		(layer "B.Cu")
		(net "SERIAL_B2_RX1")
	)
	(segment
		(start -415.16 7.0104)
		(end -415.16 -1.840001)
		(width 0.1016)
		(layer "B.Cu")
		(net "SERIAL_B2_RX1")
	)
	(segment
		(start -76.1492 36.7568)
		(end -76.3524 36.96)
		(width 0.1016)
		(layer "B.Cu")
		(net "SERIAL_B2_RX1")
	)
	(segment
		(start -76.3524 36.96)
		(end -77.040001 36.96)
		(width 0.1016)
		(layer "B.Cu")
		(net "SERIAL_B2_RX1")
	)
	(segment
		(start -154.3812 -2.2352)
		(end -155.1178 -2.9718)
		(width 0.1016)
		(layer "B.Cu")
		(net "SERIAL_B2_RX1")
	)
	(segment
		(start -69.7484 22.7584)
		(end -70.485 23.495)
		(width 0.1016)
		(layer "B.Cu")
		(net "SERIAL_B2_RX1")
	)
	(segment
		(start -70.485 23.495)
		(end -70.485 29.972)
		(width 0.1016)
		(layer "B.Cu")
		(net "SERIAL_B2_RX1")
	)
	(segment
		(start -79.74584 28.36164)
		(end -81.94548 26.162)
		(width 0.1016)
		(layer "B.Cu")
		(net "SERIAL_B2_RX1")
	)
	(segment
		(start -110.9472 22.225)
		(end -110.9472 3.048)
		(width 0.1016)
		(layer "B.Cu")
		(net "SERIAL_B2_RX1")
	)
	(segment
		(start -108.331 22.479)
		(end -108.712 22.86)
		(width 0.1016)
		(layer "B.Cu")
		(net "SERIAL_B2_RX1")
	)
	(segment
		(start -44.9326 27.3558)
		(end -56.1086 27.3558)
		(width 0.1016)
		(layer "B.Cu")
		(net "SERIAL_B2_RX1")
	)
	(segment
		(start -37.973 32.3088)
		(end -40.132 34.4678)
		(width 0.1016)
		(layer "B.Cu")
		(net "SERIAL_B2_RX1")
	)
	(segment
		(start -368.681 15.6972)
		(end -370.96446 13.41374)
		(width 0.12954)
		(layer "In2.Cu")
		(net "SERIAL_B2_RX1")
	)
	(segment
		(start -408.91206 13.41374)
		(end -413.1564 9.1694)
		(width 0.12954)
		(layer "In2.Cu")
		(net "SERIAL_B2_RX1")
	)
	(segment
		(start -413.1564 8.5852)
		(end -414.7312 7.0104)
		(width 0.12954)
		(layer "In2.Cu")
		(net "SERIAL_B2_RX1")
	)
	(segment
		(start -370.96446 13.41374)
		(end -408.91206 13.41374)
		(width 0.12954)
		(layer "In2.Cu")
		(net "SERIAL_B2_RX1")
	)
	(segment
		(start -414.7312 7.0104)
		(end -415.16 7.0104)
		(width 0.12954)
		(layer "In2.Cu")
		(net "SERIAL_B2_RX1")
	)
	(segment
		(start -413.1564 9.1694)
		(end -413.1564 8.5852)
		(width 0.12954)
		(layer "In2.Cu")
		(net "SERIAL_B2_RX1")
	)
	(segment
		(start -297.2562 29.1084)
		(end -297.2562 30.7594)
		(width 0.1016)
		(layer "F.Cu")
		(net "SERIAL_B1_TX2")
	)
	(segment
		(start -299.1866 34.798)
		(end -300.040002 35.651402)
		(width 0.1016)
		(layer "F.Cu")
		(net "SERIAL_B1_TX2")
	)
	(segment
		(start -413.2326 17.04086)
		(end -412.64586 17.6276)
		(width 0.1016)
		(layer "F.Cu")
		(net "SERIAL_B1_TX2")
	)
	(segment
		(start -299.1866 32.6898)
		(end -299.1866 34.798)
		(width 0.1016)
		(layer "F.Cu")
		(net "SERIAL_B1_TX2")
	)
	(segment
		(start -418.97 -1.840001)
		(end -418.97 2.3144)
		(width 0.1016)
		(layer "F.Cu")
		(net "SERIAL_B1_TX2")
	)
	(segment
		(start -414.6804 7.7216)
		(end -412.8135 9.5885)
		(width 0.1016)
		(layer "F.Cu")
		(net "SERIAL_B1_TX2")
	)
	(segment
		(start -414.6804 6.604)
		(end -414.6804 7.7216)
		(width 0.1016)
		(layer "F.Cu")
		(net "SERIAL_B1_TX2")
	)
	(segment
		(start -412.64586 17.6276)
		(end -411.8864 17.6276)
		(width 0.1016)
		(layer "F.Cu")
		(net "SERIAL_B1_TX2")
	)
	(segment
		(start -413.2326 14.89964)
		(end -413.2326 17.04086)
		(width 0.1016)
		(layer "F.Cu")
		(net "SERIAL_B1_TX2")
	)
	(segment
		(start -300.040002 35.651402)
		(end -300.040002 35.66)
		(width 0.1016)
		(layer "F.Cu")
		(net "SERIAL_B1_TX2")
	)
	(segment
		(start -412.8135 9.5885)
		(end -412.8135 14.48054)
		(width 0.1016)
		(layer "F.Cu")
		(net "SERIAL_B1_TX2")
	)
	(segment
		(start -418.97 2.3144)
		(end -414.6804 6.604)
		(width 0.1016)
		(layer "F.Cu")
		(net "SERIAL_B1_TX2")
	)
	(segment
		(start -412.8135 14.48054)
		(end -413.2326 14.89964)
		(width 0.1016)
		(layer "F.Cu")
		(net "SERIAL_B1_TX2")
	)
	(segment
		(start -297.2562 30.7594)
		(end -299.1866 32.6898)
		(width 0.1016)
		(layer "F.Cu")
		(net "SERIAL_B1_TX2")
	)
	(via
		(at -368.046 20.3962)
		(size 0.5588)
		(drill 0.254)
		(layers "F.Cu" "B.Cu")
		(net "SERIAL_B1_TX2")
	)
	(via
		(at -411.8864 17.6276)
		(size 0.5588)
		(drill 0.254)
		(layers "F.Cu" "B.Cu")
		(net "SERIAL_B1_TX2")
	)
	(via
		(at -297.2562 29.1084)
		(size 0.5588)
		(drill 0.254)
		(layers "F.Cu" "B.Cu")
		(net "SERIAL_B1_TX2")
	)
	(segment
		(start -367.1062 20.3962)
		(end -368.046 20.3962)
		(width 0.1016)
		(layer "B.Cu")
		(net "SERIAL_B1_TX2")
	)
	(segment
		(start -333.7814 24.638)
		(end -336.1436 24.638)
		(width 0.1016)
		(layer "B.Cu")
		(net "SERIAL_B1_TX2")
	)
	(segment
		(start -303.5681 28.6893)
		(end -306.5018 25.7556)
		(width 0.1016)
		(layer "B.Cu")
		(net "SERIAL_B1_TX2")
	)
	(segment
		(start -298.143999 28.6893)
		(end -303.5681 28.6893)
		(width 0.1016)
		(layer "B.Cu")
		(net "SERIAL_B1_TX2")
	)
	(segment
		(start -342.5444 18.2372)
		(end -364.9472 18.2372)
		(width 0.1016)
		(layer "B.Cu")
		(net "SERIAL_B1_TX2")
	)
	(segment
		(start -297.90136 29.1084)
		(end -298.143999 28.6893)
		(width 0.1016)
		(layer "B.Cu")
		(net "SERIAL_B1_TX2")
	)
	(segment
		(start -336.1436 24.638)
		(end -342.5444 18.2372)
		(width 0.1016)
		(layer "B.Cu")
		(net "SERIAL_B1_TX2")
	)
	(segment
		(start -332.6638 25.7556)
		(end -333.7814 24.638)
		(width 0.1016)
		(layer "B.Cu")
		(net "SERIAL_B1_TX2")
	)
	(segment
		(start -306.5018 25.7556)
		(end -332.6638 25.7556)
		(width 0.1016)
		(layer "B.Cu")
		(net "SERIAL_B1_TX2")
	)
	(segment
		(start -297.2562 29.1084)
		(end -297.90136 29.1084)
		(width 0.1016)
		(layer "B.Cu")
		(net "SERIAL_B1_TX2")
	)
	(segment
		(start -364.9472 18.2372)
		(end -367.1062 20.3962)
		(width 0.1016)
		(layer "B.Cu")
		(net "SERIAL_B1_TX2")
	)
	(segment
		(start -369.6462 20.3962)
		(end -371.1702 18.8722)
		(width 0.12954)
		(layer "In2.Cu")
		(net "SERIAL_B1_TX2")
	)
	(segment
		(start -380.7206 18.8722)
		(end -383.6416 15.9512)
		(width 0.12954)
		(layer "In2.Cu")
		(net "SERIAL_B1_TX2")
	)
	(segment
		(start -409.72994 17.6276)
		(end -411.8864 17.6276)
		(width 0.12954)
		(layer "In2.Cu")
		(net "SERIAL_B1_TX2")
	)
	(segment
		(start -371.1702 18.8722)
		(end -380.7206 18.8722)
		(width 0.12954)
		(layer "In2.Cu")
		(net "SERIAL_B1_TX2")
	)
	(segment
		(start -383.6416 15.9512)
		(end -408.05354 15.9512)
		(width 0.12954)
		(layer "In2.Cu")
		(net "SERIAL_B1_TX2")
	)
	(segment
		(start -408.05354 15.9512)
		(end -409.72994 17.6276)
		(width 0.12954)
		(layer "In2.Cu")
		(net "SERIAL_B1_TX2")
	)
	(segment
		(start -368.046 20.3962)
		(end -369.6462 20.3962)
		(width 0.12954)
		(layer "In2.Cu")
		(net "SERIAL_B1_TX2")
	)
	(segment
		(start -409.067 46.4947)
		(end -407.8097 46.4947)
		(width 0.12954)
		(layer "In3.Cu")
		(net "SERIAL_B1_TX2")
	)
	(segment
		(start -407.4414 36.5414)
		(end -406.46 35.56)
		(width 0.12954)
		(layer "In3.Cu")
		(net "SERIAL_B1_TX2")
	)
	(segment
		(start -407.8097 46.4947)
		(end -407.4414 46.1264)
		(width 0.12954)
		(layer "In3.Cu")
		(net "SERIAL_B1_TX2")
	)
	(segment
		(start -412.4706 17.6276)
		(end -412.9024 18.0594)
		(width 0.12954)
		(layer "In3.Cu")
		(net "SERIAL_B1_TX2")
	)
	(segment
		(start -412.9024 20.701)
		(end -409.3464 24.257)
		(width 0.12954)
		(layer "In3.Cu")
		(net "SERIAL_B1_TX2")
	)
	(segment
		(start -407.4414 46.1264)
		(end -407.4414 36.5414)
		(width 0.12954)
		(layer "In3.Cu")
		(net "SERIAL_B1_TX2")
	)
	(segment
		(start -412.9024 18.0594)
		(end -412.9024 20.701)
		(width 0.12954)
		(layer "In3.Cu")
		(net "SERIAL_B1_TX2")
	)
	(segment
		(start -409.3464 24.257)
		(end -409.3464 46.2153)
		(width 0.12954)
		(layer "In3.Cu")
		(net "SERIAL_B1_TX2")
	)
	(segment
		(start -409.3464 46.2153)
		(end -409.067 46.4947)
		(width 0.12954)
		(layer "In3.Cu")
		(net "SERIAL_B1_TX2")
	)
	(segment
		(start -411.8864 17.6276)
		(end -412.4706 17.6276)
		(width 0.12954)
		(layer "In3.Cu")
		(net "SERIAL_B1_TX2")
	)
	(segment
		(start -415.8234 6.830629)
		(end -420.24 2.414029)
		(width 0.1016)
		(layer "F.Cu")
		(net "SERIAL_B1_RX2")
	)
	(segment
		(start -415.8234 7.1374)
		(end -415.8234 6.830629)
		(width 0.1016)
		(layer "F.Cu")
		(net "SERIAL_B1_RX2")
	)
	(segment
		(start -300.9646 36.1442)
		(end -300.0488 37.06)
		(width 0.1016)
		(layer "F.Cu")
		(net "SERIAL_B1_RX2")
	)
	(segment
		(start -413.10814 14.39672)
		(end -413.10814 9.85266)
		(width 0.1016)
		(layer "F.Cu")
		(net "SERIAL_B1_RX2")
	)
	(segment
		(start -413.52216 17.3736)
		(end -413.52216 14.81074)
		(width 0.1016)
		(layer "F.Cu")
		(net "SERIAL_B1_RX2")
	)
	(segment
		(start -411.0736 18.1864)
		(end -411.099 18.161)
		(width 0.1016)
		(layer "F.Cu")
		(net "SERIAL_B1_RX2")
	)
	(segment
		(start -413.10814 9.85266)
		(end -415.8234 7.1374)
		(width 0.1016)
		(layer "F.Cu")
		(net "SERIAL_B1_RX2")
	)
	(segment
		(start -300.0488 37.06)
		(end -300.040002 37.06)
		(width 0.1016)
		(layer "F.Cu")
		(net "SERIAL_B1_RX2")
	)
	(segment
		(start -420.24 2.414029)
		(end -420.24 -1.840001)
		(width 0.1016)
		(layer "F.Cu")
		(net "SERIAL_B1_RX2")
	)
	(segment
		(start -412.73476 18.161)
		(end -413.52216 17.3736)
		(width 0.1016)
		(layer "F.Cu")
		(net "SERIAL_B1_RX2")
	)
	(segment
		(start -300.9646 31.3944)
		(end -300.9646 36.1442)
		(width 0.1016)
		(layer "F.Cu")
		(net "SERIAL_B1_RX2")
	)
	(segment
		(start -413.52216 14.81074)
		(end -413.10814 14.39672)
		(width 0.1016)
		(layer "F.Cu")
		(net "SERIAL_B1_RX2")
	)
	(segment
		(start -411.099 18.161)
		(end -412.73476 18.161)
		(width 0.1016)
		(layer "F.Cu")
		(net "SERIAL_B1_RX2")
	)
	(segment
		(start -298.7294 29.1592)
		(end -300.9646 31.3944)
		(width 0.1016)
		(layer "F.Cu")
		(net "SERIAL_B1_RX2")
	)
	(via
		(at -368.8334 20.8788)
		(size 0.5588)
		(drill 0.254)
		(layers "F.Cu" "B.Cu")
		(net "SERIAL_B1_RX2")
	)
	(via
		(at -298.7294 29.1592)
		(size 0.5588)
		(drill 0.254)
		(layers "F.Cu" "B.Cu")
		(net "SERIAL_B1_RX2")
	)
	(via
		(at -411.0736 18.1864)
		(size 0.5588)
		(drill 0.254)
		(layers "F.Cu" "B.Cu")
		(net "SERIAL_B1_RX2")
	)
	(segment
		(start -368.8334 20.8788)
		(end -367.0808 20.8788)
		(width 0.1016)
		(layer "B.Cu")
		(net "SERIAL_B1_RX2")
	)
	(segment
		(start -303.53 29.1592)
		(end -298.7294 29.1592)
		(width 0.1016)
		(layer "B.Cu")
		(net "SERIAL_B1_RX2")
	)
	(segment
		(start -342.6968 18.542)
		(end -335.9658 25.273)
		(width 0.1016)
		(layer "B.Cu")
		(net "SERIAL_B1_RX2")
	)
	(segment
		(start -364.744 18.542)
		(end -342.6968 18.542)
		(width 0.1016)
		(layer "B.Cu")
		(net "SERIAL_B1_RX2")
	)
	(segment
		(start -335.9658 25.273)
		(end -333.5782 25.273)
		(width 0.1016)
		(layer "B.Cu")
		(net "SERIAL_B1_RX2")
	)
	(segment
		(start -332.74 26.1112)
		(end -306.578 26.1112)
		(width 0.1016)
		(layer "B.Cu")
		(net "SERIAL_B1_RX2")
	)
	(segment
		(start -367.0808 20.8788)
		(end -364.744 18.542)
		(width 0.1016)
		(layer "B.Cu")
		(net "SERIAL_B1_RX2")
	)
	(segment
		(start -306.578 26.1112)
		(end -303.53 29.1592)
		(width 0.1016)
		(layer "B.Cu")
		(net "SERIAL_B1_RX2")
	)
	(segment
		(start -333.5782 25.273)
		(end -332.74 26.1112)
		(width 0.1016)
		(layer "B.Cu")
		(net "SERIAL_B1_RX2")
	)
	(segment
		(start -369.9764 20.8788)
		(end -370.6876 20.1676)
		(width 0.12954)
		(layer "In2.Cu")
		(net "SERIAL_B1_RX2")
	)
	(segment
		(start -409.78836 18.1864)
		(end -411.0736 18.1864)
		(width 0.12954)
		(layer "In2.Cu")
		(net "SERIAL_B1_RX2")
	)
	(segment
		(start -370.6876 20.1676)
		(end -380.5428 20.1676)
		(width 0.12954)
		(layer "In2.Cu")
		(net "SERIAL_B1_RX2")
	)
	(segment
		(start -368.8334 20.8788)
		(end -369.9764 20.8788)
		(width 0.12954)
		(layer "In2.Cu")
		(net "SERIAL_B1_RX2")
	)
	(segment
		(start -380.5428 20.1676)
		(end -384.47726 16.23314)
		(width 0.12954)
		(layer "In2.Cu")
		(net "SERIAL_B1_RX2")
	)
	(segment
		(start -407.8351 16.23314)
		(end -409.78836 18.1864)
		(width 0.12954)
		(layer "In2.Cu")
		(net "SERIAL_B1_RX2")
	)
	(segment
		(start -384.47726 16.23314)
		(end -407.8351 16.23314)
		(width 0.12954)
		(layer "In2.Cu")
		(net "SERIAL_B1_RX2")
	)
	(segment
		(start -407.5684 33.0516)
		(end -406.46 34.16)
		(width 0.12954)
		(layer "In3.Cu")
		(net "SERIAL_B1_RX2")
	)
	(segment
		(start -411.0736 18.1864)
		(end -411.0736 21.5392)
		(width 0.12954)
		(layer "In3.Cu")
		(net "SERIAL_B1_RX2")
	)
	(segment
		(start -411.0736 21.5392)
		(end -407.5684 25.0444)
		(width 0.12954)
		(layer "In3.Cu")
		(net "SERIAL_B1_RX2")
	)
	(segment
		(start -407.5684 25.0444)
		(end -407.5684 33.0516)
		(width 0.12954)
		(layer "In3.Cu")
		(net "SERIAL_B1_RX2")
	)
	(segment
		(start -81.9912 28.1686)
		(end -82.423 28.6004)
		(width 0.1016)
		(layer "F.Cu")
		(net "PSU_B2_ALERT_N")
	)
	(segment
		(start -79.9592 28.1686)
		(end -81.9912 28.1686)
		(width 0.1016)
		(layer "F.Cu")
		(net "PSU_B2_ALERT_N")
	)
	(segment
		(start -116.9089 1.524)
		(end -113.9698 1.524)
		(width 0.1016)
		(layer "F.Cu")
		(net "PSU_B2_ALERT_N")
	)
	(segment
		(start -81.04 36.9176)
		(end -81.04 36.96)
		(width 0.1016)
		(layer "F.Cu")
		(net "PSU_B2_ALERT_N")
	)
	(segment
		(start -113.9698 1.524)
		(end -113.9444 1.4986)
		(width 0.1016)
		(layer "F.Cu")
		(net "PSU_B2_ALERT_N")
	)
	(segment
		(start -82.423 28.6004)
		(end -82.423 29.4132)
		(width 0.1016)
		(layer "F.Cu")
		(net "PSU_B2_ALERT_N")
	)
	(segment
		(start -82.0674 29.7688)
		(end -82.0674 35.8902)
		(width 0.1016)
		(layer "F.Cu")
		(net "PSU_B2_ALERT_N")
	)
	(segment
		(start -82.423 29.4132)
		(end -82.0674 29.7688)
		(width 0.1016)
		(layer "F.Cu")
		(net "PSU_B2_ALERT_N")
	)
	(segment
		(start -79.2734 28.829)
		(end -79.2988 28.829)
		(width 0.1016)
		(layer "F.Cu")
		(net "PSU_B2_ALERT_N")
	)
	(segment
		(start -79.2988 28.829)
		(end -79.9592 28.1686)
		(width 0.1016)
		(layer "F.Cu")
		(net "PSU_B2_ALERT_N")
	)
	(segment
		(start -82.0674 35.8902)
		(end -81.04 36.9176)
		(width 0.1016)
		(layer "F.Cu")
		(net "PSU_B2_ALERT_N")
	)
	(via
		(at -368.7318 16.6878)
		(size 0.5588)
		(drill 0.254)
		(layers "F.Cu" "B.Cu")
		(net "PSU_B2_ALERT_N")
	)
	(via
		(at -95.1992 26.8478)
		(size 0.5588)
		(drill 0.254)
		(layers "F.Cu" "B.Cu")
		(net "PSU_B2_ALERT_N")
	)
	(via
		(at -417.7 6.985)
		(size 0.5588)
		(drill 0.254)
		(layers "F.Cu" "B.Cu")
		(net "PSU_B2_ALERT_N")
	)
	(via
		(at -79.2734 28.829)
		(size 0.5588)
		(drill 0.254)
		(layers "F.Cu" "B.Cu")
		(net "PSU_B2_ALERT_N")
	)
	(via
		(at -113.9444 1.4986)
		(size 0.5588)
		(drill 0.254)
		(layers "F.Cu" "B.Cu")
		(net "PSU_B2_ALERT_N")
	)
	(segment
		(start -155.8798 -2.4638)
		(end -324.993 -2.4638)
		(width 0.1016)
		(layer "B.Cu")
		(net "PSU_B2_ALERT_N")
	)
	(segment
		(start -113.9444 13.843)
		(end -113.9444 1.4986)
		(width 0.1016)
		(layer "B.Cu")
		(net "PSU_B2_ALERT_N")
	)
	(segment
		(start -417.7 6.985)
		(end -417.7 -1.840001)
		(width 0.1016)
		(layer "B.Cu")
		(net "PSU_B2_ALERT_N")
	)
	(segment
		(start -94.9452 26.5938)
		(end -81.97088 26.5938)
		(width 0.1016)
		(layer "B.Cu")
		(net "PSU_B2_ALERT_N")
	)
	(segment
		(start -104.2924 26.8478)
		(end -105.8418 25.2984)
		(width 0.1016)
		(layer "B.Cu")
		(net "PSU_B2_ALERT_N")
	)
	(segment
		(start -114.8334 16.5354)
		(end -114.8334 14.732)
		(width 0.1016)
		(layer "B.Cu")
		(net "PSU_B2_ALERT_N")
	)
	(segment
		(start -115.6716 1.4986)
		(end -118.3132 -1.143)
		(width 0.1016)
		(layer "B.Cu")
		(net "PSU_B2_ALERT_N")
	)
	(segment
		(start -113.9444 1.4986)
		(end -115.6716 1.4986)
		(width 0.1016)
		(layer "B.Cu")
		(net "PSU_B2_ALERT_N")
	)
	(segment
		(start -324.993 -2.4638)
		(end -342.8492 15.3924)
		(width 0.1016)
		(layer "B.Cu")
		(net "PSU_B2_ALERT_N")
	)
	(segment
		(start -110.0074 25.2984)
		(end -113.9444 21.3614)
		(width 0.1016)
		(layer "B.Cu")
		(net "PSU_B2_ALERT_N")
	)
	(segment
		(start -113.9444 17.4244)
		(end -114.8334 16.5354)
		(width 0.1016)
		(layer "B.Cu")
		(net "PSU_B2_ALERT_N")
	)
	(segment
		(start -154.559 -1.143)
		(end -155.8798 -2.4638)
		(width 0.1016)
		(layer "B.Cu")
		(net "PSU_B2_ALERT_N")
	)
	(segment
		(start -95.1992 26.8478)
		(end -104.2924 26.8478)
		(width 0.1016)
		(layer "B.Cu")
		(net "PSU_B2_ALERT_N")
	)
	(segment
		(start -367.538 16.7386)
		(end -368.681 16.7386)
		(width 0.1016)
		(layer "B.Cu")
		(net "PSU_B2_ALERT_N")
	)
	(segment
		(start -81.97088 26.5938)
		(end -79.73568 28.829)
		(width 0.1016)
		(layer "B.Cu")
		(net "PSU_B2_ALERT_N")
	)
	(segment
		(start -113.9444 21.3614)
		(end -113.9444 17.4244)
		(width 0.1016)
		(layer "B.Cu")
		(net "PSU_B2_ALERT_N")
	)
	(segment
		(start -79.73568 28.829)
		(end -79.2734 28.829)
		(width 0.1016)
		(layer "B.Cu")
		(net "PSU_B2_ALERT_N")
	)
	(segment
		(start -118.3132 -1.143)
		(end -154.559 -1.143)
		(width 0.1016)
		(layer "B.Cu")
		(net "PSU_B2_ALERT_N")
	)
	(segment
		(start -366.1918 15.3924)
		(end -367.538 16.7386)
		(width 0.1016)
		(layer "B.Cu")
		(net "PSU_B2_ALERT_N")
	)
	(segment
		(start -105.8418 25.2984)
		(end -110.0074 25.2984)
		(width 0.1016)
		(layer "B.Cu")
		(net "PSU_B2_ALERT_N")
	)
	(segment
		(start -114.8334 14.732)
		(end -113.9444 13.843)
		(width 0.1016)
		(layer "B.Cu")
		(net "PSU_B2_ALERT_N")
	)
	(segment
		(start -95.1992 26.8478)
		(end -94.9452 26.5938)
		(width 0.1016)
		(layer "B.Cu")
		(net "PSU_B2_ALERT_N")
	)
	(segment
		(start -368.681 16.7386)
		(end -368.7318 16.6878)
		(width 0.1016)
		(layer "B.Cu")
		(net "PSU_B2_ALERT_N")
	)
	(segment
		(start -342.8492 15.3924)
		(end -366.1918 15.3924)
		(width 0.1016)
		(layer "B.Cu")
		(net "PSU_B2_ALERT_N")
	)
	(segment
		(start -415.29 7.8486)
		(end -409.16098 13.97762)
		(width 0.12954)
		(layer "In2.Cu")
		(net "PSU_B2_ALERT_N")
	)
	(segment
		(start -371.89918 13.97762)
		(end -369.189 16.6878)
		(width 0.12954)
		(layer "In2.Cu")
		(net "PSU_B2_ALERT_N")
	)
	(segment
		(start -416.7856 7.8486)
		(end -415.29 7.8486)
		(width 0.12954)
		(layer "In2.Cu")
		(net "PSU_B2_ALERT_N")
	)
	(segment
		(start -417.7 6.985)
		(end -417.6492 6.985)
		(width 0.12954)
		(layer "In2.Cu")
		(net "PSU_B2_ALERT_N")
	)
	(segment
		(start -417.6492 6.985)
		(end -416.7856 7.8486)
		(width 0.12954)
		(layer "In2.Cu")
		(net "PSU_B2_ALERT_N")
	)
	(segment
		(start -409.16098 13.97762)
		(end -371.89918 13.97762)
		(width 0.12954)
		(layer "In2.Cu")
		(net "PSU_B2_ALERT_N")
	)
	(segment
		(start -369.189 16.6878)
		(end -368.7318 16.6878)
		(width 0.12954)
		(layer "In2.Cu")
		(net "PSU_B2_ALERT_N")
	)
	(segment
		(start -104.521 46.355)
		(end -154.178 46.355)
		(width 0.12954)
		(layer "In3.Cu")
		(net "PSU_B2_ALERT_N")
	)
	(segment
		(start -182.3974 36.522599)
		(end -183.459999 35.46)
		(width 0.12954)
		(layer "In3.Cu")
		(net "PSU_B2_ALERT_N")
	)
	(segment
		(start -182.3974 45.7708)
		(end -182.3974 36.522599)
		(width 0.12954)
		(layer "In3.Cu")
		(net "PSU_B2_ALERT_N")
	)
	(segment
		(start -103.505 37.80282)
		(end -103.505 45.339)
		(width 0.12954)
		(layer "In3.Cu")
		(net "PSU_B2_ALERT_N")
	)
	(segment
		(start -95.1992 29.49702)
		(end -103.505 37.80282)
		(width 0.12954)
		(layer "In3.Cu")
		(net "PSU_B2_ALERT_N")
	)
	(segment
		(start -154.178 46.355)
		(end -156.337 44.196)
		(width 0.12954)
		(layer "In3.Cu")
		(net "PSU_B2_ALERT_N")
	)
	(segment
		(start -103.505 45.339)
		(end -104.521 46.355)
		(width 0.12954)
		(layer "In3.Cu")
		(net "PSU_B2_ALERT_N")
	)
	(segment
		(start -167.259 44.196)
		(end -169.7482 46.6852)
		(width 0.12954)
		(layer "In3.Cu")
		(net "PSU_B2_ALERT_N")
	)
	(segment
		(start -181.483 46.6852)
		(end -182.3974 45.7708)
		(width 0.12954)
		(layer "In3.Cu")
		(net "PSU_B2_ALERT_N")
	)
	(segment
		(start -169.7482 46.6852)
		(end -181.483 46.6852)
		(width 0.12954)
		(layer "In3.Cu")
		(net "PSU_B2_ALERT_N")
	)
	(segment
		(start -95.1992 26.8478)
		(end -95.1992 29.49702)
		(width 0.12954)
		(layer "In3.Cu")
		(net "PSU_B2_ALERT_N")
	)
	(segment
		(start -156.337 44.196)
		(end -167.259 44.196)
		(width 0.12954)
		(layer "In3.Cu")
		(net "PSU_B2_ALERT_N")
	)
	(segment
		(start -108.2802 1.7526)
		(end -107.823 2.2098)
		(width 0.1016)
		(layer "F.Cu")
		(net "BLADE_B2_EN1")
	)
	(segment
		(start -109.758089 22.118709)
		(end -109.758089 22.262389)
		(width 0.1016)
		(layer "F.Cu")
		(net "BLADE_B2_EN1")
	)
	(segment
		(start -107.823 3.6322)
		(end -107.8484 3.6576)
		(width 0.1016)
		(layer "F.Cu")
		(net "BLADE_B2_EN1")
	)
	(segment
		(start -110.9399 23.4442)
		(end -110.9399 23.4696)
		(width 0.1016)
		(layer "F.Cu")
		(net "BLADE_B2_EN1")
	)
	(segment
		(start -107.823 2.2098)
		(end -107.823 3.6322)
		(width 0.1016)
		(layer "F.Cu")
		(net "BLADE_B2_EN1")
	)
	(segment
		(start -35.4638 32.0421)
		(end -33.71374 33.79216)
		(width 0.1016)
		(layer "F.Cu")
		(net "BLADE_B2_EN1")
	)
	(segment
		(start -38.424104 32.658304)
		(end -37.8079 32.0421)
		(width 0.1016)
		(layer "F.Cu")
		(net "BLADE_B2_EN1")
	)
	(segment
		(start -109.0857 1.7526)
		(end -108.2802 1.7526)
		(width 0.1016)
		(layer "F.Cu")
		(net "BLADE_B2_EN1")
	)
	(segment
		(start -37.8079 32.0421)
		(end -35.4638 32.0421)
		(width 0.1016)
		(layer "F.Cu")
		(net "BLADE_B2_EN1")
	)
	(segment
		(start -33.71374 41.626262)
		(end -32.680001 42.660001)
		(width 0.1016)
		(layer "F.Cu")
		(net "BLADE_B2_EN1")
	)
	(segment
		(start -33.71374 33.79216)
		(end -33.71374 41.626262)
		(width 0.1016)
		(layer "F.Cu")
		(net "BLADE_B2_EN1")
	)
	(segment
		(start -41.596122 32.658304)
		(end -38.424104 32.658304)
		(width 0.1016)
		(layer "F.Cu")
		(net "BLADE_B2_EN1")
	)
	(segment
		(start -109.758089 22.262389)
		(end -110.9399 23.4442)
		(width 0.1016)
		(layer "F.Cu")
		(net "BLADE_B2_EN1")
	)
	(via
		(at -41.596122 32.658304)
		(size 0.5588)
		(drill 0.254)
		(layers "F.Cu" "B.Cu")
		(net "BLADE_B2_EN1")
	)
	(via
		(at -416.43 6.985)
		(size 0.5588)
		(drill 0.254)
		(layers "F.Cu" "B.Cu")
		(net "BLADE_B2_EN1")
	)
	(via
		(at -72.771 28.8798)
		(size 0.5588)
		(drill 0.254)
		(layers "F.Cu" "B.Cu")
		(net "BLADE_B2_EN1")
	)
	(via
		(at -107.8484 3.6576)
		(size 0.5588)
		(drill 0.254)
		(layers "F.Cu" "B.Cu")
		(net "BLADE_B2_EN1")
	)
	(via
		(at -110.9399 23.4696)
		(size 0.5588)
		(drill 0.254)
		(layers "F.Cu" "B.Cu")
		(net "BLADE_B2_EN1")
	)
	(via
		(at -367.9952 16.2052)
		(size 0.5588)
		(drill 0.254)
		(layers "F.Cu" "B.Cu")
		(net "BLADE_B2_EN1")
	)
	(via
		(at -109.758089 22.118709)
		(size 0.5588)
		(drill 0.254)
		(layers "F.Cu" "B.Cu")
		(net "BLADE_B2_EN1")
	)
	(segment
		(start -106.188756 22.150144)
		(end -106.553 21.7859)
		(width 0.1016)
		(layer "B.Cu")
		(net "BLADE_B2_EN1")
	)
	(segment
		(start -111.4552 22.9543)
		(end -110.9399 23.4696)
		(width 0.1016)
		(layer "B.Cu")
		(net "BLADE_B2_EN1")
	)
	(segment
		(start -71.1962 29.21)
		(end -71.5772 29.591)
		(width 0.1016)
		(layer "B.Cu")
		(net "BLADE_B2_EN1")
	)
	(segment
		(start -74.041 28.8798)
		(end -75.1078 27.813)
		(width 0.1016)
		(layer "B.Cu")
		(net "BLADE_B2_EN1")
	)
	(segment
		(start -114.007875 0.571525)
		(end -111.4552 3.1242)
		(width 0.1016)
		(layer "B.Cu")
		(net "BLADE_B2_EN1")
	)
	(segment
		(start -44.0182 26.416)
		(end -55.0926 26.416)
		(width 0.1016)
		(layer "B.Cu")
		(net "BLADE_B2_EN1")
	)
	(segment
		(start -154.432 -1.651)
		(end -118.1862 -1.651)
		(width 0.1016)
		(layer "B.Cu")
		(net "BLADE_B2_EN1")
	)
	(segment
		(start -72.771 28.8798)
		(end -74.041 28.8798)
		(width 0.1016)
		(layer "B.Cu")
		(net "BLADE_B2_EN1")
	)
	(segment
		(start -416.43 -1.840001)
		(end -416.43 6.985)
		(width 0.1016)
		(layer "B.Cu")
		(net "BLADE_B2_EN1")
	)
	(segment
		(start -70.2564 21.844)
		(end -71.1962 22.7838)
		(width 0.1016)
		(layer "B.Cu")
		(net "BLADE_B2_EN1")
	)
	(segment
		(start -81.72196 25.4762)
		(end -100.1522 25.4762)
		(width 0.1016)
		(layer "B.Cu")
		(net "BLADE_B2_EN1")
	)
	(segment
		(start -109.240709 22.118709)
		(end -109.758089 22.118709)
		(width 0.1016)
		(layer "B.Cu")
		(net "BLADE_B2_EN1")
	)
	(segment
		(start -68.1482 21.844)
		(end -70.2564 21.844)
		(width 0.1016)
		(layer "B.Cu")
		(net "BLADE_B2_EN1")
	)
	(segment
		(start -106.553 21.7859)
		(end -108.9079 21.7859)
		(width 0.1016)
		(layer "B.Cu")
		(net "BLADE_B2_EN1")
	)
	(segment
		(start -41.5798 28.8544)
		(end -44.0182 26.416)
		(width 0.1016)
		(layer "B.Cu")
		(net "BLADE_B2_EN1")
	)
	(segment
		(start -65.9384 24.0538)
		(end -68.1482 21.844)
		(width 0.1016)
		(layer "B.Cu")
		(net "BLADE_B2_EN1")
	)
	(segment
		(start -57.4548 24.0538)
		(end -65.9384 24.0538)
		(width 0.1016)
		(layer "B.Cu")
		(net "BLADE_B2_EN1")
	)
	(segment
		(start -118.1862 -1.651)
		(end -115.963675 0.571525)
		(width 0.1016)
		(layer "B.Cu")
		(net "BLADE_B2_EN1")
	)
	(segment
		(start -72.0598 29.591)
		(end -72.771 28.8798)
		(width 0.1016)
		(layer "B.Cu")
		(net "BLADE_B2_EN1")
	)
	(segment
		(start -79.38516 27.813)
		(end -81.72196 25.4762)
		(width 0.1016)
		(layer "B.Cu")
		(net "BLADE_B2_EN1")
	)
	(segment
		(start -115.963675 0.571525)
		(end -114.007875 0.571525)
		(width 0.1016)
		(layer "B.Cu")
		(net "BLADE_B2_EN1")
	)
	(segment
		(start -103.478256 22.150144)
		(end -106.188756 22.150144)
		(width 0.1016)
		(layer "B.Cu")
		(net "BLADE_B2_EN1")
	)
	(segment
		(start -75.1078 27.813)
		(end -79.38516 27.813)
		(width 0.1016)
		(layer "B.Cu")
		(net "BLADE_B2_EN1")
	)
	(segment
		(start -55.0926 26.416)
		(end -57.4548 24.0538)
		(width 0.1016)
		(layer "B.Cu")
		(net "BLADE_B2_EN1")
	)
	(segment
		(start -342.9762 15.113)
		(end -325.1454 -2.7178)
		(width 0.1016)
		(layer "B.Cu")
		(net "BLADE_B2_EN1")
	)
	(segment
		(start -71.5772 29.591)
		(end -72.0598 29.591)
		(width 0.1016)
		(layer "B.Cu")
		(net "BLADE_B2_EN1")
	)
	(segment
		(start -155.4988 -2.7178)
		(end -154.432 -1.651)
		(width 0.1016)
		(layer "B.Cu")
		(net "BLADE_B2_EN1")
	)
	(segment
		(start -108.9079 21.7859)
		(end -109.240709 22.118709)
		(width 0.1016)
		(layer "B.Cu")
		(net "BLADE_B2_EN1")
	)
	(segment
		(start -367.4872 16.256)
		(end -366.3442 15.113)
		(width 0.1016)
		(layer "B.Cu")
		(net "BLADE_B2_EN1")
	)
	(segment
		(start -367.9444 16.256)
		(end -367.4872 16.256)
		(width 0.1016)
		(layer "B.Cu")
		(net "BLADE_B2_EN1")
	)
	(segment
		(start -41.596122 32.658304)
		(end -41.5798 32.641982)
		(width 0.1016)
		(layer "B.Cu")
		(net "BLADE_B2_EN1")
	)
	(segment
		(start -71.1962 22.7838)
		(end -71.1962 29.21)
		(width 0.1016)
		(layer "B.Cu")
		(net "BLADE_B2_EN1")
	)
	(segment
		(start -100.1522 25.4762)
		(end -103.478256 22.150144)
		(width 0.1016)
		(layer "B.Cu")
		(net "BLADE_B2_EN1")
	)
	(segment
		(start -41.5798 32.641982)
		(end -41.5798 28.8544)
		(width 0.1016)
		(layer "B.Cu")
		(net "BLADE_B2_EN1")
	)
	(segment
		(start -111.4552 3.1242)
		(end -111.4552 22.9543)
		(width 0.1016)
		(layer "B.Cu")
		(net "BLADE_B2_EN1")
	)
	(segment
		(start -367.9952 16.2052)
		(end -367.9444 16.256)
		(width 0.1016)
		(layer "B.Cu")
		(net "BLADE_B2_EN1")
	)
	(segment
		(start -366.3442 15.113)
		(end -342.9762 15.113)
		(width 0.1016)
		(layer "B.Cu")
		(net "BLADE_B2_EN1")
	)
	(segment
		(start -325.1454 -2.7178)
		(end -155.4988 -2.7178)
		(width 0.1016)
		(layer "B.Cu")
		(net "BLADE_B2_EN1")
	)
	(segment
		(start -110.0074 21.869397)
		(end -110.0074 14.986)
		(width 0.12954)
		(layer "In2.Cu")
		(net "BLADE_B2_EN1")
	)
	(segment
		(start -108.97616 14.15034)
		(end -108.1024 13.27658)
		(width 0.12954)
		(layer "In2.Cu")
		(net "BLADE_B2_EN1")
	)
	(segment
		(start -108.1024 13.27658)
		(end -108.1024 10.5664)
		(width 0.12954)
		(layer "In2.Cu")
		(net "BLADE_B2_EN1")
	)
	(segment
		(start -110.0074 14.986)
		(end -109.17174 14.15034)
		(width 0.12954)
		(layer "In2.Cu")
		(net "BLADE_B2_EN1")
	)
	(segment
		(start -72.771 31.6992)
		(end -72.771 28.8798)
		(width 0.12954)
		(layer "In2.Cu")
		(net "BLADE_B2_EN1")
	)
	(segment
		(start -110.0074 9.2964)
		(end -110.0074 5.8166)
		(width 0.12954)
		(layer "In2.Cu")
		(net "BLADE_B2_EN1")
	)
	(segment
		(start -109.0676 9.6012)
		(end -109.7026 9.6012)
		(width 0.12954)
		(layer "In2.Cu")
		(net "BLADE_B2_EN1")
	)
	(segment
		(start -75.040002 35.66)
		(end -74.2696 34.889597)
		(width 0.12954)
		(layer "In2.Cu")
		(net "BLADE_B2_EN1")
	)
	(segment
		(start -108.1024 10.5664)
		(end -109.0676 9.6012)
		(width 0.12954)
		(layer "In2.Cu")
		(net "BLADE_B2_EN1")
	)
	(segment
		(start -110.0074 5.8166)
		(end -107.8484 3.6576)
		(width 0.12954)
		(layer "In2.Cu")
		(net "BLADE_B2_EN1")
	)
	(segment
		(start -109.7026 9.6012)
		(end -110.0074 9.2964)
		(width 0.12954)
		(layer "In2.Cu")
		(net "BLADE_B2_EN1")
	)
	(segment
		(start -74.2696 33.1978)
		(end -72.771 31.6992)
		(width 0.12954)
		(layer "In2.Cu")
		(net "BLADE_B2_EN1")
	)
	(segment
		(start -371.46992 13.69568)
		(end -368.9604 16.2052)
		(width 0.12954)
		(layer "In2.Cu")
		(net "BLADE_B2_EN1")
	)
	(segment
		(start -368.9604 16.2052)
		(end -367.9952 16.2052)
		(width 0.12954)
		(layer "In2.Cu")
		(net "BLADE_B2_EN1")
	)
	(segment
		(start -109.758089 22.118709)
		(end -110.0074 21.869397)
		(width 0.12954)
		(layer "In2.Cu")
		(net "BLADE_B2_EN1")
	)
	(segment
		(start -109.17174 14.15034)
		(end -108.97616 14.15034)
		(width 0.12954)
		(layer "In2.Cu")
		(net "BLADE_B2_EN1")
	)
	(segment
		(start -415.2138 7.5184)
		(end -409.03652 13.69568)
		(width 0.12954)
		(layer "In2.Cu")
		(net "BLADE_B2_EN1")
	)
	(segment
		(start -416.43 6.985)
		(end -415.8966 7.5184)
		(width 0.12954)
		(layer "In2.Cu")
		(net "BLADE_B2_EN1")
	)
	(segment
		(start -415.8966 7.5184)
		(end -415.2138 7.5184)
		(width 0.12954)
		(layer "In2.Cu")
		(net "BLADE_B2_EN1")
	)
	(segment
		(start -74.2696 34.889597)
		(end -74.2696 33.1978)
		(width 0.12954)
		(layer "In2.Cu")
		(net "BLADE_B2_EN1")
	)
	(segment
		(start -409.03652 13.69568)
		(end -371.46992 13.69568)
		(width 0.12954)
		(layer "In2.Cu")
		(net "BLADE_B2_EN1")
	)
	(segment
		(start -417.7 3.0002)
		(end -414.3756 6.3246)
		(width 0.1016)
		(layer "F.Cu")
		(net "PSU_B1_ALERT_N")
	)
	(segment
		(start -414.3756 7.3152)
		(end -412.49346 9.19734)
		(width 0.1016)
		(layer "F.Cu")
		(net "PSU_B1_ALERT_N")
	)
	(segment
		(start -412.94304 16.57604)
		(end -412.45028 17.0688)
		(width 0.1016)
		(layer "F.Cu")
		(net "PSU_B1_ALERT_N")
	)
	(segment
		(start -417.7 -1.840001)
		(end -417.7 3.0002)
		(width 0.1016)
		(layer "F.Cu")
		(net "PSU_B1_ALERT_N")
	)
	(segment
		(start -412.94304 15.02664)
		(end -412.94304 16.57604)
		(width 0.1016)
		(layer "F.Cu")
		(net "PSU_B1_ALERT_N")
	)
	(segment
		(start -412.49346 9.19734)
		(end -412.49346 14.57706)
		(width 0.1016)
		(layer "F.Cu")
		(net "PSU_B1_ALERT_N")
	)
	(segment
		(start -412.45028 17.0688)
		(end -411.099 17.0688)
		(width 0.1016)
		(layer "F.Cu")
		(net "PSU_B1_ALERT_N")
	)
	(segment
		(start -337.9089 1.524)
		(end -334.899 1.524)
		(width 0.1016)
		(layer "F.Cu")
		(net "PSU_B1_ALERT_N")
	)
	(segment
		(start -412.49346 14.57706)
		(end -412.94304 15.02664)
		(width 0.1016)
		(layer "F.Cu")
		(net "PSU_B1_ALERT_N")
	)
	(segment
		(start -414.3756 6.3246)
		(end -414.3756 7.3152)
		(width 0.1016)
		(layer "F.Cu")
		(net "PSU_B1_ALERT_N")
	)
	(via
		(at -411.099 17.0688)
		(size 0.5588)
		(drill 0.254)
		(layers "F.Cu" "B.Cu")
		(net "PSU_B1_ALERT_N")
	)
	(via
		(at -305.3334 26.2128)
		(size 0.5588)
		(drill 0.254)
		(layers "F.Cu" "B.Cu")
		(net "PSU_B1_ALERT_N")
	)
	(via
		(at -334.899 1.524)
		(size 0.5588)
		(drill 0.254)
		(layers "F.Cu" "B.Cu")
		(net "PSU_B1_ALERT_N")
	)
	(via
		(at -335.534 24.0919)
		(size 0.5588)
		(drill 0.254)
		(layers "F.Cu" "B.Cu")
		(net "PSU_B1_ALERT_N")
	)
	(via
		(at -368.808 19.8628)
		(size 0.5588)
		(drill 0.254)
		(layers "F.Cu" "B.Cu")
		(net "PSU_B1_ALERT_N")
	)
	(segment
		(start -336.2579 24.1173)
		(end -342.47074 17.90446)
		(width 0.1016)
		(layer "B.Cu")
		(net "PSU_B1_ALERT_N")
	)
	(segment
		(start -306.2224 25.3238)
		(end -332.6892 25.3238)
		(width 0.1016)
		(layer "B.Cu")
		(net "PSU_B1_ALERT_N")
	)
	(segment
		(start -333.9211 24.0919)
		(end -335.534 24.0919)
		(width 0.1016)
		(layer "B.Cu")
		(net "PSU_B1_ALERT_N")
	)
	(segment
		(start -335.5594 24.1173)
		(end -336.2579 24.1173)
		(width 0.1016)
		(layer "B.Cu")
		(net "PSU_B1_ALERT_N")
	)
	(segment
		(start -342.47074 17.90446)
		(end -365.24946 17.90446)
		(width 0.1016)
		(layer "B.Cu")
		(net "PSU_B1_ALERT_N")
	)
	(segment
		(start -365.24946 17.90446)
		(end -367.2078 19.8628)
		(width 0.1016)
		(layer "B.Cu")
		(net "PSU_B1_ALERT_N")
	)
	(segment
		(start -305.3334 26.2128)
		(end -306.2224 25.3238)
		(width 0.1016)
		(layer "B.Cu")
		(net "PSU_B1_ALERT_N")
	)
	(segment
		(start -332.6892 25.3238)
		(end -333.9211 24.0919)
		(width 0.1016)
		(layer "B.Cu")
		(net "PSU_B1_ALERT_N")
	)
	(segment
		(start -335.534 24.0919)
		(end -335.5594 24.1173)
		(width 0.1016)
		(layer "B.Cu")
		(net "PSU_B1_ALERT_N")
	)
	(segment
		(start -367.2078 19.8628)
		(end -368.808 19.8628)
		(width 0.1016)
		(layer "B.Cu")
		(net "PSU_B1_ALERT_N")
	)
	(segment
		(start -369.697 19.8628)
		(end -370.7384 18.8214)
		(width 0.12954)
		(layer "In2.Cu")
		(net "PSU_B1_ALERT_N")
	)
	(segment
		(start -302.768 36.2458)
		(end -302.768 31.75)
		(width 0.12954)
		(layer "In2.Cu")
		(net "PSU_B1_ALERT_N")
	)
	(segment
		(start -377.240902 17.703698)
		(end -379.27534 15.66926)
		(width 0.12954)
		(layer "In2.Cu")
		(net "PSU_B1_ALERT_N")
	)
	(segment
		(start -335.153 23.7109)
		(end -335.153 21.463)
		(width 0.12954)
		(layer "In2.Cu")
		(net "PSU_B1_ALERT_N")
	)
	(segment
		(start -334.899 6.7564)
		(end -334.899 1.524)
		(width 0.12954)
		(layer "In2.Cu")
		(net "PSU_B1_ALERT_N")
	)
	(segment
		(start -371.144902 17.703698)
		(end -377.240902 17.703698)
		(width 0.12954)
		(layer "In2.Cu")
		(net "PSU_B1_ALERT_N")
	)
	(segment
		(start -335.534 24.0919)
		(end -335.153 23.7109)
		(width 0.12954)
		(layer "In2.Cu")
		(net "PSU_B1_ALERT_N")
	)
	(segment
		(start -305.3334 29.1846)
		(end -305.3334 26.2128)
		(width 0.12954)
		(layer "In2.Cu")
		(net "PSU_B1_ALERT_N")
	)
	(segment
		(start -408.25166 15.66926)
		(end -409.6512 17.0688)
		(width 0.12954)
		(layer "In2.Cu")
		(net "PSU_B1_ALERT_N")
	)
	(segment
		(start -302.0538 36.96)
		(end -302.768 36.2458)
		(width 0.12954)
		(layer "In2.Cu")
		(net "PSU_B1_ALERT_N")
	)
	(segment
		(start -336.0674 7.9248)
		(end -334.899 6.7564)
		(width 0.12954)
		(layer "In2.Cu")
		(net "PSU_B1_ALERT_N")
	)
	(segment
		(start -370.7384 18.1102)
		(end -371.144902 17.703698)
		(width 0.12954)
		(layer "In2.Cu")
		(net "PSU_B1_ALERT_N")
	)
	(segment
		(start -409.6512 17.0688)
		(end -411.099 17.0688)
		(width 0.12954)
		(layer "In2.Cu")
		(net "PSU_B1_ALERT_N")
	)
	(segment
		(start -336.0674 20.5486)
		(end -336.0674 7.9248)
		(width 0.12954)
		(layer "In2.Cu")
		(net "PSU_B1_ALERT_N")
	)
	(segment
		(start -379.27534 15.66926)
		(end -408.25166 15.66926)
		(width 0.12954)
		(layer "In2.Cu")
		(net "PSU_B1_ALERT_N")
	)
	(segment
		(start -302.768 31.75)
		(end -305.3334 29.1846)
		(width 0.12954)
		(layer "In2.Cu")
		(net "PSU_B1_ALERT_N")
	)
	(segment
		(start -370.7384 18.8214)
		(end -370.7384 18.1102)
		(width 0.12954)
		(layer "In2.Cu")
		(net "PSU_B1_ALERT_N")
	)
	(segment
		(start -335.153 21.463)
		(end -336.0674 20.5486)
		(width 0.12954)
		(layer "In2.Cu")
		(net "PSU_B1_ALERT_N")
	)
	(segment
		(start -302.04 36.96)
		(end -302.0538 36.96)
		(width 0.12954)
		(layer "In2.Cu")
		(net "PSU_B1_ALERT_N")
	)
	(segment
		(start -368.808 19.8628)
		(end -369.697 19.8628)
		(width 0.12954)
		(layer "In2.Cu")
		(net "PSU_B1_ALERT_N")
	)
	(segment
		(start -405.384 23.7998)
		(end -405.7396 23.4442)
		(width 0.12954)
		(layer "In3.Cu")
		(net "PSU_B1_ALERT_N")
	)
	(segment
		(start -404.468 35.46)
		(end -405.384 34.544)
		(width 0.12954)
		(layer "In3.Cu")
		(net "PSU_B1_ALERT_N")
	)
	(segment
		(start -410.1846 17.9832)
		(end -411.099 17.0688)
		(width 0.12954)
		(layer "In3.Cu")
		(net "PSU_B1_ALERT_N")
	)
	(segment
		(start -405.7396 23.4442)
		(end -407.4668 23.4442)
		(width 0.12954)
		(layer "In3.Cu")
		(net "PSU_B1_ALERT_N")
	)
	(segment
		(start -404.459999 35.46)
		(end -404.468 35.46)
		(width 0.12954)
		(layer "In3.Cu")
		(net "PSU_B1_ALERT_N")
	)
	(segment
		(start -410.1846 20.7264)
		(end -410.1846 17.9832)
		(width 0.12954)
		(layer "In3.Cu")
		(net "PSU_B1_ALERT_N")
	)
	(segment
		(start -405.384 34.544)
		(end -405.384 23.7998)
		(width 0.12954)
		(layer "In3.Cu")
		(net "PSU_B1_ALERT_N")
	)
	(segment
		(start -407.4668 23.4442)
		(end -410.1846 20.7264)
		(width 0.12954)
		(layer "In3.Cu")
		(net "PSU_B1_ALERT_N")
	)
	(segment
		(start -412.1912 16.5354)
		(end -412.66872 16.05788)
		(width 0.1016)
		(layer "F.Cu")
		(net "BLADE_B1_EN1")
	)
	(segment
		(start -254.71374 33.79216)
		(end -254.71374 41.626262)
		(width 0.1016)
		(layer "F.Cu")
		(net "BLADE_B1_EN1")
	)
	(segment
		(start -254.71374 41.626262)
		(end -253.680001 42.660001)
		(width 0.1016)
		(layer "F.Cu")
		(net "BLADE_B1_EN1")
	)
	(segment
		(start -293.2176 27.4066)
		(end -293.2176 28.4988)
		(width 0.1016)
		(layer "F.Cu")
		(net "BLADE_B1_EN1")
	)
	(segment
		(start -296.040002 35.613802)
		(end -296.040002 35.66)
		(width 0.1016)
		(layer "F.Cu")
		(net "BLADE_B1_EN1")
	)
	(segment
		(start -411.8864 16.5354)
		(end -412.1912 16.5354)
		(width 0.1016)
		(layer "F.Cu")
		(net "BLADE_B1_EN1")
	)
	(segment
		(start -331.9399 23.5839)
		(end -331.9399 24.13)
		(width 0.1016)
		(layer "F.Cu")
		(net "BLADE_B1_EN1")
	)
	(segment
		(start -262.596122 32.658304)
		(end -262.043418 32.1056)
		(width 0.1016)
		(layer "F.Cu")
		(net "BLADE_B1_EN1")
	)
	(segment
		(start -412.16072 14.6177)
		(end -412.16072 7.80288)
		(width 0.1016)
		(layer "F.Cu")
		(net "BLADE_B1_EN1")
	)
	(segment
		(start -412.66872 15.1257)
		(end -412.16072 14.6177)
		(width 0.1016)
		(layer "F.Cu")
		(net "BLADE_B1_EN1")
	)
	(segment
		(start -412.66872 16.05788)
		(end -412.66872 15.1257)
		(width 0.1016)
		(layer "F.Cu")
		(net "BLADE_B1_EN1")
	)
	(segment
		(start -329.0316 1.8542)
		(end -329.0316 3.4036)
		(width 0.1016)
		(layer "F.Cu")
		(net "BLADE_B1_EN1")
	)
	(segment
		(start -330.2889 22.479)
		(end -330.835 22.479)
		(width 0.1016)
		(layer "F.Cu")
		(net "BLADE_B1_EN1")
	)
	(segment
		(start -296.9514 34.702405)
		(end -296.040002 35.613802)
		(width 0.1016)
		(layer "F.Cu")
		(net "BLADE_B1_EN1")
	)
	(segment
		(start -293.2176 28.4988)
		(end -296.9514 32.2326)
		(width 0.1016)
		(layer "F.Cu")
		(net "BLADE_B1_EN1")
	)
	(segment
		(start -412.16072 7.80288)
		(end -416.43 3.5336)
		(width 0.1016)
		(layer "F.Cu")
		(net "BLADE_B1_EN1")
	)
	(segment
		(start -330.835 22.479)
		(end -331.9399 23.5839)
		(width 0.1016)
		(layer "F.Cu")
		(net "BLADE_B1_EN1")
	)
	(segment
		(start -296.9514 32.2326)
		(end -296.9514 34.702405)
		(width 0.1016)
		(layer "F.Cu")
		(net "BLADE_B1_EN1")
	)
	(segment
		(start -416.43 3.5336)
		(end -416.43 -1.840001)
		(width 0.1016)
		(layer "F.Cu")
		(net "BLADE_B1_EN1")
	)
	(segment
		(start -330.0857 1.7526)
		(end -329.1332 1.7526)
		(width 0.1016)
		(layer "F.Cu")
		(net "BLADE_B1_EN1")
	)
	(segment
		(start -262.043418 32.1056)
		(end -256.4003 32.1056)
		(width 0.1016)
		(layer "F.Cu")
		(net "BLADE_B1_EN1")
	)
	(segment
		(start -256.4003 32.1056)
		(end -254.71374 33.79216)
		(width 0.1016)
		(layer "F.Cu")
		(net "BLADE_B1_EN1")
	)
	(segment
		(start -329.1332 1.7526)
		(end -329.0316 1.8542)
		(width 0.1016)
		(layer "F.Cu")
		(net "BLADE_B1_EN1")
	)
	(via
		(at -329.0316 3.4036)
		(size 0.5588)
		(drill 0.254)
		(layers "F.Cu" "B.Cu")
		(net "BLADE_B1_EN1")
	)
	(via
		(at -368.0206 19.3294)
		(size 0.5588)
		(drill 0.254)
		(layers "F.Cu" "B.Cu")
		(net "BLADE_B1_EN1")
	)
	(via
		(at -331.9399 24.13)
		(size 0.5588)
		(drill 0.254)
		(layers "F.Cu" "B.Cu")
		(net "BLADE_B1_EN1")
	)
	(via
		(at -411.8864 16.5354)
		(size 0.5588)
		(drill 0.254)
		(layers "F.Cu" "B.Cu")
		(net "BLADE_B1_EN1")
	)
	(via
		(at -293.2176 27.4066)
		(size 0.5588)
		(drill 0.254)
		(layers "F.Cu" "B.Cu")
		(net "BLADE_B1_EN1")
	)
	(via
		(at -330.2889 22.479)
		(size 0.5588)
		(drill 0.254)
		(layers "F.Cu" "B.Cu")
		(net "BLADE_B1_EN1")
	)
	(via
		(at -262.596122 32.658304)
		(size 0.5588)
		(drill 0.254)
		(layers "F.Cu" "B.Cu")
		(net "BLADE_B1_EN1")
	)
	(segment
		(start -368.0206 19.3294)
		(end -367.2332 19.3294)
		(width 0.1016)
		(layer "B.Cu")
		(net "BLADE_B1_EN1")
	)
	(segment
		(start -290.9062 22.1234)
		(end -288.3408 22.1234)
		(width 0.1016)
		(layer "B.Cu")
		(net "BLADE_B1_EN1")
	)
	(segment
		(start -293.2176 27.4066)
		(end -293.68242 27.87142)
		(width 0.1016)
		(layer "B.Cu")
		(net "BLADE_B1_EN1")
	)
	(segment
		(start -292.4556 26.6446)
		(end -292.4556 23.6728)
		(width 0.1016)
		(layer "B.Cu")
		(net "BLADE_B1_EN1")
	)
	(segment
		(start -305.8922 24.0792)
		(end -320.7258 24.0792)
		(width 0.1016)
		(layer "B.Cu")
		(net "BLADE_B1_EN1")
	)
	(segment
		(start -322.4784 22.3266)
		(end -327.73366 22.3266)
		(width 0.1016)
		(layer "B.Cu")
		(net "BLADE_B1_EN1")
	)
	(segment
		(start -333.248 23.622)
		(end -332.74 24.13)
		(width 0.1016)
		(layer "B.Cu")
		(net "BLADE_B1_EN1")
	)
	(segment
		(start -278.4348 24.3586)
		(end -276.1234 26.67)
		(width 0.1016)
		(layer "B.Cu")
		(net "BLADE_B1_EN1")
	)
	(segment
		(start -327.88606 22.479)
		(end -330.2889 22.479)
		(width 0.1016)
		(layer "B.Cu")
		(net "BLADE_B1_EN1")
	)
	(segment
		(start -332.74 24.13)
		(end -331.9399 24.13)
		(width 0.1016)
		(layer "B.Cu")
		(net "BLADE_B1_EN1")
	)
	(segment
		(start -262.636 32.618426)
		(end -262.596122 32.658304)
		(width 0.1016)
		(layer "B.Cu")
		(net "BLADE_B1_EN1")
	)
	(segment
		(start -262.636 28.956)
		(end -262.636 32.618426)
		(width 0.1016)
		(layer "B.Cu")
		(net "BLADE_B1_EN1")
	)
	(segment
		(start -293.68242 27.87142)
		(end -302.09998 27.87142)
		(width 0.1016)
		(layer "B.Cu")
		(net "BLADE_B1_EN1")
	)
	(segment
		(start -367.2332 19.3294)
		(end -365.4806 17.5768)
		(width 0.1016)
		(layer "B.Cu")
		(net "BLADE_B1_EN1")
	)
	(segment
		(start -292.4556 23.6728)
		(end -290.9062 22.1234)
		(width 0.1016)
		(layer "B.Cu")
		(net "BLADE_B1_EN1")
	)
	(segment
		(start -320.7258 24.0792)
		(end -322.4784 22.3266)
		(width 0.1016)
		(layer "B.Cu")
		(net "BLADE_B1_EN1")
	)
	(segment
		(start -276.1234 26.67)
		(end -264.922 26.67)
		(width 0.1016)
		(layer "B.Cu")
		(net "BLADE_B1_EN1")
	)
	(segment
		(start -264.922 26.67)
		(end -262.636 28.956)
		(width 0.1016)
		(layer "B.Cu")
		(net "BLADE_B1_EN1")
	)
	(segment
		(start -286.1056 24.3586)
		(end -278.4348 24.3586)
		(width 0.1016)
		(layer "B.Cu")
		(net "BLADE_B1_EN1")
	)
	(segment
		(start -302.09998 27.87142)
		(end -305.8922 24.0792)
		(width 0.1016)
		(layer "B.Cu")
		(net "BLADE_B1_EN1")
	)
	(segment
		(start -365.4806 17.5768)
		(end -342.4174 17.5768)
		(width 0.1016)
		(layer "B.Cu")
		(net "BLADE_B1_EN1")
	)
	(segment
		(start -293.2176 27.4066)
		(end -292.4556 26.6446)
		(width 0.1016)
		(layer "B.Cu")
		(net "BLADE_B1_EN1")
	)
	(segment
		(start -288.3408 22.1234)
		(end -286.1056 24.3586)
		(width 0.1016)
		(layer "B.Cu")
		(net "BLADE_B1_EN1")
	)
	(segment
		(start -336.3722 23.622)
		(end -333.248 23.622)
		(width 0.1016)
		(layer "B.Cu")
		(net "BLADE_B1_EN1")
	)
	(segment
		(start -342.4174 17.5768)
		(end -336.3722 23.622)
		(width 0.1016)
		(layer "B.Cu")
		(net "BLADE_B1_EN1")
	)
	(segment
		(start -327.73366 22.3266)
		(end -327.88606 22.479)
		(width 0.1016)
		(layer "B.Cu")
		(net "BLADE_B1_EN1")
	)
	(segment
		(start -331.9399 23.9141)
		(end -331.9399 24.13)
		(width 0.12954)
		(layer "In2.Cu")
		(net "BLADE_B1_EN1")
	)
	(segment
		(start -368.0206 19.3294)
		(end -369.6462 19.3294)
		(width 0.12954)
		(layer "In2.Cu")
		(net "BLADE_B1_EN1")
	)
	(segment
		(start -409.6004 16.5354)
		(end -411.8864 16.5354)
		(width 0.12954)
		(layer "In2.Cu")
		(net "BLADE_B1_EN1")
	)
	(segment
		(start -329.0316 3.4036)
		(end -330.454 3.4036)
		(width 0.12954)
		(layer "In2.Cu")
		(net "BLADE_B1_EN1")
	)
	(segment
		(start -330.454 3.4036)
		(end -335.661 8.6106)
		(width 0.12954)
		(layer "In2.Cu")
		(net "BLADE_B1_EN1")
	)
	(segment
		(start -335.661 20.193)
		(end -331.9399 23.9141)
		(width 0.12954)
		(layer "In2.Cu")
		(net "BLADE_B1_EN1")
	)
	(segment
		(start -373.02948 15.38732)
		(end -408.45232 15.38732)
		(width 0.12954)
		(layer "In2.Cu")
		(net "BLADE_B1_EN1")
	)
	(segment
		(start -370.4082 18.0086)
		(end -373.02948 15.38732)
		(width 0.12954)
		(layer "In2.Cu")
		(net "BLADE_B1_EN1")
	)
	(segment
		(start -408.45232 15.38732)
		(end -409.6004 16.5354)
		(width 0.12954)
		(layer "In2.Cu")
		(net "BLADE_B1_EN1")
	)
	(segment
		(start -335.661 8.6106)
		(end -335.661 20.193)
		(width 0.12954)
		(layer "In2.Cu")
		(net "BLADE_B1_EN1")
	)
	(segment
		(start -370.4082 18.5674)
		(end -370.4082 18.0086)
		(width 0.12954)
		(layer "In2.Cu")
		(net "BLADE_B1_EN1")
	)
	(segment
		(start -369.6462 19.3294)
		(end -370.4082 18.5674)
		(width 0.12954)
		(layer "In2.Cu")
		(net "BLADE_B1_EN1")
	)
	(segment
		(start -202.379946 40.337057)
		(end -201.607001 41.110002)
		(width 0.381)
		(layer "B.Cu")
		(net "P5V_USB_B2")
	)
	(segment
		(start -201.607001 41.110002)
		(end -200.834056 41.882946)
		(width 0.381)
		(layer "B.Cu")
		(net "P5V_USB_B2")
	)
	(segment
		(start -202.379946 41.882946)
		(end -201.607001 41.110002)
		(width 0.381)
		(layer "B.Cu")
		(net "P5V_USB_B2")
	)
	(segment
		(start -201.607001 41.110002)
		(end -200.834056 40.337057)
		(width 0.381)
		(layer "B.Cu")
		(net "P5V_USB_B2")
	)
	(segment
		(start -419.618945 31.633945)
		(end -418.846 30.861)
		(width 0.381)
		(layer "B.Cu")
		(net "P5V_USB_B1")
	)
	(segment
		(start -418.846 30.861)
		(end -418.073055 30.088055)
		(width 0.381)
		(layer "B.Cu")
		(net "P5V_USB_B1")
	)
	(segment
		(start -419.618945 30.088055)
		(end -418.846 30.861)
		(width 0.381)
		(layer "B.Cu")
		(net "P5V_USB_B1")
	)
	(segment
		(start -418.846 30.861)
		(end -418.073055 31.633945)
		(width 0.381)
		(layer "B.Cu")
		(net "P5V_USB_B1")
	)
	(segment
		(start -204.5716 42.6974)
		(end -204.5716 39.116)
		(width 0.127)
		(layer "B.Cu")
		(net "USB_B2_P")
	)
	(segment
		(start -202.454601 37.957603)
		(end -201.607001 37.110002)
		(width 0.127)
		(layer "B.Cu")
		(net "USB_B2_P")
	)
	(segment
		(start -204.5716 39.116)
		(end -203.413203 37.957603)
		(width 0.127)
		(layer "B.Cu")
		(net "USB_B2_P")
	)
	(segment
		(start -189.46 43.960001)
		(end -190.007601 43.4124)
		(width 0.127)
		(layer "B.Cu")
		(net "USB_B2_P")
	)
	(segment
		(start -193.7258 44.45)
		(end -202.819 44.45)
		(width 0.127)
		(layer "B.Cu")
		(net "USB_B2_P")
	)
	(segment
		(start -203.413203 37.957603)
		(end -202.454601 37.957603)
		(width 0.127)
		(layer "B.Cu")
		(net "USB_B2_P")
	)
	(segment
		(start -202.819 44.45)
		(end -204.5716 42.6974)
		(width 0.127)
		(layer "B.Cu")
		(net "USB_B2_P")
	)
	(segment
		(start -192.6882 43.4124)
		(end -193.7258 44.45)
		(width 0.127)
		(layer "B.Cu")
		(net "USB_B2_P")
	)
	(segment
		(start -190.007601 43.4124)
		(end -192.6882 43.4124)
		(width 0.127)
		(layer "B.Cu")
		(net "USB_B2_P")
	)
	(segment
		(start -197.903856 44.1452)
		(end -198.081656 43.9674)
		(width 0.127)
		(layer "B.Cu")
		(net "USB_B2_N")
	)
	(segment
		(start -200.520056 43.9674)
		(end -200.951856 43.9674)
		(width 0.127)
		(layer "B.Cu")
		(net "USB_B2_N")
	)
	(segment
		(start -204.2668 39.242253)
		(end -203.286949 38.262403)
		(width 0.127)
		(layer "B.Cu")
		(net "USB_B2_N")
	)
	(segment
		(start -204.089 41.299653)
		(end -204.089 40.867853)
		(width 0.127)
		(layer "B.Cu")
		(net "USB_B2_N")
	)
	(segment
		(start -199.732656 43.9674)
		(end -199.910456 44.1452)
		(width 0.127)
		(layer "B.Cu")
		(net "USB_B2_N")
	)
	(segment
		(start -204.00693 42.831017)
		(end -204.2668 42.571147)
		(width 0.127)
		(layer "B.Cu")
		(net "USB_B2_N")
	)
	(segment
		(start -198.691256 44.1452)
		(end -199.123056 44.1452)
		(width 0.127)
		(layer "B.Cu")
		(net "USB_B2_N")
	)
	(segment
		(start -204.2668 39.470853)
		(end -204.2668 39.242253)
		(width 0.127)
		(layer "B.Cu")
		(net "USB_B2_N")
	)
	(segment
		(start -192.814453 43.1076)
		(end -193.852053 44.1452)
		(width 0.127)
		(layer "B.Cu")
		(net "USB_B2_N")
	)
	(segment
		(start -190.007598 43.1076)
		(end -192.814453 43.1076)
		(width 0.127)
		(layer "B.Cu")
		(net "USB_B2_N")
	)
	(segment
		(start -198.513456 43.9674)
		(end -198.691256 44.1452)
		(width 0.127)
		(layer "B.Cu")
		(net "USB_B2_N")
	)
	(segment
		(start -204.089 40.080453)
		(end -204.089 39.648653)
		(width 0.127)
		(layer "B.Cu")
		(net "USB_B2_N")
	)
	(segment
		(start -204.089 39.648653)
		(end -204.2668 39.470853)
		(width 0.127)
		(layer "B.Cu")
		(net "USB_B2_N")
	)
	(segment
		(start -199.300856 43.9674)
		(end -199.732656 43.9674)
		(width 0.127)
		(layer "B.Cu")
		(net "USB_B2_N")
	)
	(segment
		(start -200.951856 43.9674)
		(end -201.129656 44.1452)
		(width 0.127)
		(layer "B.Cu")
		(net "USB_B2_N")
	)
	(segment
		(start -204.2668 40.690053)
		(end -204.2668 40.258253)
		(width 0.127)
		(layer "B.Cu")
		(net "USB_B2_N")
	)
	(segment
		(start -202.692747 44.1452)
		(end -203.472258 43.365689)
		(width 0.127)
		(layer "B.Cu")
		(net "USB_B2_N")
	)
	(segment
		(start -199.910456 44.1452)
		(end -200.342256 44.1452)
		(width 0.127)
		(layer "B.Cu")
		(net "USB_B2_N")
	)
	(segment
		(start -204.2668 42.571147)
		(end -204.2668 41.477453)
		(width 0.127)
		(layer "B.Cu")
		(net "USB_B2_N")
	)
	(segment
		(start -201.129656 44.1452)
		(end -201.561456 44.1452)
		(width 0.127)
		(layer "B.Cu")
		(net "USB_B2_N")
	)
	(segment
		(start -204.2668 40.258253)
		(end -204.089 40.080453)
		(width 0.127)
		(layer "B.Cu")
		(net "USB_B2_N")
	)
	(segment
		(start -203.777588 42.831017)
		(end -204.00693 42.831017)
		(width 0.127)
		(layer "B.Cu")
		(net "USB_B2_N")
	)
	(segment
		(start -203.472258 43.136348)
		(end -203.777588 42.831017)
		(width 0.127)
		(layer "B.Cu")
		(net "USB_B2_N")
	)
	(segment
		(start -198.081656 43.9674)
		(end -198.513456 43.9674)
		(width 0.127)
		(layer "B.Cu")
		(net "USB_B2_N")
	)
	(segment
		(start -199.123056 44.1452)
		(end -199.300856 43.9674)
		(width 0.127)
		(layer "B.Cu")
		(net "USB_B2_N")
	)
	(segment
		(start -201.739256 43.9674)
		(end -202.171056 43.9674)
		(width 0.127)
		(layer "B.Cu")
		(net "USB_B2_N")
	)
	(segment
		(start -189.46 42.560001)
		(end -190.007598 43.1076)
		(width 0.127)
		(layer "B.Cu")
		(net "USB_B2_N")
	)
	(segment
		(start -202.171056 43.9674)
		(end -202.348856 44.1452)
		(width 0.127)
		(layer "B.Cu")
		(net "USB_B2_N")
	)
	(segment
		(start -200.342256 44.1452)
		(end -200.520056 43.9674)
		(width 0.127)
		(layer "B.Cu")
		(net "USB_B2_N")
	)
	(segment
		(start -202.454599 38.262403)
		(end -201.607001 39.110001)
		(width 0.127)
		(layer "B.Cu")
		(net "USB_B2_N")
	)
	(segment
		(start -193.852053 44.1452)
		(end -197.903856 44.1452)
		(width 0.127)
		(layer "B.Cu")
		(net "USB_B2_N")
	)
	(segment
		(start -203.472258 43.365689)
		(end -203.472258 43.136348)
		(width 0.127)
		(layer "B.Cu")
		(net "USB_B2_N")
	)
	(segment
		(start -201.561456 44.1452)
		(end -201.739256 43.9674)
		(width 0.127)
		(layer "B.Cu")
		(net "USB_B2_N")
	)
	(segment
		(start -202.348856 44.1452)
		(end -202.692747 44.1452)
		(width 0.127)
		(layer "B.Cu")
		(net "USB_B2_N")
	)
	(segment
		(start -204.089 40.867853)
		(end -204.2668 40.690053)
		(width 0.127)
		(layer "B.Cu")
		(net "USB_B2_N")
	)
	(segment
		(start -204.2668 41.477453)
		(end -204.089 41.299653)
		(width 0.127)
		(layer "B.Cu")
		(net "USB_B2_N")
	)
	(segment
		(start -203.286949 38.262403)
		(end -202.454599 38.262403)
		(width 0.127)
		(layer "B.Cu")
		(net "USB_B2_N")
	)
	(segment
		(start -415.518458 37.744542)
		(end -413.1564 40.1066)
		(width 0.127)
		(layer "B.Cu")
		(net "USB_B1_P")
	)
	(segment
		(start -413.1564 42.008313)
		(end -411.752311 43.412402)
		(width 0.127)
		(layer "B.Cu")
		(net "USB_B1_P")
	)
	(segment
		(start -421.3606 28.575)
		(end -421.3606 31.952453)
		(width 0.127)
		(layer "B.Cu")
		(net "USB_B1_P")
	)
	(segment
		(start -413.1564 40.1066)
		(end -413.1564 42.008313)
		(width 0.127)
		(layer "B.Cu")
		(net "USB_B1_P")
	)
	(segment
		(start -420.494201 27.708601)
		(end -421.3606 28.575)
		(width 0.127)
		(layer "B.Cu")
		(net "USB_B1_P")
	)
	(segment
		(start -421.3606 31.952453)
		(end -419.937453 33.3756)
		(width 0.127)
		(layer "B.Cu")
		(net "USB_B1_P")
	)
	(segment
		(start -419.937453 33.3756)
		(end -417.3982 33.3756)
		(width 0.127)
		(layer "B.Cu")
		(net "USB_B1_P")
	)
	(segment
		(start -417.3982 33.3756)
		(end -415.518458 35.255342)
		(width 0.127)
		(layer "B.Cu")
		(net "USB_B1_P")
	)
	(segment
		(start -419.693601 27.708601)
		(end -420.494201 27.708601)
		(width 0.127)
		(layer "B.Cu")
		(net "USB_B1_P")
	)
	(segment
		(start -418.846 26.861)
		(end -419.693601 27.708601)
		(width 0.127)
		(layer "B.Cu")
		(net "USB_B1_P")
	)
	(segment
		(start -415.518458 35.255342)
		(end -415.518458 37.744542)
		(width 0.127)
		(layer "B.Cu")
		(net "USB_B1_P")
	)
	(segment
		(start -411.007598 43.412402)
		(end -410.46 43.960001)
		(width 0.127)
		(layer "B.Cu")
		(net "USB_B1_P")
	)
	(segment
		(start -411.752311 43.412402)
		(end -411.007598 43.412402)
		(width 0.127)
		(layer "B.Cu")
		(net "USB_B1_P")
	)
	(segment
		(start -419.693598 28.013401)
		(end -420.367948 28.013401)
		(width 0.127)
		(layer "B.Cu")
		(net "USB_B1_N")
	)
	(segment
		(start -421.0558 28.929853)
		(end -420.878 29.107653)
		(width 0.127)
		(layer "B.Cu")
		(net "USB_B1_N")
	)
	(segment
		(start -420.367948 28.013401)
		(end -421.0558 28.701253)
		(width 0.127)
		(layer "B.Cu")
		(net "USB_B1_N")
	)
	(segment
		(start -415.213658 35.129089)
		(end -415.213658 35.602598)
		(width 0.127)
		(layer "B.Cu")
		(net "USB_B1_N")
	)
	(segment
		(start -411.626058 43.107602)
		(end -411.007601 43.107602)
		(width 0.127)
		(layer "B.Cu")
		(net "USB_B1_N")
	)
	(segment
		(start -412.8516 39.980347)
		(end -412.8516 40.238863)
		(width 0.127)
		(layer "B.Cu")
		(net "USB_B1_N")
	)
	(segment
		(start -421.0558 31.8262)
		(end -419.8112 33.0708)
		(width 0.127)
		(layer "B.Cu")
		(net "USB_B1_N")
	)
	(segment
		(start -415.035858 36.212198)
		(end -415.213658 36.389998)
		(width 0.127)
		(layer "B.Cu")
		(net "USB_B1_N")
	)
	(segment
		(start -418.12148 32.893)
		(end -417.74048 32.893)
		(width 0.127)
		(layer "B.Cu")
		(net "USB_B1_N")
	)
	(segment
		(start -416.303747 33.809653)
		(end -416.303747 34.039)
		(width 0.127)
		(layer "B.Cu")
		(net "USB_B1_N")
	)
	(segment
		(start -418.846 28.860999)
		(end -419.693598 28.013401)
		(width 0.127)
		(layer "B.Cu")
		(net "USB_B1_N")
	)
	(segment
		(start -411.007601 43.107602)
		(end -410.46 42.560001)
		(width 0.127)
		(layer "B.Cu")
		(net "USB_B1_N")
	)
	(segment
		(start -415.213658 37.618289)
		(end -412.8516 39.980347)
		(width 0.127)
		(layer "B.Cu")
		(net "USB_B1_N")
	)
	(segment
		(start -412.8516 41.127863)
		(end -412.8516 41.88206)
		(width 0.127)
		(layer "B.Cu")
		(net "USB_B1_N")
	)
	(segment
		(start -412.345381 42.162219)
		(end -411.938452 42.569148)
		(width 0.127)
		(layer "B.Cu")
		(net "USB_B1_N")
	)
	(segment
		(start -412.6738 40.416663)
		(end -412.6738 40.950063)
		(width 0.127)
		(layer "B.Cu")
		(net "USB_B1_N")
	)
	(segment
		(start -415.035858 35.780398)
		(end -415.035858 36.212198)
		(width 0.127)
		(layer "B.Cu")
		(net "USB_B1_N")
	)
	(segment
		(start -416.634475 33.478925)
		(end -416.303747 33.809653)
		(width 0.127)
		(layer "B.Cu")
		(net "USB_B1_N")
	)
	(segment
		(start -417.74048 32.893)
		(end -417.56268 33.0708)
		(width 0.127)
		(layer "B.Cu")
		(net "USB_B1_N")
	)
	(segment
		(start -411.938452 42.569148)
		(end -411.938452 42.795208)
		(width 0.127)
		(layer "B.Cu")
		(net "USB_B1_N")
	)
	(segment
		(start -416.303747 34.039)
		(end -415.213658 35.129089)
		(width 0.127)
		(layer "B.Cu")
		(net "USB_B1_N")
	)
	(segment
		(start -412.571441 42.162219)
		(end -412.345381 42.162219)
		(width 0.127)
		(layer "B.Cu")
		(net "USB_B1_N")
	)
	(segment
		(start -415.213658 35.602598)
		(end -415.035858 35.780398)
		(width 0.127)
		(layer "B.Cu")
		(net "USB_B1_N")
	)
	(segment
		(start -411.938452 42.795208)
		(end -411.626058 43.107602)
		(width 0.127)
		(layer "B.Cu")
		(net "USB_B1_N")
	)
	(segment
		(start -412.8516 40.238863)
		(end -412.6738 40.416663)
		(width 0.127)
		(layer "B.Cu")
		(net "USB_B1_N")
	)
	(segment
		(start -419.5826 33.0708)
		(end -419.4048 32.893)
		(width 0.127)
		(layer "B.Cu")
		(net "USB_B1_N")
	)
	(segment
		(start -419.8112 33.0708)
		(end -419.5826 33.0708)
		(width 0.127)
		(layer "B.Cu")
		(net "USB_B1_N")
	)
	(segment
		(start -420.878 29.107653)
		(end -420.878 29.590253)
		(width 0.127)
		(layer "B.Cu")
		(net "USB_B1_N")
	)
	(segment
		(start -421.0558 29.768053)
		(end -421.0558 31.8262)
		(width 0.127)
		(layer "B.Cu")
		(net "USB_B1_N")
	)
	(segment
		(start -412.6738 40.950063)
		(end -412.8516 41.127863)
		(width 0.127)
		(layer "B.Cu")
		(net "USB_B1_N")
	)
	(segment
		(start -420.878 29.590253)
		(end -421.0558 29.768053)
		(width 0.127)
		(layer "B.Cu")
		(net "USB_B1_N")
	)
	(segment
		(start -412.8516 41.88206)
		(end -412.571441 42.162219)
		(width 0.127)
		(layer "B.Cu")
		(net "USB_B1_N")
	)
	(segment
		(start -417.56268 33.0708)
		(end -417.271947 33.0708)
		(width 0.127)
		(layer "B.Cu")
		(net "USB_B1_N")
	)
	(segment
		(start -421.0558 28.701253)
		(end -421.0558 28.929853)
		(width 0.127)
		(layer "B.Cu")
		(net "USB_B1_N")
	)
	(segment
		(start -416.863822 33.478925)
		(end -416.634475 33.478925)
		(width 0.127)
		(layer "B.Cu")
		(net "USB_B1_N")
	)
	(segment
		(start -418.973 32.893)
		(end -418.7952 33.0708)
		(width 0.127)
		(layer "B.Cu")
		(net "USB_B1_N")
	)
	(segment
		(start -418.29928 33.0708)
		(end -418.12148 32.893)
		(width 0.127)
		(layer "B.Cu")
		(net "USB_B1_N")
	)
	(segment
		(start -418.7952 33.0708)
		(end -418.29928 33.0708)
		(width 0.127)
		(layer "B.Cu")
		(net "USB_B1_N")
	)
	(segment
		(start -415.213658 36.389998)
		(end -415.213658 37.618289)
		(width 0.127)
		(layer "B.Cu")
		(net "USB_B1_N")
	)
	(segment
		(start -417.271947 33.0708)
		(end -416.863822 33.478925)
		(width 0.127)
		(layer "B.Cu")
		(net "USB_B1_N")
	)
	(segment
		(start -419.4048 32.893)
		(end -418.973 32.893)
		(width 0.127)
		(layer "B.Cu")
		(net "USB_B1_N")
	)
	(segment
		(start -165.0238 30.541199)
		(end -165.0238 29.7688)
		(width 0.127)
		(layer "F.Cu")
		(net "BLADE_MATED_B2_N<0>")
	)
	(via
		(at -165.0238 29.7688)
		(size 0.5588)
		(drill 0.254)
		(layers "F.Cu" "B.Cu")
		(net "BLADE_MATED_B2_N<0>")
	)
	(segment
		(start -170.6934 46.2534)
		(end -180.0987 46.2534)
		(width 0.12954)
		(layer "In3.Cu")
		(net "BLADE_MATED_B2_N<0>")
	)
	(segment
		(start -180.0987 46.2534)
		(end -180.447 45.9051)
		(width 0.12954)
		(layer "In3.Cu")
		(net "BLADE_MATED_B2_N<0>")
	)
	(segment
		(start -169.8244 37.1348)
		(end -169.8244 45.3844)
		(width 0.12954)
		(layer "In3.Cu")
		(net "BLADE_MATED_B2_N<0>")
	)
	(segment
		(start -180.447 45.9051)
		(end -180.447 35.179)
		(width 0.12954)
		(layer "In3.Cu")
		(net "BLADE_MATED_B2_N<0>")
	)
	(segment
		(start -165.0238 29.7688)
		(end -169.1894 33.9344)
		(width 0.12954)
		(layer "In3.Cu")
		(net "BLADE_MATED_B2_N<0>")
	)
	(segment
		(start -169.1894 33.9344)
		(end -169.1894 36.4998)
		(width 0.12954)
		(layer "In3.Cu")
		(net "BLADE_MATED_B2_N<0>")
	)
	(segment
		(start -169.1894 36.4998)
		(end -169.8244 37.1348)
		(width 0.12954)
		(layer "In3.Cu")
		(net "BLADE_MATED_B2_N<0>")
	)
	(segment
		(start -180.447 35.179)
		(end -181.46 34.166)
		(width 0.12954)
		(layer "In3.Cu")
		(net "BLADE_MATED_B2_N<0>")
	)
	(segment
		(start -169.8244 45.3844)
		(end -170.6934 46.2534)
		(width 0.12954)
		(layer "In3.Cu")
		(net "BLADE_MATED_B2_N<0>")
	)
	(segment
		(start -181.46 34.166)
		(end -181.46 34.16)
		(width 0.12954)
		(layer "In3.Cu")
		(net "BLADE_MATED_B2_N<0>")
	)
	(segment
		(start -385.826 30.541199)
		(end -388.604999 30.541199)
		(width 0.1016)
		(layer "F.Cu")
		(net "BLADE_MATED_B1_N<0>")
	)
	(segment
		(start -388.604999 30.541199)
		(end -388.62 30.5562)
		(width 0.1016)
		(layer "F.Cu")
		(net "BLADE_MATED_B1_N<0>")
	)
	(via
		(at -388.62 30.5562)
		(size 0.5588)
		(drill 0.254)
		(layers "F.Cu" "B.Cu")
		(net "BLADE_MATED_B1_N<0>")
	)
	(segment
		(start -401.447 35.179)
		(end -402.46 34.166)
		(width 0.12954)
		(layer "In3.Cu")
		(net "BLADE_MATED_B1_N<0>")
	)
	(segment
		(start -401.0279 46.4058)
		(end -401.447 45.9867)
		(width 0.12954)
		(layer "In3.Cu")
		(net "BLADE_MATED_B1_N<0>")
	)
	(segment
		(start -391.4902 37.0586)
		(end -391.4902 46.0248)
		(width 0.12954)
		(layer "In3.Cu")
		(net "BLADE_MATED_B1_N<0>")
	)
	(segment
		(start -390.398 35.9664)
		(end -391.4902 37.0586)
		(width 0.12954)
		(layer "In3.Cu")
		(net "BLADE_MATED_B1_N<0>")
	)
	(segment
		(start -391.8712 46.4058)
		(end -401.0279 46.4058)
		(width 0.12954)
		(layer "In3.Cu")
		(net "BLADE_MATED_B1_N<0>")
	)
	(segment
		(start -388.62 30.5562)
		(end -390.398 32.3342)
		(width 0.12954)
		(layer "In3.Cu")
		(net "BLADE_MATED_B1_N<0>")
	)
	(segment
		(start -391.4902 46.0248)
		(end -391.8712 46.4058)
		(width 0.12954)
		(layer "In3.Cu")
		(net "BLADE_MATED_B1_N<0>")
	)
	(segment
		(start -390.398 32.3342)
		(end -390.398 35.9664)
		(width 0.12954)
		(layer "In3.Cu")
		(net "BLADE_MATED_B1_N<0>")
	)
	(segment
		(start -401.447 45.9867)
		(end -401.447 35.179)
		(width 0.12954)
		(layer "In3.Cu")
		(net "BLADE_MATED_B1_N<0>")
	)
	(segment
		(start -402.46 34.166)
		(end -402.46 34.16)
		(width 0.12954)
		(layer "In3.Cu")
		(net "BLADE_MATED_B1_N<0>")
	)
	(segment
		(start -44.5008 0.4826)
		(end -44.4754 0.4572)
		(width 0.3048)
		(layer "F.Cu")
		(net "UNNAMED_8_FERRITE_I54_A")
	)
	(segment
		(start -44.5008 0.4318)
		(end -44.5008 -0.251201)
		(width 0.3048)
		(layer "F.Cu")
		(net "UNNAMED_8_FERRITE_I54_A")
	)
	(segment
		(start -44.4754 0.4572)
		(end -44.5008 0.4318)
		(width 0.3048)
		(layer "F.Cu")
		(net "UNNAMED_8_FERRITE_I54_A")
	)
	(segment
		(start -44.5008 -0.251201)
		(end -44.498001 -0.254)
		(width 0.3048)
		(layer "F.Cu")
		(net "UNNAMED_8_FERRITE_I54_A")
	)
	(segment
		(start -44.5008 1.143)
		(end -44.5008 0.4826)
		(width 0.3048)
		(layer "F.Cu")
		(net "UNNAMED_8_FERRITE_I54_A")
	)
	(via
		(at -44.4754 0.4572)
		(size 0.5588)
		(drill 0.254)
		(layers "F.Cu" "B.Cu")
		(net "UNNAMED_8_FERRITE_I54_A")
	)
	(segment
		(start -44.802801 6.8988)
		(end -44.802801 6.223)
		(width 0.3048)
		(layer "F.Cu")
		(net "UNNAMED_8_FERRITE_I51_A")
	)
	(segment
		(start -44.792801 7.582002)
		(end -44.792801 6.9088)
		(width 0.3048)
		(layer "F.Cu")
		(net "UNNAMED_8_FERRITE_I51_A")
	)
	(segment
		(start -44.792801 6.9088)
		(end -44.802801 6.8988)
		(width 0.3048)
		(layer "F.Cu")
		(net "UNNAMED_8_FERRITE_I51_A")
	)
	(via
		(at -44.792801 6.9088)
		(size 0.5588)
		(drill 0.254)
		(layers "F.Cu" "B.Cu")
		(net "UNNAMED_8_FERRITE_I51_A")
	)
	(segment
		(start -46.393001 11.061802)
		(end -45.6692 11.061802)
		(width 0.3048)
		(layer "F.Cu")
		(net "UNNAMED_8_FERRITE_I47_B")
	)
	(segment
		(start -44.9988 11.061802)
		(end -44.996001 11.059003)
		(width 0.3048)
		(layer "F.Cu")
		(net "UNNAMED_8_FERRITE_I47_B")
	)
	(segment
		(start -45.6692 11.061802)
		(end -44.9988 11.061802)
		(width 0.3048)
		(layer "F.Cu")
		(net "UNNAMED_8_FERRITE_I47_B")
	)
	(segment
		(start -45.6692 11.061802)
		(end -45.6692 11.049)
		(width 0.3048)
		(layer "F.Cu")
		(net "UNNAMED_8_FERRITE_I47_B")
	)
	(via
		(at -45.6692 11.049)
		(size 0.5588)
		(drill 0.254)
		(layers "F.Cu" "B.Cu")
		(net "UNNAMED_8_FERRITE_I47_B")
	)
	(segment
		(start -58.153201 45.631202)
		(end -58.089803 45.6946)
		(width 0.3048)
		(layer "F.Cu")
		(net "UNNAMED_6_FERRITE_I27_B")
	)
	(segment
		(start -57.2516 45.6946)
		(end -56.390799 45.6946)
		(width 0.3048)
		(layer "F.Cu")
		(net "UNNAMED_6_FERRITE_I27_B")
	)
	(segment
		(start -57.2516 45.6946)
		(end -57.2516 45.6692)
		(width 0.3048)
		(layer "F.Cu")
		(net "UNNAMED_6_FERRITE_I27_B")
	)
	(segment
		(start -58.089803 45.6946)
		(end -57.2516 45.6946)
		(width 0.3048)
		(layer "F.Cu")
		(net "UNNAMED_6_FERRITE_I27_B")
	)
	(via
		(at -57.2516 45.6692)
		(size 0.5588)
		(drill 0.254)
		(layers "F.Cu" "B.Cu")
		(net "UNNAMED_6_FERRITE_I27_B")
	)
	(segment
		(start -65.503801 45.72)
		(end -64.7192 45.72)
		(width 0.3048)
		(layer "F.Cu")
		(net "UNNAMED_6_FERRITE_I24_A")
	)
	(segment
		(start -64.7192 45.72)
		(end -63.9318 45.72)
		(width 0.3048)
		(layer "F.Cu")
		(net "UNNAMED_6_FERRITE_I24_A")
	)
	(via
		(at -64.7192 45.72)
		(size 0.5588)
		(drill 0.254)
		(layers "F.Cu" "B.Cu")
		(net "UNNAMED_6_FERRITE_I24_A")
	)
	(segment
		(start -123.551 4.074399)
		(end -123.540601 4.064)
		(width 0.3048)
		(layer "F.Cu")
		(net "UNNAMED_6_1X2HDR_I56_IO")
	)
	(segment
		(start -123.540601 4.064)
		(end -119.8299 4.064)
		(width 0.3048)
		(layer "F.Cu")
		(net "UNNAMED_6_1X2HDR_I56_IO")
	)
	(segment
		(start -112.021701 4.277599)
		(end -112.0067 4.2926)
		(width 0.3048)
		(layer "F.Cu")
		(net "UNNAMED_6_1X2HDR_I52_IO")
	)
	(segment
		(start -115.423 4.277599)
		(end -112.021701 4.277599)
		(width 0.3048)
		(layer "F.Cu")
		(net "UNNAMED_6_1X2HDR_I52_IO")
	)
	(segment
		(start -278.2824 45.6184)
		(end -278.295202 45.631202)
		(width 0.3048)
		(layer "F.Cu")
		(net "UNNAMED_4_FERRITE_I151_B")
	)
	(segment
		(start -278.295202 45.631202)
		(end -279.153201 45.631202)
		(width 0.3048)
		(layer "F.Cu")
		(net "UNNAMED_4_FERRITE_I151_B")
	)
	(segment
		(start -277.396199 45.6438)
		(end -278.257 45.6438)
		(width 0.3048)
		(layer "F.Cu")
		(net "UNNAMED_4_FERRITE_I151_B")
	)
	(segment
		(start -278.257 45.6438)
		(end -278.2824 45.6184)
		(width 0.3048)
		(layer "F.Cu")
		(net "UNNAMED_4_FERRITE_I151_B")
	)
	(via
		(at -278.2824 45.6184)
		(size 0.5588)
		(drill 0.254)
		(layers "F.Cu" "B.Cu")
		(net "UNNAMED_4_FERRITE_I151_B")
	)
	(segment
		(start -285.6738 45.72)
		(end -285.6992 45.6946)
		(width 0.3048)
		(layer "F.Cu")
		(net "UNNAMED_4_FERRITE_I148_A")
	)
	(segment
		(start -284.9372 45.72)
		(end -285.6738 45.72)
		(width 0.3048)
		(layer "F.Cu")
		(net "UNNAMED_4_FERRITE_I148_A")
	)
	(segment
		(start -285.6992 45.6946)
		(end -286.433001 45.6946)
		(width 0.3048)
		(layer "F.Cu")
		(net "UNNAMED_4_FERRITE_I148_A")
	)
	(via
		(at -285.6738 45.72)
		(size 0.5588)
		(drill 0.254)
		(layers "F.Cu" "B.Cu")
		(net "UNNAMED_4_FERRITE_I148_A")
	)
	(segment
		(start -340.840299 4.074399)
		(end -340.8299 4.064)
		(width 0.3048)
		(layer "F.Cu")
		(net "UNNAMED_4_1X2HDR_I90_IO")
	)
	(segment
		(start -344.551 4.074399)
		(end -340.840299 4.074399)
		(width 0.3048)
		(layer "F.Cu")
		(net "UNNAMED_4_1X2HDR_I90_IO")
	)
	(segment
		(start -336.423 4.277599)
		(end -333.021701 4.277599)
		(width 0.3048)
		(layer "F.Cu")
		(net "UNNAMED_4_1X2HDR_I81_IO")
	)
	(segment
		(start -333.021701 4.277599)
		(end -333.0067 4.2926)
		(width 0.3048)
		(layer "F.Cu")
		(net "UNNAMED_4_1X2HDR_I81_IO")
	)
	(segment
		(start -267.017398 11.188802)
		(end -267.774001 11.188802)
		(width 0.3048)
		(layer "F.Cu")
		(net "UNNAMED_16_FERRITE_I46_B")
	)
	(segment
		(start -266.976601 11.173201)
		(end -267.0048 11.2014)
		(width 0.3048)
		(layer "F.Cu")
		(net "UNNAMED_16_FERRITE_I46_B")
	)
	(segment
		(start -267.0048 11.2014)
		(end -267.017398 11.188802)
		(width 0.3048)
		(layer "F.Cu")
		(net "UNNAMED_16_FERRITE_I46_B")
	)
	(segment
		(start -266.192 11.173201)
		(end -266.976601 11.173201)
		(width 0.3048)
		(layer "F.Cu")
		(net "UNNAMED_16_FERRITE_I46_B")
	)
	(via
		(at -267.0048 11.2014)
		(size 0.5588)
		(drill 0.254)
		(layers "F.Cu" "B.Cu")
		(net "UNNAMED_16_FERRITE_I46_B")
	)
	(segment
		(start -266.0142 0.6858)
		(end -265.986001 0.657601)
		(width 0.381)
		(layer "F.Cu")
		(net "UNNAMED_16_FERRITE_I40_A")
	)
	(segment
		(start -265.9888 1.3716)
		(end -265.9888 0.7112)
		(width 0.381)
		(layer "F.Cu")
		(net "UNNAMED_16_FERRITE_I40_A")
	)
	(segment
		(start -265.9888 0.7112)
		(end -266.0142 0.6858)
		(width 0.381)
		(layer "F.Cu")
		(net "UNNAMED_16_FERRITE_I40_A")
	)
	(segment
		(start -265.986001 0.657601)
		(end -265.986001 0)
		(width 0.381)
		(layer "F.Cu")
		(net "UNNAMED_16_FERRITE_I40_A")
	)
	(via
		(at -266.0142 0.6858)
		(size 0.5588)
		(drill 0.254)
		(layers "F.Cu" "B.Cu")
		(net "UNNAMED_16_FERRITE_I40_A")
	)
	(segment
		(start -266.011401 5.842)
		(end -266.011401 6.6802)
		(width 0.3048)
		(layer "F.Cu")
		(net "UNNAMED_16_FERRITE_I115_A")
	)
	(segment
		(start -266.011401 6.6802)
		(end -265.9888 6.702801)
		(width 0.3048)
		(layer "F.Cu")
		(net "UNNAMED_16_FERRITE_I115_A")
	)
	(segment
		(start -265.9888 6.702801)
		(end -265.9888 7.4676)
		(width 0.3048)
		(layer "F.Cu")
		(net "UNNAMED_16_FERRITE_I115_A")
	)
	(via
		(at -266.011401 6.6802)
		(size 0.5588)
		(drill 0.254)
		(layers "F.Cu" "B.Cu")
		(net "UNNAMED_16_FERRITE_I115_A")
	)
	(segment
		(start -110.195599 17.4244)
		(end -110.195599 18.8214)
		(width 0.1016)
		(layer "F.Cu")
		(net "SKU_B2_ID2")
	)
	(segment
		(start -110.195599 18.8214)
		(end -110.195599 20.2184)
		(width 0.1016)
		(layer "F.Cu")
		(net "SKU_B2_ID2")
	)
	(segment
		(start -109.1946 20.2184)
		(end -110.195599 20.2184)
		(width 0.1016)
		(layer "F.Cu")
		(net "SKU_B2_ID2")
	)
	(via
		(at -71.7042 28.8798)
		(size 0.5588)
		(drill 0.254)
		(layers "F.Cu" "B.Cu")
		(net "SKU_B2_ID2")
	)
	(via
		(at -109.1946 20.2184)
		(size 0.5588)
		(drill 0.254)
		(layers "F.Cu" "B.Cu")
		(net "SKU_B2_ID2")
	)
	(segment
		(start -81.661 25.0952)
		(end -79.22006 27.53614)
		(width 0.1016)
		(layer "B.Cu")
		(net "SKU_B2_ID2")
	)
	(segment
		(start -104.6734 20.2184)
		(end -99.7966 25.0952)
		(width 0.1016)
		(layer "B.Cu")
		(net "SKU_B2_ID2")
	)
	(segment
		(start -99.7966 25.0952)
		(end -81.661 25.0952)
		(width 0.1016)
		(layer "B.Cu")
		(net "SKU_B2_ID2")
	)
	(segment
		(start -73.787 28.194)
		(end -72.39 28.194)
		(width 0.1016)
		(layer "B.Cu")
		(net "SKU_B2_ID2")
	)
	(segment
		(start -72.39 28.194)
		(end -71.7042 28.8798)
		(width 0.1016)
		(layer "B.Cu")
		(net "SKU_B2_ID2")
	)
	(segment
		(start -109.1946 20.2184)
		(end -104.6734 20.2184)
		(width 0.1016)
		(layer "B.Cu")
		(net "SKU_B2_ID2")
	)
	(segment
		(start -74.44486 27.53614)
		(end -73.787 28.194)
		(width 0.1016)
		(layer "B.Cu")
		(net "SKU_B2_ID2")
	)
	(segment
		(start -79.22006 27.53614)
		(end -74.44486 27.53614)
		(width 0.1016)
		(layer "B.Cu")
		(net "SKU_B2_ID2")
	)
	(segment
		(start -71.7042 31.7754)
		(end -71.7042 28.8798)
		(width 0.12954)
		(layer "In2.Cu")
		(net "SKU_B2_ID2")
	)
	(segment
		(start -73.8632 37.2832)
		(end -73.8632 33.9344)
		(width 0.12954)
		(layer "In2.Cu")
		(net "SKU_B2_ID2")
	)
	(segment
		(start -73.8632 33.9344)
		(end -71.7042 31.7754)
		(width 0.12954)
		(layer "In2.Cu")
		(net "SKU_B2_ID2")
	)
	(segment
		(start -75.040002 38.460002)
		(end -73.8632 37.2832)
		(width 0.12954)
		(layer "In2.Cu")
		(net "SKU_B2_ID2")
	)
	(segment
		(start -78.359 9.2456)
		(end -79.436199 9.2456)
		(width 0.1016)
		(layer "F.Cu")
		(net "SKU_B2_ID1")
	)
	(segment
		(start -79.436199 7.8486)
		(end -79.436199 9.2456)
		(width 0.1016)
		(layer "F.Cu")
		(net "SKU_B2_ID1")
	)
	(via
		(at -78.359 9.2456)
		(size 0.5588)
		(drill 0.254)
		(layers "F.Cu" "B.Cu")
		(net "SKU_B2_ID1")
	)
	(segment
		(start -78.2828 33.502798)
		(end -79.040002 34.26)
		(width 0.12954)
		(layer "In2.Cu")
		(net "SKU_B2_ID1")
	)
	(segment
		(start -78.359 9.2456)
		(end -78.359 11.5062)
		(width 0.12954)
		(layer "In2.Cu")
		(net "SKU_B2_ID1")
	)
	(segment
		(start -78.0288 12.3952)
		(end -78.8162 13.1826)
		(width 0.12954)
		(layer "In2.Cu")
		(net "SKU_B2_ID1")
	)
	(segment
		(start -79.7306 13.1826)
		(end -82.8548 16.3068)
		(width 0.12954)
		(layer "In2.Cu")
		(net "SKU_B2_ID1")
	)
	(segment
		(start -78.359 11.5062)
		(end -78.0288 11.8364)
		(width 0.12954)
		(layer "In2.Cu")
		(net "SKU_B2_ID1")
	)
	(segment
		(start -78.2828 28.829)
		(end -78.2828 33.502798)
		(width 0.12954)
		(layer "In2.Cu")
		(net "SKU_B2_ID1")
	)
	(segment
		(start -82.8548 16.3068)
		(end -82.8548 24.257)
		(width 0.12954)
		(layer "In2.Cu")
		(net "SKU_B2_ID1")
	)
	(segment
		(start -82.8548 24.257)
		(end -78.2828 28.829)
		(width 0.12954)
		(layer "In2.Cu")
		(net "SKU_B2_ID1")
	)
	(segment
		(start -78.0288 11.8364)
		(end -78.0288 12.3952)
		(width 0.12954)
		(layer "In2.Cu")
		(net "SKU_B2_ID1")
	)
	(segment
		(start -78.8162 13.1826)
		(end -79.7306 13.1826)
		(width 0.12954)
		(layer "In2.Cu")
		(net "SKU_B2_ID1")
	)
	(segment
		(start -79.430801 6.3754)
		(end -79.4688 6.337402)
		(width 0.1016)
		(layer "F.Cu")
		(net "SKU_B2_ID0")
	)
	(segment
		(start -79.4688 5.016602)
		(end -79.4688 6.337402)
		(width 0.1016)
		(layer "F.Cu")
		(net "SKU_B2_ID0")
	)
	(segment
		(start -78.5876 6.3754)
		(end -79.430801 6.3754)
		(width 0.1016)
		(layer "F.Cu")
		(net "SKU_B2_ID0")
	)
	(via
		(at -78.5876 6.3754)
		(size 0.5588)
		(drill 0.254)
		(layers "F.Cu" "B.Cu")
		(net "SKU_B2_ID0")
	)
	(segment
		(start -77.83322 7.12978)
		(end -77.83322 11.60018)
		(width 0.12954)
		(layer "In2.Cu")
		(net "SKU_B2_ID0")
	)
	(segment
		(start -76.2508 31.369)
		(end -76.2508 37.5612)
		(width 0.12954)
		(layer "In2.Cu")
		(net "SKU_B2_ID0")
	)
	(segment
		(start -76.2508 37.5612)
		(end -77.040001 38.350401)
		(width 0.12954)
		(layer "In2.Cu")
		(net "SKU_B2_ID0")
	)
	(segment
		(start -77.040001 38.350401)
		(end -77.040001 38.359999)
		(width 0.12954)
		(layer "In2.Cu")
		(net "SKU_B2_ID0")
	)
	(segment
		(start -78.5876 6.3754)
		(end -77.83322 7.12978)
		(width 0.12954)
		(layer "In2.Cu")
		(net "SKU_B2_ID0")
	)
	(segment
		(start -77.5716 11.8618)
		(end -76.5302 11.8618)
		(width 0.12954)
		(layer "In2.Cu")
		(net "SKU_B2_ID0")
	)
	(segment
		(start -74.4982 25.5524)
		(end -74.4982 29.6164)
		(width 0.12954)
		(layer "In2.Cu")
		(net "SKU_B2_ID0")
	)
	(segment
		(start -72.7202 15.6718)
		(end -72.7202 23.7744)
		(width 0.12954)
		(layer "In2.Cu")
		(net "SKU_B2_ID0")
	)
	(segment
		(start -76.5302 11.8618)
		(end -72.7202 15.6718)
		(width 0.12954)
		(layer "In2.Cu")
		(net "SKU_B2_ID0")
	)
	(segment
		(start -72.7202 23.7744)
		(end -74.4982 25.5524)
		(width 0.12954)
		(layer "In2.Cu")
		(net "SKU_B2_ID0")
	)
	(segment
		(start -74.4982 29.6164)
		(end -76.2508 31.369)
		(width 0.12954)
		(layer "In2.Cu")
		(net "SKU_B2_ID0")
	)
	(segment
		(start -77.83322 11.60018)
		(end -77.5716 11.8618)
		(width 0.12954)
		(layer "In2.Cu")
		(net "SKU_B2_ID0")
	)
	(segment
		(start -330.8096 21.3614)
		(end -330.819999 21.351001)
		(width 0.1016)
		(layer "F.Cu")
		(net "SKU_B1_ID2")
	)
	(segment
		(start -330.819999 17.4498)
		(end -330.819999 18.8468)
		(width 0.1016)
		(layer "F.Cu")
		(net "SKU_B1_ID2")
	)
	(segment
		(start -330.819999 21.351001)
		(end -330.819999 20.2438)
		(width 0.1016)
		(layer "F.Cu")
		(net "SKU_B1_ID2")
	)
	(segment
		(start -330.819999 18.8468)
		(end -330.819999 20.2438)
		(width 0.1016)
		(layer "F.Cu")
		(net "SKU_B1_ID2")
	)
	(via
		(at -293.1668 26.1874)
		(size 0.5588)
		(drill 0.254)
		(layers "F.Cu" "B.Cu")
		(net "SKU_B1_ID2")
	)
	(via
		(at -330.8096 21.3614)
		(size 0.5588)
		(drill 0.254)
		(layers "F.Cu" "B.Cu")
		(net "SKU_B1_ID2")
	)
	(segment
		(start -293.1668 26.1874)
		(end -294.58412 27.60472)
		(width 0.1016)
		(layer "B.Cu")
		(net "SKU_B1_ID2")
	)
	(segment
		(start -330.3524 21.3614)
		(end -330.8096 21.3614)
		(width 0.1016)
		(layer "B.Cu")
		(net "SKU_B1_ID2")
	)
	(segment
		(start -329.6666 22.0472)
		(end -330.3524 21.3614)
		(width 0.1016)
		(layer "B.Cu")
		(net "SKU_B1_ID2")
	)
	(segment
		(start -305.7144 23.7744)
		(end -320.5226 23.7744)
		(width 0.1016)
		(layer "B.Cu")
		(net "SKU_B1_ID2")
	)
	(segment
		(start -322.2498 22.0472)
		(end -329.6666 22.0472)
		(width 0.1016)
		(layer "B.Cu")
		(net "SKU_B1_ID2")
	)
	(segment
		(start -294.58412 27.60472)
		(end -301.88408 27.60472)
		(width 0.1016)
		(layer "B.Cu")
		(net "SKU_B1_ID2")
	)
	(segment
		(start -320.5226 23.7744)
		(end -322.2498 22.0472)
		(width 0.1016)
		(layer "B.Cu")
		(net "SKU_B1_ID2")
	)
	(segment
		(start -301.88408 27.60472)
		(end -305.7144 23.7744)
		(width 0.1016)
		(layer "B.Cu")
		(net "SKU_B1_ID2")
	)
	(segment
		(start -295.021 32.3088)
		(end -295.021 37.4904)
		(width 0.12954)
		(layer "In2.Cu")
		(net "SKU_B1_ID2")
	)
	(segment
		(start -295.021 37.4904)
		(end -295.990602 38.460002)
		(width 0.12954)
		(layer "In2.Cu")
		(net "SKU_B1_ID2")
	)
	(segment
		(start -292.5064 26.8478)
		(end -292.5064 28.2194)
		(width 0.12954)
		(layer "In2.Cu")
		(net "SKU_B1_ID2")
	)
	(segment
		(start -295.990602 38.460002)
		(end -296.040002 38.460002)
		(width 0.12954)
		(layer "In2.Cu")
		(net "SKU_B1_ID2")
	)
	(segment
		(start -293.3446 29.0576)
		(end -293.3446 30.6324)
		(width 0.12954)
		(layer "In2.Cu")
		(net "SKU_B1_ID2")
	)
	(segment
		(start -293.3446 30.6324)
		(end -295.021 32.3088)
		(width 0.12954)
		(layer "In2.Cu")
		(net "SKU_B1_ID2")
	)
	(segment
		(start -293.1668 26.1874)
		(end -292.5064 26.8478)
		(width 0.12954)
		(layer "In2.Cu")
		(net "SKU_B1_ID2")
	)
	(segment
		(start -292.5064 28.2194)
		(end -293.3446 29.0576)
		(width 0.12954)
		(layer "In2.Cu")
		(net "SKU_B1_ID2")
	)
	(segment
		(start -299.4406 8.8646)
		(end -299.4152 8.8392)
		(width 0.1016)
		(layer "F.Cu")
		(net "SKU_B1_ID1")
	)
	(segment
		(start -300.289199 7.4676)
		(end -300.289199 8.8646)
		(width 0.1016)
		(layer "F.Cu")
		(net "SKU_B1_ID1")
	)
	(segment
		(start -300.289199 8.8646)
		(end -299.4406 8.8646)
		(width 0.1016)
		(layer "F.Cu")
		(net "SKU_B1_ID1")
	)
	(via
		(at -299.4152 8.8392)
		(size 0.5588)
		(drill 0.254)
		(layers "F.Cu" "B.Cu")
		(net "SKU_B1_ID1")
	)
	(segment
		(start -301.1932 12.7762)
		(end -303.8856 15.4686)
		(width 0.12954)
		(layer "In2.Cu")
		(net "SKU_B1_ID1")
	)
	(segment
		(start -303.8856 15.4686)
		(end -303.8856 23.7236)
		(width 0.12954)
		(layer "In2.Cu")
		(net "SKU_B1_ID1")
	)
	(segment
		(start -299.3136 33.1724)
		(end -300.040002 33.898802)
		(width 0.12954)
		(layer "In2.Cu")
		(net "SKU_B1_ID1")
	)
	(segment
		(start -303.8856 23.7236)
		(end -301.879 25.7302)
		(width 0.12954)
		(layer "In2.Cu")
		(net "SKU_B1_ID1")
	)
	(segment
		(start -299.4152 8.8392)
		(end -298.96816 9.28624)
		(width 0.12954)
		(layer "In2.Cu")
		(net "SKU_B1_ID1")
	)
	(segment
		(start -301.879 25.7302)
		(end -301.879 29.083)
		(width 0.12954)
		(layer "In2.Cu")
		(net "SKU_B1_ID1")
	)
	(segment
		(start -298.96816 9.28624)
		(end -298.96816 12.25296)
		(width 0.12954)
		(layer "In2.Cu")
		(net "SKU_B1_ID1")
	)
	(segment
		(start -301.879 29.083)
		(end -299.3136 31.6484)
		(width 0.12954)
		(layer "In2.Cu")
		(net "SKU_B1_ID1")
	)
	(segment
		(start -299.4914 12.7762)
		(end -301.1932 12.7762)
		(width 0.12954)
		(layer "In2.Cu")
		(net "SKU_B1_ID1")
	)
	(segment
		(start -300.040002 33.898802)
		(end -300.040002 34.26)
		(width 0.12954)
		(layer "In2.Cu")
		(net "SKU_B1_ID1")
	)
	(segment
		(start -299.3136 31.6484)
		(end -299.3136 33.1724)
		(width 0.12954)
		(layer "In2.Cu")
		(net "SKU_B1_ID1")
	)
	(segment
		(start -298.96816 12.25296)
		(end -299.4914 12.7762)
		(width 0.12954)
		(layer "In2.Cu")
		(net "SKU_B1_ID1")
	)
	(segment
		(start -296.814001 9.779)
		(end -297.815 9.779)
		(width 0.1016)
		(layer "F.Cu")
		(net "SKU_B1_ID0")
	)
	(segment
		(start -296.814001 8.382)
		(end -296.814001 9.779)
		(width 0.1016)
		(layer "F.Cu")
		(net "SKU_B1_ID0")
	)
	(via
		(at -297.815 9.779)
		(size 0.5588)
		(drill 0.254)
		(layers "F.Cu" "B.Cu")
		(net "SKU_B1_ID0")
	)
	(segment
		(start -297.0784 12.1158)
		(end -298.27982 12.1158)
		(width 0.12954)
		(layer "In2.Cu")
		(net "SKU_B1_ID0")
	)
	(segment
		(start -294.1828 15.0114)
		(end -297.0784 12.1158)
		(width 0.12954)
		(layer "In2.Cu")
		(net "SKU_B1_ID0")
	)
	(segment
		(start -298.040001 38.359999)
		(end -298.040001 38.350401)
		(width 0.12954)
		(layer "In2.Cu")
		(net "SKU_B1_ID0")
	)
	(segment
		(start -297.18 37.4904)
		(end -297.18 33.9852)
		(width 0.12954)
		(layer "In2.Cu")
		(net "SKU_B1_ID0")
	)
	(segment
		(start -296.3418 29.0576)
		(end -296.3418 26.3271)
		(width 0.12954)
		(layer "In2.Cu")
		(net "SKU_B1_ID0")
	)
	(segment
		(start -298.040001 38.350401)
		(end -297.18 37.4904)
		(width 0.12954)
		(layer "In2.Cu")
		(net "SKU_B1_ID0")
	)
	(segment
		(start -296.3418 26.3271)
		(end -294.1828 24.1681)
		(width 0.12954)
		(layer "In2.Cu")
		(net "SKU_B1_ID0")
	)
	(segment
		(start -297.7134 30.4292)
		(end -296.3418 29.0576)
		(width 0.12954)
		(layer "In2.Cu")
		(net "SKU_B1_ID0")
	)
	(segment
		(start -294.1828 24.1681)
		(end -294.1828 15.0114)
		(width 0.12954)
		(layer "In2.Cu")
		(net "SKU_B1_ID0")
	)
	(segment
		(start -298.66336 10.62736)
		(end -297.815 9.779)
		(width 0.12954)
		(layer "In2.Cu")
		(net "SKU_B1_ID0")
	)
	(segment
		(start -298.66336 11.73226)
		(end -298.66336 10.62736)
		(width 0.12954)
		(layer "In2.Cu")
		(net "SKU_B1_ID0")
	)
	(segment
		(start -297.18 33.9852)
		(end -297.7134 33.4518)
		(width 0.12954)
		(layer "In2.Cu")
		(net "SKU_B1_ID0")
	)
	(segment
		(start -298.27982 12.1158)
		(end -298.66336 11.73226)
		(width 0.12954)
		(layer "In2.Cu")
		(net "SKU_B1_ID0")
	)
	(segment
		(start -297.7134 33.4518)
		(end -297.7134 30.4292)
		(width 0.12954)
		(layer "In2.Cu")
		(net "SKU_B1_ID0")
	)
	(segment
		(start -35.742552 20.743276)
		(end -35.732176 20.753649)
		(width 0.11176)
		(layer "In5.Cu")
		(net "SAS_B2_TX8P")
	)
	(segment
		(start -37.8079 23.164086)
		(end -37.8079 27.4955)
		(width 0.11176)
		(layer "In5.Cu")
		(net "SAS_B2_TX8P")
	)
	(segment
		(start -35.732176 20.753649)
		(end -36.129024 21.150496)
		(width 0.11176)
		(layer "In5.Cu")
		(net "SAS_B2_TX8P")
	)
	(segment
		(start -37.317352 28.679788)
		(end -36.79984 29.1973)
		(width 0.11176)
		(layer "In5.Cu")
		(net "SAS_B2_TX8P")
	)
	(segment
		(start -36.79984 29.1973)
		(end -36.068752 29.928391)
		(width 0.11176)
		(layer "In5.Cu")
		(net "SAS_B2_TX8P")
	)
	(segment
		(start -35.29076 33.14478)
		(end -35.29076 33.50736)
		(width 0.11176)
		(layer "In5.Cu")
		(net "SAS_B2_TX8P")
	)
	(segment
		(start -35.4765 31.93796)
		(end -35.4765 32.393085)
		(width 0.11176)
		(layer "In5.Cu")
		(net "SAS_B2_TX8P")
	)
	(segment
		(start -36.914143 21.4757)
		(end -37.304983 21.4757)
		(width 0.11176)
		(layer "In5.Cu")
		(net "SAS_B2_TX8P")
	)
	(segment
		(start -35.5219 31.248604)
		(end -35.5219 31.89256)
		(width 0.11176)
		(layer "In5.Cu")
		(net "SAS_B2_TX8P")
	)
	(segment
		(start -35.4765 32.393085)
		(end -35.5219 32.438485)
		(width 0.11176)
		(layer "In5.Cu")
		(net "SAS_B2_TX8P")
	)
	(segment
		(start -35.5219 33.7385)
		(end -35.5219 38.7858)
		(width 0.11176)
		(layer "In5.Cu")
		(net "SAS_B2_TX8P")
	)
	(segment
		(start -37.807903 21.97862)
		(end -37.807903 23.163373)
		(width 0.11176)
		(layer "In5.Cu")
		(net "SAS_B2_TX8P")
	)
	(segment
		(start -35.5219 31.89256)
		(end -35.4765 31.93796)
		(width 0.11176)
		(layer "In5.Cu")
		(net "SAS_B2_TX8P")
	)
	(segment
		(start -35.35 21.239371)
		(end -35.591262 20.789016)
		(width 0.11176)
		(layer "In5.Cu")
		(net "SAS_B2_TX8P")
	)
	(segment
		(start -36.068 39.3319)
		(end -36.20135 39.3319)
		(width 0.11176)
		(layer "In5.Cu")
		(net "SAS_B2_TX8P")
	)
	(segment
		(start -36.428992 39.426192)
		(end -36.55074 39.54794)
		(width 0.11176)
		(layer "In5.Cu")
		(net "SAS_B2_TX8P")
	)
	(segment
		(start -37.807903 23.163373)
		(end -37.8079 23.164086)
		(width 0.11176)
		(layer "In5.Cu")
		(net "SAS_B2_TX8P")
	)
	(segment
		(start -35.5219 32.438485)
		(end -35.5219 32.91364)
		(width 0.11176)
		(layer "In5.Cu")
		(net "SAS_B2_TX8P")
	)
	(arc
		(start -35.591262 20.789016)
		(mid -35.657434 20.734813)
		(end -35.742552 20.743276)
		(width 0.11176)
		(layer "In5.Cu")
		(net "SAS_B2_TX8P")
	)
	(arc
		(start -35.29076 33.50736)
		(mid -35.335491 33.615349)
		(end -35.44348 33.66008)
		(width 0.11176)
		(layer "In5.Cu")
		(net "SAS_B2_TX8P")
	)
	(arc
		(start -35.5219 38.7858)
		(mid -35.681849 39.171951)
		(end -36.068 39.3319)
		(width 0.11176)
		(layer "In5.Cu")
		(net "SAS_B2_TX8P")
	)
	(arc
		(start -35.42316 33.01238)
		(mid -35.329539 33.051159)
		(end -35.29076 33.14478)
		(width 0.11176)
		(layer "In5.Cu")
		(net "SAS_B2_TX8P")
	)
	(arc
		(start -36.20135 39.3319)
		(mid -36.324549 39.356406)
		(end -36.428992 39.426192)
		(width 0.11176)
		(layer "In5.Cu")
		(net "SAS_B2_TX8P")
	)
	(arc
		(start -35.44348 33.66008)
		(mid -35.498931 33.683049)
		(end -35.5219 33.7385)
		(width 0.11176)
		(layer "In5.Cu")
		(net "SAS_B2_TX8P")
	)
	(arc
		(start -36.55074 39.54794)
		(mid -36.646407 39.691115)
		(end -36.68 39.860002)
		(width 0.11176)
		(layer "In5.Cu")
		(net "SAS_B2_TX8P")
	)
	(arc
		(start -36.129024 21.150496)
		(mid -36.48924 21.391183)
		(end -36.914143 21.4757)
		(width 0.11176)
		(layer "In5.Cu")
		(net "SAS_B2_TX8P")
	)
	(arc
		(start -37.8079 27.4955)
		(mid -37.680411 28.136432)
		(end -37.317352 28.679788)
		(width 0.11176)
		(layer "In5.Cu")
		(net "SAS_B2_TX8P")
	)
	(arc
		(start -37.304983 21.4757)
		(mid -37.660601 21.623002)
		(end -37.807903 21.97862)
		(width 0.11176)
		(layer "In5.Cu")
		(net "SAS_B2_TX8P")
	)
	(arc
		(start -36.068752 29.928391)
		(mid -35.664023 30.53411)
		(end -35.5219 31.248604)
		(width 0.11176)
		(layer "In5.Cu")
		(net "SAS_B2_TX8P")
	)
	(arc
		(start -35.5219 32.91364)
		(mid -35.49298 32.98346)
		(end -35.42316 33.01238)
		(width 0.11176)
		(layer "In5.Cu")
		(net "SAS_B2_TX8P")
	)
	(segment
		(start -36.91414 21.1328)
		(end -37.304983 21.1328)
		(width 0.11176)
		(layer "In5.Cu")
		(net "SAS_B2_TX8N")
	)
	(segment
		(start -38.1508 23.164698)
		(end -38.1508 27.495497)
		(width 0.11176)
		(layer "In5.Cu")
		(net "SAS_B2_TX8N")
	)
	(segment
		(start -36.068 38.989)
		(end -36.151002 38.989)
		(width 0.11176)
		(layer "In5.Cu")
		(net "SAS_B2_TX8N")
	)
	(segment
		(start -37.042308 29.439768)
		(end -36.31122 30.170859)
		(width 0.11176)
		(layer "In5.Cu")
		(net "SAS_B2_TX8N")
	)
	(segment
		(start -35.90448 20.441018)
		(end -36.371489 20.908028)
		(width 0.11176)
		(layer "In5.Cu")
		(net "SAS_B2_TX8N")
	)
	(segment
		(start -37.559821 28.922256)
		(end -37.042308 29.439768)
		(width 0.11176)
		(layer "In5.Cu")
		(net "SAS_B2_TX8N")
	)
	(segment
		(start -35.864803 31.248604)
		(end -35.8648 32.9111)
		(width 0.11176)
		(layer "In5.Cu")
		(net "SAS_B2_TX8N")
	)
	(segment
		(start -36.100001 19.839371)
		(end -35.85874 20.289728)
		(width 0.11176)
		(layer "In5.Cu")
		(net "SAS_B2_TX8N")
	)
	(segment
		(start -35.8648 32.9111)
		(end -35.8648 38.7858)
		(width 0.11176)
		(layer "In5.Cu")
		(net "SAS_B2_TX8N")
	)
	(segment
		(start -38.150803 21.97862)
		(end -38.150803 23.163985)
		(width 0.11176)
		(layer "In5.Cu")
		(net "SAS_B2_TX8N")
	)
	(segment
		(start -38.150803 23.163985)
		(end -38.1508 23.164698)
		(width 0.11176)
		(layer "In5.Cu")
		(net "SAS_B2_TX8N")
	)
	(segment
		(start -35.904477 20.441018)
		(end -35.90448 20.441018)
		(width 0.11176)
		(layer "In5.Cu")
		(net "SAS_B2_TX8N")
	)
	(arc
		(start -38.1508 27.495497)
		(mid -37.997211 28.267653)
		(end -37.559821 28.922256)
		(width 0.11176)
		(layer "In5.Cu")
		(net "SAS_B2_TX8N")
	)
	(arc
		(start -36.31122 30.170859)
		(mid -35.980822 30.665332)
		(end -35.864803 31.248604)
		(width 0.11176)
		(layer "In5.Cu")
		(net "SAS_B2_TX8N")
	)
	(arc
		(start -37.304983 21.1328)
		(mid -37.903068 21.380535)
		(end -38.150803 21.97862)
		(width 0.11176)
		(layer "In5.Cu")
		(net "SAS_B2_TX8N")
	)
	(arc
		(start -35.8648 38.7858)
		(mid -35.924316 38.929484)
		(end -36.068 38.989)
		(width 0.11176)
		(layer "In5.Cu")
		(net "SAS_B2_TX8N")
	)
	(arc
		(start -36.151002 38.989)
		(mid -36.52506 38.83406)
		(end -36.68 38.460002)
		(width 0.11176)
		(layer "In5.Cu")
		(net "SAS_B2_TX8N")
	)
	(arc
		(start -35.85874 20.289728)
		(mid -35.850276 20.374845)
		(end -35.904477 20.441018)
		(width 0.11176)
		(layer "In5.Cu")
		(net "SAS_B2_TX8N")
	)
	(arc
		(start -36.371489 20.908028)
		(mid -36.62046 21.074384)
		(end -36.91414 21.1328)
		(width 0.11176)
		(layer "In5.Cu")
		(net "SAS_B2_TX8N")
	)
	(segment
		(start -35.3187 27.0383)
		(end -35.3187 26.8986)
		(width 0.11176)
		(layer "In5.Cu")
		(net "SAS_B2_TX7P")
	)
	(segment
		(start -35.659949 26.074751)
		(end -35.8775 25.8572)
		(width 0.11176)
		(layer "In5.Cu")
		(net "SAS_B2_TX7P")
	)
	(segment
		(start -33.48514 30.05042)
		(end -33.528 30.00756)
		(width 0.11176)
		(layer "In5.Cu")
		(net "SAS_B2_TX7P")
	)
	(segment
		(start -34.1884 36.4363)
		(end -34.0487 36.4363)
		(width 0.11176)
		(layer "In5.Cu")
		(net "SAS_B2_TX7P")
	)
	(segment
		(start -36.086318 24.863481)
		(end -35.804986 24.582148)
		(width 0.11176)
		(layer "In5.Cu")
		(net "SAS_B2_TX7P")
	)
	(segment
		(start -33.48514 30.516891)
		(end -33.48514 30.05042)
		(width 0.11176)
		(layer "In5.Cu")
		(net "SAS_B2_TX7P")
	)
	(segment
		(start -35.778735 24.562661)
		(end -35.742555 24.543278)
		(width 0.11176)
		(layer "In5.Cu")
		(net "SAS_B2_TX7P")
	)
	(segment
		(start -33.7874 28.9052)
		(end -35.081395 27.611205)
		(width 0.11176)
		(layer "In5.Cu")
		(net "SAS_B2_TX7P")
	)
	(segment
		(start -35.591262 24.589016)
		(end -35.35 25.039371)
		(width 0.11176)
		(layer "In5.Cu")
		(net "SAS_B2_TX7P")
	)
	(segment
		(start -33.528 31.12802)
		(end -33.528 30.559751)
		(width 0.11176)
		(layer "In5.Cu")
		(net "SAS_B2_TX7P")
	)
	(segment
		(start -33.29686 31.7827)
		(end -33.29686 31.35916)
		(width 0.11176)
		(layer "In5.Cu")
		(net "SAS_B2_TX7P")
	)
	(segment
		(start -33.528 35.9156)
		(end -33.528 32.01384)
		(width 0.11176)
		(layer "In5.Cu")
		(net "SAS_B2_TX7P")
	)
	(segment
		(start -33.528 30.559751)
		(end -33.48514 30.516891)
		(width 0.11176)
		(layer "In5.Cu")
		(net "SAS_B2_TX7P")
	)
	(segment
		(start -34.679999 36.96)
		(end -34.679999 36.927899)
		(width 0.11176)
		(layer "In5.Cu")
		(net "SAS_B2_TX7P")
	)
	(segment
		(start -36.1823 25.121347)
		(end -36.1823 25.0952)
		(width 0.11176)
		(layer "In5.Cu")
		(net "SAS_B2_TX7P")
	)
	(segment
		(start -35.742555 24.543278)
		(end -35.742552 24.543276)
		(width 0.11176)
		(layer "In5.Cu")
		(net "SAS_B2_TX7P")
	)
	(segment
		(start -33.528 30.00756)
		(end -33.528 29.531447)
		(width 0.11176)
		(layer "In5.Cu")
		(net "SAS_B2_TX7P")
	)
	(arc
		(start -35.804986 24.582148)
		(mid -35.792577 24.571439)
		(end -35.778735 24.562661)
		(width 0.11176)
		(layer "In5.Cu")
		(net "SAS_B2_TX7P")
	)
	(arc
		(start -35.081395 27.611205)
		(mid -35.257027 27.348354)
		(end -35.3187 27.0383)
		(width 0.11176)
		(layer "In5.Cu")
		(net "SAS_B2_TX7P")
	)
	(arc
		(start -34.679999 36.927899)
		(mid -34.536013 36.580286)
		(end -34.1884 36.4363)
		(width 0.11176)
		(layer "In5.Cu")
		(net "SAS_B2_TX7P")
	)
	(arc
		(start -33.29686 31.35916)
		(mid -33.341591 31.251171)
		(end -33.44958 31.20644)
		(width 0.11176)
		(layer "In5.Cu")
		(net "SAS_B2_TX7P")
	)
	(arc
		(start -34.0487 36.4363)
		(mid -33.680509 36.283791)
		(end -33.528 35.9156)
		(width 0.11176)
		(layer "In5.Cu")
		(net "SAS_B2_TX7P")
	)
	(arc
		(start -35.3187 26.8986)
		(mid -35.407388 26.452736)
		(end -35.659949 26.074751)
		(width 0.11176)
		(layer "In5.Cu")
		(net "SAS_B2_TX7P")
	)
	(arc
		(start -33.42926 31.9151)
		(mid -33.335639 31.876321)
		(end -33.29686 31.7827)
		(width 0.11176)
		(layer "In5.Cu")
		(net "SAS_B2_TX7P")
	)
	(arc
		(start -36.1823 25.0952)
		(mid -36.157355 24.969794)
		(end -36.086318 24.863481)
		(width 0.11176)
		(layer "In5.Cu")
		(net "SAS_B2_TX7P")
	)
	(arc
		(start -33.528 32.01384)
		(mid -33.49908 31.94402)
		(end -33.42926 31.9151)
		(width 0.11176)
		(layer "In5.Cu")
		(net "SAS_B2_TX7P")
	)
	(arc
		(start -35.8775 25.8572)
		(mid -36.103085 25.519588)
		(end -36.1823 25.121347)
		(width 0.11176)
		(layer "In5.Cu")
		(net "SAS_B2_TX7P")
	)
	(arc
		(start -35.742552 24.543276)
		(mid -35.657434 24.534812)
		(end -35.591262 24.589016)
		(width 0.11176)
		(layer "In5.Cu")
		(net "SAS_B2_TX7P")
	)
	(arc
		(start -33.44958 31.20644)
		(mid -33.505031 31.183471)
		(end -33.528 31.12802)
		(width 0.11176)
		(layer "In5.Cu")
		(net "SAS_B2_TX7P")
	)
	(arc
		(start -33.528 29.531447)
		(mid -33.595416 29.192525)
		(end -33.7874 28.9052)
		(width 0.11176)
		(layer "In5.Cu")
		(net "SAS_B2_TX7P")
	)
	(segment
		(start -36.5252 25.121347)
		(end -36.5252 25.095197)
		(width 0.11176)
		(layer "In5.Cu")
		(net "SAS_B2_TX7N")
	)
	(segment
		(start -34.029868 29.147668)
		(end -35.323864 27.853673)
		(width 0.11176)
		(layer "In5.Cu")
		(net "SAS_B2_TX7N")
	)
	(segment
		(start -35.85874 24.089728)
		(end -36.100001 23.639371)
		(width 0.11176)
		(layer "In5.Cu")
		(net "SAS_B2_TX7N")
	)
	(segment
		(start -35.90448 24.241018)
		(end -35.904477 24.241018)
		(width 0.11176)
		(layer "In5.Cu")
		(net "SAS_B2_TX7N")
	)
	(segment
		(start -34.679999 35.56)
		(end -34.679999 35.601801)
		(width 0.11176)
		(layer "In5.Cu")
		(net "SAS_B2_TX7N")
	)
	(segment
		(start -33.8709 35.9156)
		(end -33.8709 29.531447)
		(width 0.11176)
		(layer "In5.Cu")
		(net "SAS_B2_TX7N")
	)
	(segment
		(start -36.328787 24.621012)
		(end -36.047451 24.339677)
		(width 0.11176)
		(layer "In5.Cu")
		(net "SAS_B2_TX7N")
	)
	(segment
		(start -35.6616 27.038297)
		(end -35.6616 26.898603)
		(width 0.11176)
		(layer "In5.Cu")
		(net "SAS_B2_TX7N")
	)
	(segment
		(start -35.902417 26.317219)
		(end -36.119968 26.099668)
		(width 0.11176)
		(layer "In5.Cu")
		(net "SAS_B2_TX7N")
	)
	(segment
		(start -34.1884 36.0934)
		(end -34.0487 36.0934)
		(width 0.11176)
		(layer "In5.Cu")
		(net "SAS_B2_TX7N")
	)
	(segment
		(start -35.94085 24.260503)
		(end -35.90448 24.241018)
		(width 0.11176)
		(layer "In5.Cu")
		(net "SAS_B2_TX7N")
	)
	(arc
		(start -33.8709 29.531447)
		(mid -33.912215 29.323747)
		(end -34.029868 29.147668)
		(width 0.11176)
		(layer "In5.Cu")
		(net "SAS_B2_TX7N")
	)
	(arc
		(start -36.5252 25.095197)
		(mid -36.474154 24.83857)
		(end -36.328787 24.621012)
		(width 0.11176)
		(layer "In5.Cu")
		(net "SAS_B2_TX7N")
	)
	(arc
		(start -34.679999 35.601801)
		(mid -34.536013 35.949414)
		(end -34.1884 36.0934)
		(width 0.11176)
		(layer "In5.Cu")
		(net "SAS_B2_TX7N")
	)
	(arc
		(start -34.0487 36.0934)
		(mid -33.922976 36.041324)
		(end -33.8709 35.9156)
		(width 0.11176)
		(layer "In5.Cu")
		(net "SAS_B2_TX7N")
	)
	(arc
		(start -36.119968 26.099668)
		(mid -36.419884 25.65081)
		(end -36.5252 25.121347)
		(width 0.11176)
		(layer "In5.Cu")
		(net "SAS_B2_TX7N")
	)
	(arc
		(start -35.904477 24.241018)
		(mid -35.850275 24.174845)
		(end -35.85874 24.089728)
		(width 0.11176)
		(layer "In5.Cu")
		(net "SAS_B2_TX7N")
	)
	(arc
		(start -35.6616 26.898603)
		(mid -35.724186 26.58396)
		(end -35.902417 26.317219)
		(width 0.11176)
		(layer "In5.Cu")
		(net "SAS_B2_TX7N")
	)
	(arc
		(start -36.047451 24.339677)
		(mid -35.997056 24.296177)
		(end -35.94085 24.260503)
		(width 0.11176)
		(layer "In5.Cu")
		(net "SAS_B2_TX7N")
	)
	(arc
		(start -35.323864 27.853673)
		(mid -35.573827 27.479575)
		(end -35.6616 27.038297)
		(width 0.11176)
		(layer "In5.Cu")
		(net "SAS_B2_TX7N")
	)
	(segment
		(start -33.3248 30.3784)
		(end -33.2994 30.3784)
		(width 0.10668)
		(layer "B.Cu")
		(net "SAS_B2_TX6P")
	)
	(segment
		(start -33.147 30.5308)
		(end -33.147 30.881)
		(width 0.10668)
		(layer "B.Cu")
		(net "SAS_B2_TX6P")
	)
	(segment
		(start -33.254 30.988)
		(end -33.34766 30.988)
		(width 0.10668)
		(layer "B.Cu")
		(net "SAS_B2_TX6P")
	)
	(segment
		(start -33.37052 32.258)
		(end -33.381 32.258)
		(width 0.10668)
		(layer "B.Cu")
		(net "SAS_B2_TX6P")
	)
	(segment
		(start -33.1724 31.8316)
		(end -33.1724 32.05988)
		(width 0.10668)
		(layer "B.Cu")
		(net "SAS_B2_TX6P")
	)
	(segment
		(start -33.47466 31.115)
		(end -33.47466 31.52934)
		(width 0.10668)
		(layer "B.Cu")
		(net "SAS_B2_TX6P")
	)
	(segment
		(start -36.722126 22.993429)
		(end -37.0078 23.2791)
		(width 0.10668)
		(layer "B.Cu")
		(net "SAS_B2_TX6P")
	)
	(segment
		(start -33.98552 21.40966)
		(end -34.122926 21.547066)
		(width 0.10668)
		(layer "B.Cu")
		(net "SAS_B2_TX6P")
	)
	(segment
		(start -34.679999 45.325139)
		(end -34.679999 45.360001)
		(width 0.10668)
		(layer "B.Cu")
		(net "SAS_B2_TX6P")
	)
	(segment
		(start -33.1 21.239371)
		(end -33.322072 20.824838)
		(width 0.10668)
		(layer "B.Cu")
		(net "SAS_B2_TX6P")
	)
	(segment
		(start -37.399018 27.747328)
		(end -37.386473 27.759873)
		(width 0.10668)
		(layer "B.Cu")
		(net "SAS_B2_TX6P")
	)
	(segment
		(start -34.1122 44.88434)
		(end -34.2392 44.88434)
		(width 0.10668)
		(layer "B.Cu")
		(net "SAS_B2_TX6P")
	)
	(segment
		(start -33.466486 20.78118)
		(end -33.560522 20.831556)
		(width 0.10668)
		(layer "B.Cu")
		(net "SAS_B2_TX6P")
	)
	(segment
		(start -33.466484 20.78118)
		(end -33.466486 20.78118)
		(width 0.10668)
		(layer "B.Cu")
		(net "SAS_B2_TX6P")
	)
	(segment
		(start -33.47466 32.35166)
		(end -33.47466 44.2468)
		(width 0.10668)
		(layer "B.Cu")
		(net "SAS_B2_TX6P")
	)
	(segment
		(start -33.47466 29.0068)
		(end -33.47466 30.22854)
		(width 0.10668)
		(layer "B.Cu")
		(net "SAS_B2_TX6P")
	)
	(segment
		(start -37.79266 25.17392)
		(end -37.79266 26.797)
		(width 0.10668)
		(layer "B.Cu")
		(net "SAS_B2_TX6P")
	)
	(segment
		(start -34.32588 22.03704)
		(end -34.32588 22.10308)
		(width 0.10668)
		(layer "B.Cu")
		(net "SAS_B2_TX6P")
	)
	(segment
		(start -34.9558 22.733)
		(end -36.0934 22.733)
		(width 0.10668)
		(layer "B.Cu")
		(net "SAS_B2_TX6P")
	)
	(segment
		(start -36.890292 27.9654)
		(end -34.51606 27.9654)
		(width 0.10668)
		(layer "B.Cu")
		(net "SAS_B2_TX6P")
	)
	(arc
		(start -37.386473 27.759873)
		(mid -37.158823 27.911984)
		(end -36.890292 27.9654)
		(width 0.10668)
		(layer "B.Cu")
		(net "SAS_B2_TX6P")
	)
	(arc
		(start -33.2994 30.3784)
		(mid -33.191637 30.423037)
		(end -33.147 30.5308)
		(width 0.10668)
		(layer "B.Cu")
		(net "SAS_B2_TX6P")
	)
	(arc
		(start -34.32588 22.10308)
		(mid -34.510379 22.548501)
		(end -34.9558 22.733)
		(width 0.10668)
		(layer "B.Cu")
		(net "SAS_B2_TX6P")
	)
	(arc
		(start -33.34766 30.988)
		(mid -33.437463 31.025197)
		(end -33.47466 31.115)
		(width 0.10668)
		(layer "B.Cu")
		(net "SAS_B2_TX6P")
	)
	(arc
		(start -34.122926 21.547066)
		(mid -34.273134 21.771868)
		(end -34.32588 22.03704)
		(width 0.10668)
		(layer "B.Cu")
		(net "SAS_B2_TX6P")
	)
	(arc
		(start -33.47466 44.2468)
		(mid -33.661391 44.697609)
		(end -34.1122 44.88434)
		(width 0.10668)
		(layer "B.Cu")
		(net "SAS_B2_TX6P")
	)
	(arc
		(start -33.381 32.258)
		(mid -33.447228 32.285432)
		(end -33.47466 32.35166)
		(width 0.10668)
		(layer "B.Cu")
		(net "SAS_B2_TX6P")
	)
	(arc
		(start -34.51606 27.9654)
		(mid -33.779679 28.270419)
		(end -33.47466 29.0068)
		(width 0.10668)
		(layer "B.Cu")
		(net "SAS_B2_TX6P")
	)
	(arc
		(start -33.47466 30.22854)
		(mid -33.430767 30.334507)
		(end -33.3248 30.3784)
		(width 0.10668)
		(layer "B.Cu")
		(net "SAS_B2_TX6P")
	)
	(arc
		(start -36.0934 22.733)
		(mid -36.433664 22.800684)
		(end -36.722126 22.993429)
		(width 0.10668)
		(layer "B.Cu")
		(net "SAS_B2_TX6P")
	)
	(arc
		(start -34.2392 44.88434)
		(mid -34.550892 45.013447)
		(end -34.679999 45.325139)
		(width 0.10668)
		(layer "B.Cu")
		(net "SAS_B2_TX6P")
	)
	(arc
		(start -33.147 30.881)
		(mid -33.17834 30.95666)
		(end -33.254 30.988)
		(width 0.10668)
		(layer "B.Cu")
		(net "SAS_B2_TX6P")
	)
	(arc
		(start -33.47466 31.52934)
		(mid -33.447228 31.595568)
		(end -33.381 31.623)
		(width 0.10668)
		(layer "B.Cu")
		(net "SAS_B2_TX6P")
	)
	(arc
		(start -33.381 31.623)
		(mid -33.233498 31.684098)
		(end -33.1724 31.8316)
		(width 0.10668)
		(layer "B.Cu")
		(net "SAS_B2_TX6P")
	)
	(arc
		(start -37.79266 26.797)
		(mid -37.690355 27.311314)
		(end -37.399018 27.747328)
		(width 0.10668)
		(layer "B.Cu")
		(net "SAS_B2_TX6P")
	)
	(arc
		(start -37.0078 23.2791)
		(mid -37.588682 24.148451)
		(end -37.79266 25.17392)
		(width 0.10668)
		(layer "B.Cu")
		(net "SAS_B2_TX6P")
	)
	(arc
		(start -33.560522 20.831556)
		(mid -33.628849 20.884708)
		(end -33.67564 20.95754)
		(width 0.10668)
		(layer "B.Cu")
		(net "SAS_B2_TX6P")
	)
	(arc
		(start -33.322072 20.824838)
		(mid -33.385236 20.7731)
		(end -33.466484 20.78118)
		(width 0.10668)
		(layer "B.Cu")
		(net "SAS_B2_TX6P")
	)
	(arc
		(start -33.1724 32.05988)
		(mid -33.230428 32.199972)
		(end -33.37052 32.258)
		(width 0.10668)
		(layer "B.Cu")
		(net "SAS_B2_TX6P")
	)
	(arc
		(start -33.67564 20.95754)
		(mid -33.807998 21.199077)
		(end -33.98552 21.40966)
		(width 0.10668)
		(layer "B.Cu")
		(net "SAS_B2_TX6P")
	)
	(segment
		(start -37.706145 28.054455)
		(end -37.6936 28.067)
		(width 0.10668)
		(layer "B.Cu")
		(net "SAS_B2_TX6N")
	)
	(segment
		(start -34.290406 21.100296)
		(end -34.430053 21.23994)
		(width 0.10668)
		(layer "B.Cu")
		(net "SAS_B2_TX6N")
	)
	(segment
		(start -36.890295 28.39974)
		(end -34.51606 28.39974)
		(width 0.10668)
		(layer "B.Cu")
		(net "SAS_B2_TX6N")
	)
	(segment
		(start -33.909 29.0068)
		(end -33.909 44.2468)
		(width 0.10668)
		(layer "B.Cu")
		(net "SAS_B2_TX6N")
	)
	(segment
		(start -33.671589 20.398313)
		(end -33.671591 20.398316)
		(width 0.10668)
		(layer "B.Cu")
		(net "SAS_B2_TX6N")
	)
	(segment
		(start -34.679999 44.009201)
		(end -34.679999 43.960001)
		(width 0.10668)
		(layer "B.Cu")
		(net "SAS_B2_TX6N")
	)
	(segment
		(start -34.76022 22.037043)
		(end -34.76022 22.10308)
		(width 0.10668)
		(layer "B.Cu")
		(net "SAS_B2_TX6N")
	)
	(segment
		(start -38.227 25.173917)
		(end -38.227 26.797)
		(width 0.10668)
		(layer "B.Cu")
		(net "SAS_B2_TX6N")
	)
	(segment
		(start -33.850001 19.839371)
		(end -33.627929 20.253902)
		(width 0.10668)
		(layer "B.Cu")
		(net "SAS_B2_TX6N")
	)
	(segment
		(start -37.029253 22.686302)
		(end -37.314924 22.971973)
		(width 0.10668)
		(layer "B.Cu")
		(net "SAS_B2_TX6N")
	)
	(segment
		(start -34.9558 22.29866)
		(end -36.093403 22.29866)
		(width 0.10668)
		(layer "B.Cu")
		(net "SAS_B2_TX6N")
	)
	(segment
		(start -34.288133 21.098088)
		(end -34.290406 21.100296)
		(width 0.10668)
		(layer "B.Cu")
		(net "SAS_B2_TX6N")
	)
	(segment
		(start -33.671591 20.398316)
		(end -33.765627 20.448692)
		(width 0.10668)
		(layer "B.Cu")
		(net "SAS_B2_TX6N")
	)
	(segment
		(start -34.1122 44.45)
		(end -34.2392 44.45)
		(width 0.10668)
		(layer "B.Cu")
		(net "SAS_B2_TX6N")
	)
	(arc
		(start -33.627929 20.253902)
		(mid -33.619851 20.33515)
		(end -33.671589 20.398313)
		(width 0.10668)
		(layer "B.Cu")
		(net "SAS_B2_TX6N")
	)
	(arc
		(start -34.430053 21.23994)
		(mid -34.674414 21.605654)
		(end -34.76022 22.037043)
		(width 0.10668)
		(layer "B.Cu")
		(net "SAS_B2_TX6N")
	)
	(arc
		(start -33.765627 20.448692)
		(mid -33.949491 20.591722)
		(end -34.0754 20.787708)
		(width 0.10668)
		(layer "B.Cu")
		(net "SAS_B2_TX6N")
	)
	(arc
		(start -37.314924 22.971973)
		(mid -37.989959 23.982233)
		(end -38.227 25.173917)
		(width 0.10668)
		(layer "B.Cu")
		(net "SAS_B2_TX6N")
	)
	(arc
		(start -37.6936 28.067)
		(mid -37.325041 28.313264)
		(end -36.890295 28.39974)
		(width 0.10668)
		(layer "B.Cu")
		(net "SAS_B2_TX6N")
	)
	(arc
		(start -34.0754 20.787708)
		(mid -34.166264 20.953523)
		(end -34.288133 21.098088)
		(width 0.10668)
		(layer "B.Cu")
		(net "SAS_B2_TX6N")
	)
	(arc
		(start -33.909 44.2468)
		(mid -33.968516 44.390484)
		(end -34.1122 44.45)
		(width 0.10668)
		(layer "B.Cu")
		(net "SAS_B2_TX6N")
	)
	(arc
		(start -34.51606 28.39974)
		(mid -34.086804 28.577544)
		(end -33.909 29.0068)
		(width 0.10668)
		(layer "B.Cu")
		(net "SAS_B2_TX6N")
	)
	(arc
		(start -34.2392 44.45)
		(mid -34.550892 44.320893)
		(end -34.679999 44.009201)
		(width 0.10668)
		(layer "B.Cu")
		(net "SAS_B2_TX6N")
	)
	(arc
		(start -34.76022 22.10308)
		(mid -34.817504 22.241376)
		(end -34.9558 22.29866)
		(width 0.10668)
		(layer "B.Cu")
		(net "SAS_B2_TX6N")
	)
	(arc
		(start -36.093403 22.29866)
		(mid -36.599881 22.399406)
		(end -37.029253 22.686302)
		(width 0.10668)
		(layer "B.Cu")
		(net "SAS_B2_TX6N")
	)
	(arc
		(start -38.227 26.797)
		(mid -38.091634 27.47753)
		(end -37.706145 28.054455)
		(width 0.10668)
		(layer "B.Cu")
		(net "SAS_B2_TX6N")
	)
	(segment
		(start -31.5341 31.85922)
		(end -31.5341 31.10074)
		(width 0.11176)
		(layer "In5.Cu")
		(net "SAS_B2_TX5P")
	)
	(segment
		(start -33.492554 24.543278)
		(end -33.492552 24.543276)
		(width 0.11176)
		(layer "In5.Cu")
		(net "SAS_B2_TX5P")
	)
	(segment
		(start -31.5341 38.735)
		(end -31.5341 33.6242)
		(width 0.11176)
		(layer "In5.Cu")
		(net "SAS_B2_TX5P")
	)
	(segment
		(start -31.5014 31.89192)
		(end -31.5341 31.85922)
		(width 0.11176)
		(layer "In5.Cu")
		(net "SAS_B2_TX5P")
	)
	(segment
		(start -33.341262 24.589016)
		(end -33.1 25.039371)
		(width 0.11176)
		(layer "In5.Cu")
		(net "SAS_B2_TX5P")
	)
	(segment
		(start -31.5014 32.324838)
		(end -31.5014 31.89192)
		(width 0.11176)
		(layer "In5.Cu")
		(net "SAS_B2_TX5P")
	)
	(segment
		(start -32.151899 39.3319)
		(end -32.131 39.3319)
		(width 0.11176)
		(layer "In5.Cu")
		(net "SAS_B2_TX5P")
	)
	(segment
		(start -31.30328 33.39338)
		(end -31.30328 33.00222)
		(width 0.11176)
		(layer "In5.Cu")
		(net "SAS_B2_TX5P")
	)
	(segment
		(start -31.5341 32.7714)
		(end -31.5341 32.357538)
		(width 0.11176)
		(layer "In5.Cu")
		(net "SAS_B2_TX5P")
	)
	(segment
		(start -33.8963 25.397884)
		(end -33.896297 25.2222)
		(width 0.11176)
		(layer "In5.Cu")
		(net "SAS_B2_TX5P")
	)
	(segment
		(start -33.53181 24.56431)
		(end -33.492554 24.543278)
		(width 0.11176)
		(layer "In5.Cu")
		(net "SAS_B2_TX5P")
	)
	(segment
		(start -33.68405 24.709788)
		(end -33.558058 24.583796)
		(width 0.11176)
		(layer "In5.Cu")
		(net "SAS_B2_TX5P")
	)
	(segment
		(start -31.5341 32.357538)
		(end -31.5014 32.324838)
		(width 0.11176)
		(layer "In5.Cu")
		(net "SAS_B2_TX5P")
	)
	(arc
		(start -33.492552 24.543276)
		(mid -33.407434 24.534812)
		(end -33.341262 24.589016)
		(width 0.11176)
		(layer "In5.Cu")
		(net "SAS_B2_TX5P")
	)
	(arc
		(start -31.5341 31.10074)
		(mid -31.949674 29.011502)
		(end -33.133132 27.240332)
		(width 0.11176)
		(layer "In5.Cu")
		(net "SAS_B2_TX5P")
	)
	(arc
		(start -33.133132 27.240332)
		(mid -33.697959 26.39501)
		(end -33.8963 25.397884)
		(width 0.11176)
		(layer "In5.Cu")
		(net "SAS_B2_TX5P")
	)
	(arc
		(start -32.131 39.3319)
		(mid -31.708928 39.157072)
		(end -31.5341 38.735)
		(width 0.11176)
		(layer "In5.Cu")
		(net "SAS_B2_TX5P")
	)
	(arc
		(start -31.44806 33.53816)
		(mid -31.345685 33.495755)
		(end -31.30328 33.39338)
		(width 0.11176)
		(layer "In5.Cu")
		(net "SAS_B2_TX5P")
	)
	(arc
		(start -32.680001 39.860002)
		(mid -32.525324 39.486577)
		(end -32.151899 39.3319)
		(width 0.11176)
		(layer "In5.Cu")
		(net "SAS_B2_TX5P")
	)
	(arc
		(start -33.558058 24.583796)
		(mid -33.54565 24.573088)
		(end -33.53181 24.56431)
		(width 0.11176)
		(layer "In5.Cu")
		(net "SAS_B2_TX5P")
	)
	(arc
		(start -33.896297 25.2222)
		(mid -33.841136 24.944885)
		(end -33.68405 24.709788)
		(width 0.11176)
		(layer "In5.Cu")
		(net "SAS_B2_TX5P")
	)
	(arc
		(start -31.30328 33.00222)
		(mid -31.342709 32.907029)
		(end -31.4379 32.8676)
		(width 0.11176)
		(layer "In5.Cu")
		(net "SAS_B2_TX5P")
	)
	(arc
		(start -31.4379 32.8676)
		(mid -31.505924 32.839424)
		(end -31.5341 32.7714)
		(width 0.11176)
		(layer "In5.Cu")
		(net "SAS_B2_TX5P")
	)
	(arc
		(start -31.5341 33.6242)
		(mid -31.508899 33.563361)
		(end -31.44806 33.53816)
		(width 0.11176)
		(layer "In5.Cu")
		(net "SAS_B2_TX5P")
	)
	(segment
		(start -33.926518 24.46732)
		(end -33.800527 24.341328)
		(width 0.11176)
		(layer "In5.Cu")
		(net "SAS_B2_TX5N")
	)
	(segment
		(start -33.608739 24.089728)
		(end -33.850001 23.639371)
		(width 0.11176)
		(layer "In5.Cu")
		(net "SAS_B2_TX5N")
	)
	(segment
		(start -33.693738 24.26205)
		(end -33.654479 24.241018)
		(width 0.11176)
		(layer "In5.Cu")
		(net "SAS_B2_TX5N")
	)
	(segment
		(start -34.2392 25.397884)
		(end -34.2392 25.2222)
		(width 0.11176)
		(layer "In5.Cu")
		(net "SAS_B2_TX5N")
	)
	(segment
		(start -33.654479 24.241018)
		(end -33.654477 24.241018)
		(width 0.11176)
		(layer "In5.Cu")
		(net "SAS_B2_TX5N")
	)
	(segment
		(start -31.877 38.735)
		(end -31.877 31.10074)
		(width 0.11176)
		(layer "In5.Cu")
		(net "SAS_B2_TX5N")
	)
	(segment
		(start -32.151003 38.989)
		(end -32.131 38.989)
		(width 0.11176)
		(layer "In5.Cu")
		(net "SAS_B2_TX5N")
	)
	(arc
		(start -33.3756 27.4828)
		(mid -34.014758 26.526232)
		(end -34.2392 25.397884)
		(width 0.11176)
		(layer "In5.Cu")
		(net "SAS_B2_TX5N")
	)
	(arc
		(start -32.680001 38.460002)
		(mid -32.525061 38.83406)
		(end -32.151003 38.989)
		(width 0.11176)
		(layer "In5.Cu")
		(net "SAS_B2_TX5N")
	)
	(arc
		(start -33.800527 24.341328)
		(mid -33.750047 24.297763)
		(end -33.693738 24.26205)
		(width 0.11176)
		(layer "In5.Cu")
		(net "SAS_B2_TX5N")
	)
	(arc
		(start -32.131 38.989)
		(mid -31.951395 38.914605)
		(end -31.877 38.735)
		(width 0.11176)
		(layer "In5.Cu")
		(net "SAS_B2_TX5N")
	)
	(arc
		(start -31.877 31.10074)
		(mid -32.266473 29.142725)
		(end -33.3756 27.4828)
		(width 0.11176)
		(layer "In5.Cu")
		(net "SAS_B2_TX5N")
	)
	(arc
		(start -33.654477 24.241018)
		(mid -33.600275 24.174846)
		(end -33.608739 24.089728)
		(width 0.11176)
		(layer "In5.Cu")
		(net "SAS_B2_TX5N")
	)
	(arc
		(start -34.2392 25.2222)
		(mid -34.157937 24.813662)
		(end -33.926518 24.46732)
		(width 0.11176)
		(layer "In5.Cu")
		(net "SAS_B2_TX5N")
	)
	(segment
		(start -29.5275 35.7632)
		(end -29.5275 32.34404)
		(width 0.11176)
		(layer "In5.Cu")
		(net "SAS_B2_TX4P")
	)
	(segment
		(start -26.8986 22.402803)
		(end -26.131604 21.635806)
		(width 0.11176)
		(layer "In5.Cu")
		(net "SAS_B2_TX4P")
	)
	(segment
		(start -29.5275 31.51156)
		(end -29.5275 30.784066)
		(width 0.11176)
		(layer "In5.Cu")
		(net "SAS_B2_TX4P")
	)
	(segment
		(start -29.5275 30.114146)
		(end -29.5275 28.749523)
		(width 0.11176)
		(layer "In5.Cu")
		(net "SAS_B2_TX4P")
	)
	(segment
		(start -25.326645 21.302381)
		(end -24.808058 20.783796)
		(width 0.11176)
		(layer "In5.Cu")
		(net "SAS_B2_TX4P")
	)
	(segment
		(start -24.742554 20.743278)
		(end -24.742557 20.743278)
		(width 0.11176)
		(layer "In5.Cu")
		(net "SAS_B2_TX4P")
	)
	(segment
		(start -24.742557 20.743278)
		(end -24.742554 20.743276)
		(width 0.11176)
		(layer "In5.Cu")
		(net "SAS_B2_TX4P")
	)
	(segment
		(start -30.68 36.96)
		(end -30.68 36.9157)
		(width 0.11176)
		(layer "In5.Cu")
		(net "SAS_B2_TX4P")
	)
	(segment
		(start -29.27096 32.0875)
		(end -29.27096 31.7681)
		(width 0.11176)
		(layer "In5.Cu")
		(net "SAS_B2_TX4P")
	)
	(segment
		(start -29.5275 30.784066)
		(end -29.42622 30.682786)
		(width 0.11176)
		(layer "In5.Cu")
		(net "SAS_B2_TX4P")
	)
	(segment
		(start -24.78181 20.76431)
		(end -24.742554 20.743278)
		(width 0.11176)
		(layer "In5.Cu")
		(net "SAS_B2_TX4P")
	)
	(segment
		(start -29.42622 30.215426)
		(end -29.5275 30.114146)
		(width 0.11176)
		(layer "In5.Cu")
		(net "SAS_B2_TX4P")
	)
	(segment
		(start -29.42622 30.682786)
		(end -29.42622 30.215426)
		(width 0.11176)
		(layer "In5.Cu")
		(net "SAS_B2_TX4P")
	)
	(segment
		(start -24.591264 20.789016)
		(end -24.350002 21.239371)
		(width 0.11176)
		(layer "In5.Cu")
		(net "SAS_B2_TX4P")
	)
	(arc
		(start -29.27096 31.7681)
		(mid -29.317922 31.654722)
		(end -29.4313 31.60776)
		(width 0.11176)
		(layer "In5.Cu")
		(net "SAS_B2_TX4P")
	)
	(arc
		(start -29.4313 31.60776)
		(mid -29.499324 31.579584)
		(end -29.5275 31.51156)
		(width 0.11176)
		(layer "In5.Cu")
		(net "SAS_B2_TX4P")
	)
	(arc
		(start -24.808058 20.783796)
		(mid -24.79565 20.773088)
		(end -24.78181 20.76431)
		(width 0.11176)
		(layer "In5.Cu")
		(net "SAS_B2_TX4P")
	)
	(arc
		(start -30.68 36.9157)
		(mid -30.539587 36.576713)
		(end -30.2006 36.4363)
		(width 0.11176)
		(layer "In5.Cu")
		(net "SAS_B2_TX4P")
	)
	(arc
		(start -30.2006 36.4363)
		(mid -29.724646 36.239154)
		(end -29.5275 35.7632)
		(width 0.11176)
		(layer "In5.Cu")
		(net "SAS_B2_TX4P")
	)
	(arc
		(start -29.5275 32.34404)
		(mid -29.503043 32.284997)
		(end -29.444 32.26054)
		(width 0.11176)
		(layer "In5.Cu")
		(net "SAS_B2_TX4P")
	)
	(arc
		(start -25.806397 21.5011)
		(mid -25.546758 21.449454)
		(end -25.326645 21.302381)
		(width 0.11176)
		(layer "In5.Cu")
		(net "SAS_B2_TX4P")
	)
	(arc
		(start -26.131604 21.635806)
		(mid -25.982398 21.536109)
		(end -25.806397 21.5011)
		(width 0.11176)
		(layer "In5.Cu")
		(net "SAS_B2_TX4P")
	)
	(arc
		(start -29.5275 28.749523)
		(mid -28.844271 25.314703)
		(end -26.8986 22.402803)
		(width 0.11176)
		(layer "In5.Cu")
		(net "SAS_B2_TX4P")
	)
	(arc
		(start -24.742554 20.743276)
		(mid -24.657436 20.734812)
		(end -24.591264 20.789016)
		(width 0.11176)
		(layer "In5.Cu")
		(net "SAS_B2_TX4P")
	)
	(arc
		(start -29.444 32.26054)
		(mid -29.321642 32.209858)
		(end -29.27096 32.0875)
		(width 0.11176)
		(layer "In5.Cu")
		(net "SAS_B2_TX4P")
	)
	(segment
		(start -29.8704 35.7632)
		(end -29.8704 28.749523)
		(width 0.11176)
		(layer "In5.Cu")
		(net "SAS_B2_TX4N")
	)
	(segment
		(start -24.943737 20.46205)
		(end -24.904479 20.441018)
		(width 0.11176)
		(layer "In5.Cu")
		(net "SAS_B2_TX4N")
	)
	(segment
		(start -25.569111 21.059912)
		(end -25.050526 20.541328)
		(width 0.11176)
		(layer "In5.Cu")
		(net "SAS_B2_TX4N")
	)
	(segment
		(start -24.904479 20.441018)
		(end -24.904476 20.441018)
		(width 0.11176)
		(layer "In5.Cu")
		(net "SAS_B2_TX4N")
	)
	(segment
		(start -30.68 35.56)
		(end -30.68 35.614)
		(width 0.11176)
		(layer "In5.Cu")
		(net "SAS_B2_TX4N")
	)
	(segment
		(start -24.858739 20.289728)
		(end -25.100001 19.839371)
		(width 0.11176)
		(layer "In5.Cu")
		(net "SAS_B2_TX4N")
	)
	(segment
		(start -27.141068 22.160334)
		(end -26.374072 21.393338)
		(width 0.11176)
		(layer "In5.Cu")
		(net "SAS_B2_TX4N")
	)
	(arc
		(start -25.050526 20.541328)
		(mid -25.000046 20.497763)
		(end -24.943737 20.46205)
		(width 0.11176)
		(layer "In5.Cu")
		(net "SAS_B2_TX4N")
	)
	(arc
		(start -29.8704 28.749523)
		(mid -29.16107 25.183479)
		(end -27.141068 22.160334)
		(width 0.11176)
		(layer "In5.Cu")
		(net "SAS_B2_TX4N")
	)
	(arc
		(start -26.374072 21.393338)
		(mid -26.113622 21.219309)
		(end -25.8064 21.158197)
		(width 0.11176)
		(layer "In5.Cu")
		(net "SAS_B2_TX4N")
	)
	(arc
		(start -30.2006 36.0934)
		(mid -29.967113 35.996687)
		(end -29.8704 35.7632)
		(width 0.11176)
		(layer "In5.Cu")
		(net "SAS_B2_TX4N")
	)
	(arc
		(start -24.904476 20.441018)
		(mid -24.850274 20.374845)
		(end -24.858739 20.289728)
		(width 0.11176)
		(layer "In5.Cu")
		(net "SAS_B2_TX4N")
	)
	(arc
		(start -30.68 35.614)
		(mid -30.539587 35.952987)
		(end -30.2006 36.0934)
		(width 0.11176)
		(layer "In5.Cu")
		(net "SAS_B2_TX4N")
	)
	(arc
		(start -25.8064 21.158197)
		(mid -25.67798 21.132654)
		(end -25.569111 21.059912)
		(width 0.11176)
		(layer "In5.Cu")
		(net "SAS_B2_TX4N")
	)
	(segment
		(start -27.5082 32.63932)
		(end -27.5082 31.9405)
		(width 0.11176)
		(layer "In5.Cu")
		(net "SAS_B2_TX3P")
	)
	(segment
		(start -28.680001 39.860002)
		(end -28.680001 39.703601)
		(width 0.11176)
		(layer "In5.Cu")
		(net "SAS_B2_TX3P")
	)
	(segment
		(start -24.742557 24.543276)
		(end -24.742554 24.543273)
		(width 0.11176)
		(layer "In5.Cu")
		(net "SAS_B2_TX3P")
	)
	(segment
		(start -27.44502 31.525159)
		(end -27.5082 31.461979)
		(width 0.11176)
		(layer "In5.Cu")
		(net "SAS_B2_TX3P")
	)
	(segment
		(start -27.5082 38.7096)
		(end -27.5082 33.43116)
		(width 0.11176)
		(layer "In5.Cu")
		(net "SAS_B2_TX3P")
	)
	(segment
		(start -27.27706 33.20002)
		(end -27.27706 32.87046)
		(width 0.11176)
		(layer "In5.Cu")
		(net "SAS_B2_TX3P")
	)
	(segment
		(start -27.251177 25.84878)
		(end -27.180306 25.777909)
		(width 0.11176)
		(layer "In5.Cu")
		(net "SAS_B2_TX3P")
	)
	(segment
		(start -24.591264 24.589014)
		(end -24.350002 25.039371)
		(width 0.11176)
		(layer "In5.Cu")
		(net "SAS_B2_TX3P")
	)
	(segment
		(start -28.321 39.3446)
		(end -28.1432 39.3446)
		(width 0.11176)
		(layer "In5.Cu")
		(net "SAS_B2_TX3P")
	)
	(segment
		(start -27.5082 31.9405)
		(end -27.44502 31.87732)
		(width 0.11176)
		(layer "In5.Cu")
		(net "SAS_B2_TX3P")
	)
	(segment
		(start -24.826504 24.588249)
		(end -24.742557 24.543276)
		(width 0.11176)
		(layer "In5.Cu")
		(net "SAS_B2_TX3P")
	)
	(segment
		(start -25.272558 25.027539)
		(end -24.852754 24.607736)
		(width 0.11176)
		(layer "In5.Cu")
		(net "SAS_B2_TX3P")
	)
	(segment
		(start -27.5082 31.461979)
		(end -27.5082 26.469284)
		(width 0.11176)
		(layer "In5.Cu")
		(net "SAS_B2_TX3P")
	)
	(segment
		(start -26.390603 25.4508)
		(end -26.2944 25.4508)
		(width 0.11176)
		(layer "In5.Cu")
		(net "SAS_B2_TX3P")
	)
	(segment
		(start -27.44502 31.87732)
		(end -27.44502 31.525159)
		(width 0.11176)
		(layer "In5.Cu")
		(net "SAS_B2_TX3P")
	)
	(arc
		(start -27.412 33.33496)
		(mid -27.316583 33.295437)
		(end -27.27706 33.20002)
		(width 0.11176)
		(layer "In5.Cu")
		(net "SAS_B2_TX3P")
	)
	(arc
		(start -28.1432 39.3446)
		(mid -27.694187 39.158613)
		(end -27.5082 38.7096)
		(width 0.11176)
		(layer "In5.Cu")
		(net "SAS_B2_TX3P")
	)
	(arc
		(start -27.40184 32.74568)
		(mid -27.477048 32.714528)
		(end -27.5082 32.63932)
		(width 0.11176)
		(layer "In5.Cu")
		(net "SAS_B2_TX3P")
	)
	(arc
		(start -28.680001 39.703601)
		(mid -28.574852 39.449749)
		(end -28.321 39.3446)
		(width 0.11176)
		(layer "In5.Cu")
		(net "SAS_B2_TX3P")
	)
	(arc
		(start -26.2944 25.4508)
		(mid -25.741383 25.340798)
		(end -25.272558 25.027539)
		(width 0.11176)
		(layer "In5.Cu")
		(net "SAS_B2_TX3P")
	)
	(arc
		(start -27.5082 26.469284)
		(mid -27.441401 26.13347)
		(end -27.251177 25.84878)
		(width 0.11176)
		(layer "In5.Cu")
		(net "SAS_B2_TX3P")
	)
	(arc
		(start -27.5082 33.43116)
		(mid -27.480024 33.363136)
		(end -27.412 33.33496)
		(width 0.11176)
		(layer "In5.Cu")
		(net "SAS_B2_TX3P")
	)
	(arc
		(start -27.27706 32.87046)
		(mid -27.313607 32.782227)
		(end -27.40184 32.74568)
		(width 0.11176)
		(layer "In5.Cu")
		(net "SAS_B2_TX3P")
	)
	(arc
		(start -27.180306 25.777909)
		(mid -26.817987 25.535814)
		(end -26.390603 25.4508)
		(width 0.11176)
		(layer "In5.Cu")
		(net "SAS_B2_TX3P")
	)
	(arc
		(start -24.742554 24.543273)
		(mid -24.657436 24.534811)
		(end -24.591264 24.589014)
		(width 0.11176)
		(layer "In5.Cu")
		(net "SAS_B2_TX3P")
	)
	(arc
		(start -24.852754 24.607736)
		(mid -24.840345 24.597028)
		(end -24.826504 24.588249)
		(width 0.11176)
		(layer "In5.Cu")
		(net "SAS_B2_TX3P")
	)
	(segment
		(start -25.515026 24.785071)
		(end -25.09522 24.365265)
		(width 0.11176)
		(layer "In5.Cu")
		(net "SAS_B2_TX3N")
	)
	(segment
		(start -24.958731 24.270078)
		(end -24.904479 24.241016)
		(width 0.11176)
		(layer "In5.Cu")
		(net "SAS_B2_TX3N")
	)
	(segment
		(start -27.8511 38.7096)
		(end -27.8511 26.469282)
		(width 0.11176)
		(layer "In5.Cu")
		(net "SAS_B2_TX3N")
	)
	(segment
		(start -28.680001 38.460002)
		(end -28.680001 38.642699)
		(width 0.11176)
		(layer "In5.Cu")
		(net "SAS_B2_TX3N")
	)
	(segment
		(start -27.493646 25.606312)
		(end -27.422775 25.53544)
		(width 0.11176)
		(layer "In5.Cu")
		(net "SAS_B2_TX3N")
	)
	(segment
		(start -26.3906 25.1079)
		(end -26.294398 25.1079)
		(width 0.11176)
		(layer "In5.Cu")
		(net "SAS_B2_TX3N")
	)
	(segment
		(start -24.904479 24.241016)
		(end -24.904476 24.241016)
		(width 0.11176)
		(layer "In5.Cu")
		(net "SAS_B2_TX3N")
	)
	(segment
		(start -24.858739 24.089726)
		(end -25.100001 23.639371)
		(width 0.11176)
		(layer "In5.Cu")
		(net "SAS_B2_TX3N")
	)
	(segment
		(start -28.321 39.0017)
		(end -28.1432 39.0017)
		(width 0.11176)
		(layer "In5.Cu")
		(net "SAS_B2_TX3N")
	)
	(segment
		(start -24.988429 24.285989)
		(end -24.958731 24.270078)
		(width 0.11176)
		(layer "In5.Cu")
		(net "SAS_B2_TX3N")
	)
	(arc
		(start -25.09522 24.365265)
		(mid -25.044739 24.321701)
		(end -24.988429 24.285989)
		(width 0.11176)
		(layer "In5.Cu")
		(net "SAS_B2_TX3N")
	)
	(arc
		(start -28.1432 39.0017)
		(mid -27.936654 38.916146)
		(end -27.8511 38.7096)
		(width 0.11176)
		(layer "In5.Cu")
		(net "SAS_B2_TX3N")
	)
	(arc
		(start -26.294398 25.1079)
		(mid -25.872605 25.023998)
		(end -25.515026 24.785071)
		(width 0.11176)
		(layer "In5.Cu")
		(net "SAS_B2_TX3N")
	)
	(arc
		(start -27.422775 25.53544)
		(mid -26.949209 25.219013)
		(end -26.3906 25.1079)
		(width 0.11176)
		(layer "In5.Cu")
		(net "SAS_B2_TX3N")
	)
	(arc
		(start -24.904476 24.241016)
		(mid -24.850274 24.174843)
		(end -24.858739 24.089726)
		(width 0.11176)
		(layer "In5.Cu")
		(net "SAS_B2_TX3N")
	)
	(arc
		(start -28.680001 38.642699)
		(mid -28.574852 38.896551)
		(end -28.321 39.0017)
		(width 0.11176)
		(layer "In5.Cu")
		(net "SAS_B2_TX3N")
	)
	(arc
		(start -27.8511 26.469282)
		(mid -27.7582 26.002246)
		(end -27.493646 25.606312)
		(width 0.11176)
		(layer "In5.Cu")
		(net "SAS_B2_TX3N")
	)
	(segment
		(start -24.350734 35.597534)
		(end -24.590891 35.837691)
		(width 0.10668)
		(layer "B.Cu")
		(net "SAS_B2_TX2P")
	)
	(segment
		(start -23.81583 35.01183)
		(end -24.059777 35.01183)
		(width 0.10668)
		(layer "B.Cu")
		(net "SAS_B2_TX2P")
	)
	(segment
		(start -22.466501 20.781188)
		(end -22.54662 20.824106)
		(width 0.10668)
		(layer "B.Cu")
		(net "SAS_B2_TX2P")
	)
	(segment
		(start -23.524873 34.720873)
		(end -23.81583 35.01183)
		(width 0.10668)
		(layer "B.Cu")
		(net "SAS_B2_TX2P")
	)
	(segment
		(start -19.633113 22.891885)
		(end -19.162415 23.362582)
		(width 0.10668)
		(layer "B.Cu")
		(net "SAS_B2_TX2P")
	)
	(segment
		(start -24.885637 35.837691)
		(end -25.321473 36.273527)
		(width 0.10668)
		(layer "B.Cu")
		(net "SAS_B2_TX2P")
	)
	(segment
		(start -22.259155 22.1234)
		(end -21.4884 22.1234)
		(width 0.10668)
		(layer "B.Cu")
		(net "SAS_B2_TX2P")
	)
	(segment
		(start -23.524873 34.598902)
		(end -23.524873 34.720873)
		(width 0.10668)
		(layer "B.Cu")
		(net "SAS_B2_TX2P")
	)
	(segment
		(start -23.524878 34.476931)
		(end -23.524873 34.598902)
		(width 0.10668)
		(layer "B.Cu")
		(net "SAS_B2_TX2P")
	)
	(segment
		(start -22.466488 20.78118)
		(end -22.466501 20.781188)
		(width 0.10668)
		(layer "B.Cu")
		(net "SAS_B2_TX2P")
	)
	(segment
		(start -18.6236 24.6634)
		(end -18.6236 26.6954)
		(width 0.10668)
		(layer "B.Cu")
		(net "SAS_B2_TX2P")
	)
	(segment
		(start -25.81256 36.47694)
		(end -26.19694 36.47694)
		(width 0.10668)
		(layer "B.Cu")
		(net "SAS_B2_TX2P")
	)
	(segment
		(start -22.466485 20.78118)
		(end -22.466488 20.78118)
		(width 0.10668)
		(layer "B.Cu")
		(net "SAS_B2_TX2P")
	)
	(segment
		(start -24.590891 35.837691)
		(end -24.885637 35.837691)
		(width 0.10668)
		(layer "B.Cu")
		(net "SAS_B2_TX2P")
	)
	(segment
		(start -20.660243 31.612294)
		(end -23.524878 34.476931)
		(width 0.10668)
		(layer "B.Cu")
		(net "SAS_B2_TX2P")
	)
	(segment
		(start -24.350734 35.302787)
		(end -24.350734 35.597534)
		(width 0.10668)
		(layer "B.Cu")
		(net "SAS_B2_TX2P")
	)
	(segment
		(start -24.059777 35.01183)
		(end -24.350734 35.302787)
		(width 0.10668)
		(layer "B.Cu")
		(net "SAS_B2_TX2P")
	)
	(segment
		(start -22.571677 20.842709)
		(end -22.587537 20.858569)
		(width 0.10668)
		(layer "B.Cu")
		(net "SAS_B2_TX2P")
	)
	(segment
		(start -22.100002 21.239371)
		(end -22.322074 20.824838)
		(width 0.10668)
		(layer "B.Cu")
		(net "SAS_B2_TX2P")
	)
	(arc
		(start -26.19694 36.47694)
		(mid -26.538515 36.618425)
		(end -26.68 36.96)
		(width 0.10668)
		(layer "B.Cu")
		(net "SAS_B2_TX2P")
	)
	(arc
		(start -22.54662 20.824106)
		(mid -22.559832 20.832486)
		(end -22.571677 20.842709)
		(width 0.10668)
		(layer "B.Cu")
		(net "SAS_B2_TX2P")
	)
	(arc
		(start -21.4884 22.1234)
		(mid -20.484326 22.323123)
		(end -19.633113 22.891885)
		(width 0.10668)
		(layer "B.Cu")
		(net "SAS_B2_TX2P")
	)
	(arc
		(start -25.321473 36.273527)
		(mid -25.546786 36.424076)
		(end -25.81256 36.47694)
		(width 0.10668)
		(layer "B.Cu")
		(net "SAS_B2_TX2P")
	)
	(arc
		(start -19.162415 23.362582)
		(mid -18.763633 23.959403)
		(end -18.6236 24.6634)
		(width 0.10668)
		(layer "B.Cu")
		(net "SAS_B2_TX2P")
	)
	(arc
		(start -22.587537 20.858569)
		(mid -22.800741 21.12544)
		(end -22.949751 21.432804)
		(width 0.10668)
		(layer "B.Cu")
		(net "SAS_B2_TX2P")
	)
	(arc
		(start -22.322074 20.824838)
		(mid -22.385238 20.7731)
		(end -22.466485 20.78118)
		(width 0.10668)
		(layer "B.Cu")
		(net "SAS_B2_TX2P")
	)
	(arc
		(start -22.949751 21.432804)
		(mid -22.74748 21.921129)
		(end -22.259155 22.1234)
		(width 0.10668)
		(layer "B.Cu")
		(net "SAS_B2_TX2P")
	)
	(arc
		(start -18.6236 26.6954)
		(mid -19.152906 29.356404)
		(end -20.660243 31.612294)
		(width 0.10668)
		(layer "B.Cu")
		(net "SAS_B2_TX2P")
	)
	(segment
		(start -22.714311 20.421199)
		(end -22.671593 20.398316)
		(width 0.10668)
		(layer "B.Cu")
		(net "SAS_B2_TX2N")
	)
	(segment
		(start -22.62793 20.253902)
		(end -22.85 19.839371)
		(width 0.10668)
		(layer "B.Cu")
		(net "SAS_B2_TX2N")
	)
	(segment
		(start -25.6286 35.9664)
		(end -25.455121 35.792921)
		(width 0.10668)
		(layer "B.Cu")
		(net "SAS_B2_TX2N")
	)
	(segment
		(start -25.455121 35.792921)
		(end -25.332502 35.6703)
		(width 0.10668)
		(layer "B.Cu")
		(net "SAS_B2_TX2N")
	)
	(segment
		(start -22.751725 20.441242)
		(end -22.714311 20.421199)
		(width 0.10668)
		(layer "B.Cu")
		(net "SAS_B2_TX2N")
	)
	(segment
		(start -19.05794 26.6954)
		(end -19.05794 24.663397)
		(width 0.10668)
		(layer "B.Cu")
		(net "SAS_B2_TX2N")
	)
	(segment
		(start -25.332502 35.6703)
		(end -20.96737 31.305167)
		(width 0.10668)
		(layer "B.Cu")
		(net "SAS_B2_TX2N")
	)
	(segment
		(start -26.1974 36.0426)
		(end -25.812562 36.0426)
		(width 0.10668)
		(layer "B.Cu")
		(net "SAS_B2_TX2N")
	)
	(segment
		(start -22.671593 20.398316)
		(end -22.67159 20.398313)
		(width 0.10668)
		(layer "B.Cu")
		(net "SAS_B2_TX2N")
	)
	(segment
		(start -21.488403 22.55774)
		(end -22.259155 22.55774)
		(width 0.10668)
		(layer "B.Cu")
		(net "SAS_B2_TX2N")
	)
	(segment
		(start -19.469542 23.669709)
		(end -19.94024 23.199011)
		(width 0.10668)
		(layer "B.Cu")
		(net "SAS_B2_TX2N")
	)
	(segment
		(start -22.894663 20.551442)
		(end -22.878806 20.535585)
		(width 0.10668)
		(layer "B.Cu")
		(net "SAS_B2_TX2N")
	)
	(arc
		(start -23.38134 21.354156)
		(mid -23.186471 20.923412)
		(end -22.894663 20.551442)
		(width 0.10668)
		(layer "B.Cu")
		(net "SAS_B2_TX2N")
	)
	(arc
		(start -22.67159 20.398313)
		(mid -22.619851 20.33515)
		(end -22.62793 20.253902)
		(width 0.10668)
		(layer "B.Cu")
		(net "SAS_B2_TX2N")
	)
	(arc
		(start -19.94024 23.199011)
		(mid -20.650543 22.724401)
		(end -21.488403 22.55774)
		(width 0.10668)
		(layer "B.Cu")
		(net "SAS_B2_TX2N")
	)
	(arc
		(start -26.68 35.56)
		(mid -26.53865 35.90125)
		(end -26.1974 36.0426)
		(width 0.10668)
		(layer "B.Cu")
		(net "SAS_B2_TX2N")
	)
	(arc
		(start -22.878806 20.535585)
		(mid -22.818734 20.483741)
		(end -22.751725 20.441242)
		(width 0.10668)
		(layer "B.Cu")
		(net "SAS_B2_TX2N")
	)
	(arc
		(start -25.812562 36.0426)
		(mid -25.713002 36.022796)
		(end -25.6286 35.9664)
		(width 0.10668)
		(layer "B.Cu")
		(net "SAS_B2_TX2N")
	)
	(arc
		(start -19.469374 23.669879)
		(mid -19.469458 23.669794)
		(end -19.469542 23.669709)
		(width 0.10668)
		(layer "B.Cu")
		(net "SAS_B2_TX2N")
	)
	(arc
		(start -22.259155 22.55774)
		(mid -23.081942 22.199944)
		(end -23.38134 21.354156)
		(width 0.10668)
		(layer "B.Cu")
		(net "SAS_B2_TX2N")
	)
	(arc
		(start -19.05794 24.663397)
		(mid -19.164868 24.125728)
		(end -19.469374 23.669879)
		(width 0.10668)
		(layer "B.Cu")
		(net "SAS_B2_TX2N")
	)
	(arc
		(start -20.96737 31.305167)
		(mid -19.554186 29.190188)
		(end -19.05794 26.6954)
		(width 0.10668)
		(layer "B.Cu")
		(net "SAS_B2_TX2N")
	)
	(segment
		(start -26.2128 44.831452)
		(end -25.780997 44.831452)
		(width 0.11176)
		(layer "In5.Cu")
		(net "SAS_B2_TX1P")
	)
	(segment
		(start -22.576503 24.588249)
		(end -22.492556 24.543276)
		(width 0.11176)
		(layer "In5.Cu")
		(net "SAS_B2_TX1P")
	)
	(segment
		(start -23.368 42.037)
		(end -23.37054 42.037)
		(width 0.11176)
		(layer "In5.Cu")
		(net "SAS_B2_TX1P")
	)
	(segment
		(start -23.4823 38.696339)
		(end -23.4823 26.137453)
		(width 0.11176)
		(layer "In5.Cu")
		(net "SAS_B2_TX1P")
	)
	(segment
		(start -23.25624 40.88384)
		(end -23.25624 40.49776)
		(width 0.11176)
		(layer "In5.Cu")
		(net "SAS_B2_TX1P")
	)
	(segment
		(start -22.492556 24.543276)
		(end -22.492553 24.543273)
		(width 0.11176)
		(layer "In5.Cu")
		(net "SAS_B2_TX1P")
	)
	(segment
		(start -23.25624 42.45864)
		(end -23.25624 42.14876)
		(width 0.11176)
		(layer "In5.Cu")
		(net "SAS_B2_TX1P")
	)
	(segment
		(start -23.022557 25.027539)
		(end -22.602754 24.607736)
		(width 0.11176)
		(layer "In5.Cu")
		(net "SAS_B2_TX1P")
	)
	(segment
		(start -23.4823 42.947793)
		(end -23.4823 42.6847)
		(width 0.11176)
		(layer "In5.Cu")
		(net "SAS_B2_TX1P")
	)
	(segment
		(start -23.4823 40.2717)
		(end -23.4823 39.392299)
		(width 0.11176)
		(layer "In5.Cu")
		(net "SAS_B2_TX1P")
	)
	(segment
		(start -23.2918 38.886839)
		(end -23.4823 38.696339)
		(width 0.11176)
		(layer "In5.Cu")
		(net "SAS_B2_TX1P")
	)
	(segment
		(start -26.68 45.360001)
		(end -26.68 45.298652)
		(width 0.11176)
		(layer "In5.Cu")
		(net "SAS_B2_TX1P")
	)
	(segment
		(start -24.216812 44.183544)
		(end -23.836732 43.803468)
		(width 0.11176)
		(layer "In5.Cu")
		(net "SAS_B2_TX1P")
	)
	(segment
		(start -22.341263 24.589014)
		(end -22.100002 25.039371)
		(width 0.11176)
		(layer "In5.Cu")
		(net "SAS_B2_TX1P")
	)
	(segment
		(start -23.4823 39.392299)
		(end -23.2918 39.201799)
		(width 0.11176)
		(layer "In5.Cu")
		(net "SAS_B2_TX1P")
	)
	(segment
		(start -23.4823 41.92524)
		(end -23.4823 41.1099)
		(width 0.11176)
		(layer "In5.Cu")
		(net "SAS_B2_TX1P")
	)
	(segment
		(start -23.2918 39.201799)
		(end -23.2918 38.886839)
		(width 0.11176)
		(layer "In5.Cu")
		(net "SAS_B2_TX1P")
	)
	(arc
		(start -23.4823 42.6847)
		(mid -23.456262 42.621838)
		(end -23.3934 42.5958)
		(width 0.11176)
		(layer "In5.Cu")
		(net "SAS_B2_TX1P")
	)
	(arc
		(start -22.602754 24.607736)
		(mid -22.590345 24.597027)
		(end -22.576503 24.588249)
		(width 0.11176)
		(layer "In5.Cu")
		(net "SAS_B2_TX1P")
	)
	(arc
		(start -23.25624 40.49776)
		(mid -23.296413 40.400773)
		(end -23.3934 40.3606)
		(width 0.11176)
		(layer "In5.Cu")
		(net "SAS_B2_TX1P")
	)
	(arc
		(start -23.37054 42.037)
		(mid -23.449566 42.004266)
		(end -23.4823 41.92524)
		(width 0.11176)
		(layer "In5.Cu")
		(net "SAS_B2_TX1P")
	)
	(arc
		(start -23.4823 26.137453)
		(mid -23.362817 25.536771)
		(end -23.022557 25.027539)
		(width 0.11176)
		(layer "In5.Cu")
		(net "SAS_B2_TX1P")
	)
	(arc
		(start -25.780997 44.831452)
		(mid -24.934467 44.663065)
		(end -24.216812 44.183544)
		(width 0.11176)
		(layer "In5.Cu")
		(net "SAS_B2_TX1P")
	)
	(arc
		(start -23.3934 40.3606)
		(mid -23.456262 40.334562)
		(end -23.4823 40.2717)
		(width 0.11176)
		(layer "In5.Cu")
		(net "SAS_B2_TX1P")
	)
	(arc
		(start -23.4823 41.1099)
		(mid -23.448822 41.029078)
		(end -23.368 40.9956)
		(width 0.11176)
		(layer "In5.Cu")
		(net "SAS_B2_TX1P")
	)
	(arc
		(start -23.25624 42.14876)
		(mid -23.288974 42.069734)
		(end -23.368 42.037)
		(width 0.11176)
		(layer "In5.Cu")
		(net "SAS_B2_TX1P")
	)
	(arc
		(start -23.368 40.9956)
		(mid -23.288974 40.962866)
		(end -23.25624 40.88384)
		(width 0.11176)
		(layer "In5.Cu")
		(net "SAS_B2_TX1P")
	)
	(arc
		(start -26.68 45.298652)
		(mid -26.54316 44.968292)
		(end -26.2128 44.831452)
		(width 0.11176)
		(layer "In5.Cu")
		(net "SAS_B2_TX1P")
	)
	(arc
		(start -23.836732 43.803468)
		(mid -23.574414 43.410881)
		(end -23.4823 42.947793)
		(width 0.11176)
		(layer "In5.Cu")
		(net "SAS_B2_TX1P")
	)
	(arc
		(start -22.492553 24.543273)
		(mid -22.407435 24.534811)
		(end -22.341263 24.589014)
		(width 0.11176)
		(layer "In5.Cu")
		(net "SAS_B2_TX1P")
	)
	(arc
		(start -23.3934 42.5958)
		(mid -23.296413 42.555627)
		(end -23.25624 42.45864)
		(width 0.11176)
		(layer "In5.Cu")
		(net "SAS_B2_TX1P")
	)
	(segment
		(start -22.654476 24.241016)
		(end -22.654478 24.241016)
		(width 0.11176)
		(layer "In5.Cu")
		(net "SAS_B2_TX1N")
	)
	(segment
		(start -23.8252 26.137451)
		(end -23.8252 42.947791)
		(width 0.11176)
		(layer "In5.Cu")
		(net "SAS_B2_TX1N")
	)
	(segment
		(start -22.70873 24.270078)
		(end -22.738428 24.285989)
		(width 0.11176)
		(layer "In5.Cu")
		(net "SAS_B2_TX1N")
	)
	(segment
		(start -26.68 44.021352)
		(end -26.68 43.960001)
		(width 0.11176)
		(layer "In5.Cu")
		(net "SAS_B2_TX1N")
	)
	(segment
		(start -24.0792 43.561)
		(end -24.459278 43.941075)
		(width 0.11176)
		(layer "In5.Cu")
		(net "SAS_B2_TX1N")
	)
	(segment
		(start -25.781 44.488552)
		(end -26.2128 44.488552)
		(width 0.11176)
		(layer "In5.Cu")
		(net "SAS_B2_TX1N")
	)
	(segment
		(start -22.654478 24.241016)
		(end -22.70873 24.270078)
		(width 0.11176)
		(layer "In5.Cu")
		(net "SAS_B2_TX1N")
	)
	(segment
		(start -22.85 23.639371)
		(end -22.608738 24.089726)
		(width 0.11176)
		(layer "In5.Cu")
		(net "SAS_B2_TX1N")
	)
	(segment
		(start -22.84522 24.365265)
		(end -23.265026 24.785071)
		(width 0.11176)
		(layer "In5.Cu")
		(net "SAS_B2_TX1N")
	)
	(arc
		(start -24.459278 43.941075)
		(mid -25.065689 44.346267)
		(end -25.781 44.488552)
		(width 0.11176)
		(layer "In5.Cu")
		(net "SAS_B2_TX1N")
	)
	(arc
		(start -23.8252 42.947791)
		(mid -23.891212 43.279658)
		(end -24.0792 43.561)
		(width 0.11176)
		(layer "In5.Cu")
		(net "SAS_B2_TX1N")
	)
	(arc
		(start -22.608738 24.089726)
		(mid -22.600274 24.174844)
		(end -22.654476 24.241016)
		(width 0.11176)
		(layer "In5.Cu")
		(net "SAS_B2_TX1N")
	)
	(arc
		(start -22.738428 24.285989)
		(mid -22.794738 24.321701)
		(end -22.84522 24.365265)
		(width 0.11176)
		(layer "In5.Cu")
		(net "SAS_B2_TX1N")
	)
	(arc
		(start -26.2128 44.488552)
		(mid -26.54316 44.351712)
		(end -26.68 44.021352)
		(width 0.11176)
		(layer "In5.Cu")
		(net "SAS_B2_TX1N")
	)
	(arc
		(start -23.265026 24.785071)
		(mid -23.679616 25.405548)
		(end -23.8252 26.137451)
		(width 0.11176)
		(layer "In5.Cu")
		(net "SAS_B2_TX1N")
	)
	(segment
		(start -37.539376 11.756039)
		(end -37.242633 11.459296)
		(width 0.11176)
		(layer "In5.Cu")
		(net "SAS_B2_RX8P")
	)
	(segment
		(start -38.0419 13.081003)
		(end -38.0419 12.969245)
		(width 0.11176)
		(layer "In5.Cu")
		(net "SAS_B2_RX8P")
	)
	(segment
		(start -35.520828 13.024498)
		(end -35.520838 13.024503)
		(width 0.11176)
		(layer "In5.Cu")
		(net "SAS_B2_RX8P")
	)
	(segment
		(start -35.591262 13.189016)
		(end -35.35 13.639371)
		(width 0.11176)
		(layer "In5.Cu")
		(net "SAS_B2_RX8P")
	)
	(segment
		(start -37.191 43.5229)
		(end -39.223 43.5229)
		(width 0.11176)
		(layer "In5.Cu")
		(net "SAS_B2_RX8P")
	)
	(segment
		(start -35.179 11.3157)
		(end -34.945312 11.549388)
		(width 0.11176)
		(layer "In5.Cu")
		(net "SAS_B2_RX8P")
	)
	(segment
		(start -40.8359 41.91)
		(end -40.8359 18.761443)
		(width 0.11176)
		(layer "In5.Cu")
		(net "SAS_B2_RX8P")
	)
	(segment
		(start -34.945312 12.47649)
		(end -35.414041 12.945219)
		(width 0.11176)
		(layer "In5.Cu")
		(net "SAS_B2_RX8P")
	)
	(segment
		(start -35.545522 13.037726)
		(end -35.545525 13.037726)
		(width 0.11176)
		(layer "In5.Cu")
		(net "SAS_B2_RX8P")
	)
	(segment
		(start -39.592468 15.759532)
		(end -38.839493 15.006559)
		(width 0.11176)
		(layer "In5.Cu")
		(net "SAS_B2_RX8P")
	)
	(segment
		(start -36.68 44.060001)
		(end -36.68 44.0339)
		(width 0.11176)
		(layer "In5.Cu")
		(net "SAS_B2_RX8P")
	)
	(segment
		(start -35.520838 13.024503)
		(end -35.545522 13.037726)
		(width 0.11176)
		(layer "In5.Cu")
		(net "SAS_B2_RX8P")
	)
	(arc
		(start -38.839493 15.006559)
		(mid -38.249188 14.123106)
		(end -38.0419 13.081003)
		(width 0.11176)
		(layer "In5.Cu")
		(net "SAS_B2_RX8P")
	)
	(arc
		(start -35.545525 13.037726)
		(mid -35.599727 13.103899)
		(end -35.591262 13.189016)
		(width 0.11176)
		(layer "In5.Cu")
		(net "SAS_B2_RX8P")
	)
	(arc
		(start -36.68 44.0339)
		(mid -36.829668 43.672568)
		(end -37.191 43.5229)
		(width 0.11176)
		(layer "In5.Cu")
		(net "SAS_B2_RX8P")
	)
	(arc
		(start -35.414041 12.945219)
		(mid -35.46452 12.988784)
		(end -35.520828 13.024498)
		(width 0.11176)
		(layer "In5.Cu")
		(net "SAS_B2_RX8P")
	)
	(arc
		(start -40.8359 18.761443)
		(mid -40.512743 17.13682)
		(end -39.592468 15.759532)
		(width 0.11176)
		(layer "In5.Cu")
		(net "SAS_B2_RX8P")
	)
	(arc
		(start -37.242633 11.459296)
		(mid -36.689712 11.089835)
		(end -36.037492 10.960097)
		(width 0.11176)
		(layer "In5.Cu")
		(net "SAS_B2_RX8P")
	)
	(arc
		(start -36.037492 10.960097)
		(mid -35.572879 11.052516)
		(end -35.179 11.3157)
		(width 0.11176)
		(layer "In5.Cu")
		(net "SAS_B2_RX8P")
	)
	(arc
		(start -39.223 43.5229)
		(mid -40.363493 43.050493)
		(end -40.8359 41.91)
		(width 0.11176)
		(layer "In5.Cu")
		(net "SAS_B2_RX8P")
	)
	(arc
		(start -34.945312 11.549388)
		(mid -34.753303 12.012939)
		(end -34.945312 12.47649)
		(width 0.11176)
		(layer "In5.Cu")
		(net "SAS_B2_RX8P")
	)
	(arc
		(start -38.0419 12.969245)
		(mid -37.911299 12.312663)
		(end -37.539376 11.756039)
		(width 0.11176)
		(layer "In5.Cu")
		(net "SAS_B2_RX8P")
	)
	(segment
		(start -38.55752 43.18)
		(end -39.223 43.18)
		(width 0.11176)
		(layer "In5.Cu")
		(net "SAS_B2_RX8N")
	)
	(segment
		(start -40.493 41.91)
		(end -40.493 41.45534)
		(width 0.11176)
		(layer "In5.Cu")
		(net "SAS_B2_RX8N")
	)
	(segment
		(start -40.26186 37.11702)
		(end -40.26186 36.69538)
		(width 0.11176)
		(layer "In5.Cu")
		(net "SAS_B2_RX8N")
	)
	(segment
		(start -38.51688 43.13936)
		(end -38.55752 43.18)
		(width 0.11176)
		(layer "In5.Cu")
		(net "SAS_B2_RX8N")
	)
	(segment
		(start -40.26186 39.15156)
		(end -40.26186 38.72992)
		(width 0.11176)
		(layer "In5.Cu")
		(net "SAS_B2_RX8N")
	)
	(segment
		(start -37.191 43.18)
		(end -38.024067 43.18)
		(width 0.11176)
		(layer "In5.Cu")
		(net "SAS_B2_RX8N")
	)
	(segment
		(start -36.68 42.660001)
		(end -36.68 42.669)
		(width 0.11176)
		(layer "In5.Cu")
		(net "SAS_B2_RX8N")
	)
	(segment
		(start -35.421468 11.558168)
		(end -35.187781 11.791856)
		(width 0.11176)
		(layer "In5.Cu")
		(net "SAS_B2_RX8N")
	)
	(segment
		(start -35.187781 12.234022)
		(end -35.65651 12.702751)
		(width 0.11176)
		(layer "In5.Cu")
		(net "SAS_B2_RX8N")
	)
	(segment
		(start -37.296908 11.998508)
		(end -37.0078 11.7094)
		(width 0.11176)
		(layer "In5.Cu")
		(net "SAS_B2_RX8N")
	)
	(segment
		(start -39.35 16.002)
		(end -38.597025 15.249027)
		(width 0.11176)
		(layer "In5.Cu")
		(net "SAS_B2_RX8N")
	)
	(segment
		(start -40.493 40.73144)
		(end -40.493 39.3827)
		(width 0.11176)
		(layer "In5.Cu")
		(net "SAS_B2_RX8N")
	)
	(segment
		(start -38.024067 43.18)
		(end -38.064707 43.13936)
		(width 0.11176)
		(layer "In5.Cu")
		(net "SAS_B2_RX8N")
	)
	(segment
		(start -40.26186 35.44062)
		(end -40.26186 35.13582)
		(width 0.11176)
		(layer "In5.Cu")
		(net "SAS_B2_RX8N")
	)
	(segment
		(start -40.493 36.46424)
		(end -40.493 35.67176)
		(width 0.11176)
		(layer "In5.Cu")
		(net "SAS_B2_RX8N")
	)
	(segment
		(start -35.65651 12.702751)
		(end -35.65651 12.702753)
		(width 0.11176)
		(layer "In5.Cu")
		(net "SAS_B2_RX8N")
	)
	(segment
		(start -40.26186 41.2242)
		(end -40.26186 40.96258)
		(width 0.11176)
		(layer "In5.Cu")
		(net "SAS_B2_RX8N")
	)
	(segment
		(start -37.0078 11.7094)
		(end -37.000144 11.701742)
		(width 0.11176)
		(layer "In5.Cu")
		(net "SAS_B2_RX8N")
	)
	(segment
		(start -37.699 13.081005)
		(end -37.699 12.969245)
		(width 0.11176)
		(layer "In5.Cu")
		(net "SAS_B2_RX8N")
	)
	(segment
		(start -35.85874 12.689728)
		(end -36.100001 12.239371)
		(width 0.11176)
		(layer "In5.Cu")
		(net "SAS_B2_RX8N")
	)
	(segment
		(start -35.705057 12.734183)
		(end -35.707447 12.735466)
		(width 0.11176)
		(layer "In5.Cu")
		(net "SAS_B2_RX8N")
	)
	(segment
		(start -40.493 38.49878)
		(end -40.493 37.34816)
		(width 0.11176)
		(layer "In5.Cu")
		(net "SAS_B2_RX8N")
	)
	(segment
		(start -35.682758 12.722238)
		(end -35.705057 12.734183)
		(width 0.11176)
		(layer "In5.Cu")
		(net "SAS_B2_RX8N")
	)
	(segment
		(start -38.064707 43.13936)
		(end -38.51688 43.13936)
		(width 0.11176)
		(layer "In5.Cu")
		(net "SAS_B2_RX8N")
	)
	(segment
		(start -35.707447 12.735466)
		(end -35.70745 12.735469)
		(width 0.11176)
		(layer "In5.Cu")
		(net "SAS_B2_RX8N")
	)
	(segment
		(start -40.493 34.90468)
		(end -40.493 18.761446)
		(width 0.11176)
		(layer "In5.Cu")
		(net "SAS_B2_RX8N")
	)
	(arc
		(start -40.493 37.34816)
		(mid -40.466218 37.283502)
		(end -40.40156 37.25672)
		(width 0.11176)
		(layer "In5.Cu")
		(net "SAS_B2_RX8N")
	)
	(arc
		(start -39.223 43.18)
		(mid -40.121026 42.808026)
		(end -40.493 41.91)
		(width 0.11176)
		(layer "In5.Cu")
		(net "SAS_B2_RX8N")
	)
	(arc
		(start -40.26186 40.96258)
		(mid -40.306497 40.854817)
		(end -40.41426 40.81018)
		(width 0.11176)
		(layer "In5.Cu")
		(net "SAS_B2_RX8N")
	)
	(arc
		(start -40.40664 41.36898)
		(mid -40.304265 41.326575)
		(end -40.26186 41.2242)
		(width 0.11176)
		(layer "In5.Cu")
		(net "SAS_B2_RX8N")
	)
	(arc
		(start -40.40156 37.25672)
		(mid -40.302777 37.215803)
		(end -40.26186 37.11702)
		(width 0.11176)
		(layer "In5.Cu")
		(net "SAS_B2_RX8N")
	)
	(arc
		(start -35.70745 12.735469)
		(mid -35.792568 12.743931)
		(end -35.85874 12.689728)
		(width 0.11176)
		(layer "In5.Cu")
		(net "SAS_B2_RX8N")
	)
	(arc
		(start -40.41426 40.81018)
		(mid -40.469938 40.787118)
		(end -40.493 40.73144)
		(width 0.11176)
		(layer "In5.Cu")
		(net "SAS_B2_RX8N")
	)
	(arc
		(start -40.493 41.45534)
		(mid -40.467706 41.394274)
		(end -40.40664 41.36898)
		(width 0.11176)
		(layer "In5.Cu")
		(net "SAS_B2_RX8N")
	)
	(arc
		(start -40.40156 38.59022)
		(mid -40.466218 38.563438)
		(end -40.493 38.49878)
		(width 0.11176)
		(layer "In5.Cu")
		(net "SAS_B2_RX8N")
	)
	(arc
		(start -40.26186 35.13582)
		(mid -40.310961 35.017281)
		(end -40.4295 34.96818)
		(width 0.11176)
		(layer "In5.Cu")
		(net "SAS_B2_RX8N")
	)
	(arc
		(start -38.597025 15.249027)
		(mid -37.93239 14.25433)
		(end -37.699 13.081005)
		(width 0.11176)
		(layer "In5.Cu")
		(net "SAS_B2_RX8N")
	)
	(arc
		(start -35.65651 12.702753)
		(mid -35.668918 12.71346)
		(end -35.682758 12.722238)
		(width 0.11176)
		(layer "In5.Cu")
		(net "SAS_B2_RX8N")
	)
	(arc
		(start -37.000144 11.701742)
		(mid -36.558475 11.40663)
		(end -36.037492 11.303)
		(width 0.11176)
		(layer "In5.Cu")
		(net "SAS_B2_RX8N")
	)
	(arc
		(start -40.41934 35.5981)
		(mid -40.307985 35.551975)
		(end -40.26186 35.44062)
		(width 0.11176)
		(layer "In5.Cu")
		(net "SAS_B2_RX8N")
	)
	(arc
		(start -40.26186 36.69538)
		(mid -40.305753 36.589413)
		(end -40.41172 36.54552)
		(width 0.11176)
		(layer "In5.Cu")
		(net "SAS_B2_RX8N")
	)
	(arc
		(start -40.26186 38.72992)
		(mid -40.302777 38.631137)
		(end -40.40156 38.59022)
		(width 0.11176)
		(layer "In5.Cu")
		(net "SAS_B2_RX8N")
	)
	(arc
		(start -37.699 12.969245)
		(mid -37.5945 12.443886)
		(end -37.296908 11.998508)
		(width 0.11176)
		(layer "In5.Cu")
		(net "SAS_B2_RX8N")
	)
	(arc
		(start -40.39648 39.28618)
		(mid -40.301289 39.246751)
		(end -40.26186 39.15156)
		(width 0.11176)
		(layer "In5.Cu")
		(net "SAS_B2_RX8N")
	)
	(arc
		(start -35.187781 11.791856)
		(mid -35.096205 12.012939)
		(end -35.187781 12.234022)
		(width 0.11176)
		(layer "In5.Cu")
		(net "SAS_B2_RX8N")
	)
	(arc
		(start -40.493 35.67176)
		(mid -40.471425 35.619675)
		(end -40.41934 35.5981)
		(width 0.11176)
		(layer "In5.Cu")
		(net "SAS_B2_RX8N")
	)
	(arc
		(start -40.41172 36.54552)
		(mid -40.469194 36.521714)
		(end -40.493 36.46424)
		(width 0.11176)
		(layer "In5.Cu")
		(net "SAS_B2_RX8N")
	)
	(arc
		(start -40.493 18.761446)
		(mid -40.195944 17.268045)
		(end -39.35 16.002)
		(width 0.11176)
		(layer "In5.Cu")
		(net "SAS_B2_RX8N")
	)
	(arc
		(start -40.493 39.3827)
		(mid -40.46473 39.31445)
		(end -40.39648 39.28618)
		(width 0.11176)
		(layer "In5.Cu")
		(net "SAS_B2_RX8N")
	)
	(arc
		(start -36.68 42.669)
		(mid -36.829668 43.030332)
		(end -37.191 43.18)
		(width 0.11176)
		(layer "In5.Cu")
		(net "SAS_B2_RX8N")
	)
	(arc
		(start -40.4295 34.96818)
		(mid -40.474401 34.949581)
		(end -40.493 34.90468)
		(width 0.11176)
		(layer "In5.Cu")
		(net "SAS_B2_RX8N")
	)
	(arc
		(start -36.037492 11.303)
		(mid -35.704102 11.369317)
		(end -35.421468 11.558168)
		(width 0.11176)
		(layer "In5.Cu")
		(net "SAS_B2_RX8N")
	)
	(segment
		(start -35.399475 16.737416)
		(end -35.341695 16.679636)
		(width 0.11176)
		(layer "In5.Cu")
		(net "SAS_B2_RX7P")
	)
	(segment
		(start -39.6875 20.890997)
		(end -39.6875 32.790188)
		(width 0.11176)
		(layer "In5.Cu")
		(net "SAS_B2_RX7P")
	)
	(segment
		(start -35.117446 15.129154)
		(end -35.19075 15.05585)
		(width 0.11176)
		(layer "In5.Cu")
		(net "SAS_B2_RX7P")
	)
	(segment
		(start -35.75797 14.8209)
		(end -36.692655 14.8209)
		(width 0.11176)
		(layer "In5.Cu")
		(net "SAS_B2_RX7P")
	)
	(segment
		(start -35.545525 16.837724)
		(end -35.545522 16.837724)
		(width 0.11176)
		(layer "In5.Cu")
		(net "SAS_B2_RX7P")
	)
	(segment
		(start -35.545522 16.837724)
		(end -35.506261 16.81669)
		(width 0.11176)
		(layer "In5.Cu")
		(net "SAS_B2_RX7P")
	)
	(segment
		(start -37.007361 35.33264)
		(end -36.68 35.66)
		(width 0.11176)
		(layer "In5.Cu")
		(net "SAS_B2_RX7P")
	)
	(segment
		(start -35.35 17.439371)
		(end -35.591262 16.989014)
		(width 0.11176)
		(layer "In5.Cu")
		(net "SAS_B2_RX7P")
	)
	(segment
		(start -37.844943 35.1536)
		(end -37.4396 35.1536)
		(width 0.11176)
		(layer "In5.Cu")
		(net "SAS_B2_RX7P")
	)
	(segment
		(start -37.592 15.720245)
		(end -37.592 15.832008)
		(width 0.11176)
		(layer "In5.Cu")
		(net "SAS_B2_RX7P")
	)
	(segment
		(start -34.9558 15.748)
		(end -34.9558 15.5194)
		(width 0.11176)
		(layer "In5.Cu")
		(net "SAS_B2_RX7P")
	)
	(arc
		(start -35.19075 15.05585)
		(mid -35.450993 14.881961)
		(end -35.75797 14.8209)
		(width 0.11176)
		(layer "In5.Cu")
		(net "SAS_B2_RX7P")
	)
	(arc
		(start -37.4396 35.1536)
		(mid -37.205674 35.200131)
		(end -37.007361 35.33264)
		(width 0.11176)
		(layer "In5.Cu")
		(net "SAS_B2_RX7P")
	)
	(arc
		(start -38.8874 34.7218)
		(mid -38.409117 35.041379)
		(end -37.844943 35.1536)
		(width 0.11176)
		(layer "In5.Cu")
		(net "SAS_B2_RX7P")
	)
	(arc
		(start -37.656668 15.988132)
		(mid -39.159704 18.237586)
		(end -39.6875 20.890997)
		(width 0.11176)
		(layer "In5.Cu")
		(net "SAS_B2_RX7P")
	)
	(arc
		(start -39.6875 32.790188)
		(mid -39.479561 33.835569)
		(end -38.8874 34.7218)
		(width 0.11176)
		(layer "In5.Cu")
		(net "SAS_B2_RX7P")
	)
	(arc
		(start -35.341695 16.679636)
		(mid -35.056091 16.252198)
		(end -34.9558 15.748)
		(width 0.11176)
		(layer "In5.Cu")
		(net "SAS_B2_RX7P")
	)
	(arc
		(start -35.591262 16.989014)
		(mid -35.599727 16.903896)
		(end -35.545525 16.837724)
		(width 0.11176)
		(layer "In5.Cu")
		(net "SAS_B2_RX7P")
	)
	(arc
		(start -35.506261 16.81669)
		(mid -35.449954 16.780979)
		(end -35.399475 16.737416)
		(width 0.11176)
		(layer "In5.Cu")
		(net "SAS_B2_RX7P")
	)
	(arc
		(start -37.592 15.832008)
		(mid -37.608807 15.916501)
		(end -37.656668 15.988132)
		(width 0.11176)
		(layer "In5.Cu")
		(net "SAS_B2_RX7P")
	)
	(arc
		(start -36.692655 14.8209)
		(mid -37.328588 15.084312)
		(end -37.592 15.720245)
		(width 0.11176)
		(layer "In5.Cu")
		(net "SAS_B2_RX7P")
	)
	(arc
		(start -34.9558 15.5194)
		(mid -34.99781 15.3082)
		(end -35.117446 15.129154)
		(width 0.11176)
		(layer "In5.Cu")
		(net "SAS_B2_RX7P")
	)
	(segment
		(start -39.344597 27.076077)
		(end -39.344597 27.80284)
		(width 0.11176)
		(layer "In5.Cu")
		(net "SAS_B2_RX7N")
	)
	(segment
		(start -35.75797 15.1638)
		(end -36.692655 15.1638)
		(width 0.11176)
		(layer "In5.Cu")
		(net "SAS_B2_RX7N")
	)
	(segment
		(start -39.2611 30.5054)
		(end -39.2738 30.5054)
		(width 0.11176)
		(layer "In5.Cu")
		(net "SAS_B2_RX7N")
	)
	(segment
		(start -37.844941 34.8107)
		(end -37.4396 34.8107)
		(width 0.11176)
		(layer "In5.Cu")
		(net "SAS_B2_RX7N")
	)
	(segment
		(start -39.11378 29.94152)
		(end -39.11378 30.35808)
		(width 0.11176)
		(layer "In5.Cu")
		(net "SAS_B2_RX7N")
	)
	(segment
		(start -35.359912 15.371623)
		(end -35.433218 15.298318)
		(width 0.11176)
		(layer "In5.Cu")
		(net "SAS_B2_RX7N")
	)
	(segment
		(start -35.641938 16.494945)
		(end -35.584163 16.437168)
		(width 0.11176)
		(layer "In5.Cu")
		(net "SAS_B2_RX7N")
	)
	(segment
		(start -39.11346 24.499885)
		(end -39.11346 24.814845)
		(width 0.11176)
		(layer "In5.Cu")
		(net "SAS_B2_RX7N")
	)
	(segment
		(start -39.344597 25.04598)
		(end -39.344597 26.202963)
		(width 0.11176)
		(layer "In5.Cu")
		(net "SAS_B2_RX7N")
	)
	(segment
		(start -35.70745 16.535466)
		(end -35.707447 16.535464)
		(width 0.11176)
		(layer "In5.Cu")
		(net "SAS_B2_RX7N")
	)
	(segment
		(start -39.344597 30.576197)
		(end -39.344597 32.790188)
		(width 0.11176)
		(layer "In5.Cu")
		(net "SAS_B2_RX7N")
	)
	(segment
		(start -36.100001 16.039371)
		(end -35.85874 16.489726)
		(width 0.11176)
		(layer "In5.Cu")
		(net "SAS_B2_RX7N")
	)
	(segment
		(start -39.11346 24.814845)
		(end -39.344597 25.04598)
		(width 0.11176)
		(layer "In5.Cu")
		(net "SAS_B2_RX7N")
	)
	(segment
		(start -39.344597 20.891)
		(end -39.344597 24.26875)
		(width 0.11176)
		(layer "In5.Cu")
		(net "SAS_B2_RX7N")
	)
	(segment
		(start -37.082984 34.662986)
		(end -36.68 34.26)
		(width 0.11176)
		(layer "In5.Cu")
		(net "SAS_B2_RX7N")
	)
	(segment
		(start -35.2987 15.748003)
		(end -35.2987 15.5194)
		(width 0.11176)
		(layer "In5.Cu")
		(net "SAS_B2_RX7N")
	)
	(segment
		(start -39.11378 28.03144)
		(end -39.11378 28.59024)
		(width 0.11176)
		(layer "In5.Cu")
		(net "SAS_B2_RX7N")
	)
	(segment
		(start -35.298703 15.748)
		(end -35.2987 15.748003)
		(width 0.11176)
		(layer "In5.Cu")
		(net "SAS_B2_RX7N")
	)
	(segment
		(start -39.13156 26.416)
		(end -39.13156 26.86304)
		(width 0.11176)
		(layer "In5.Cu")
		(net "SAS_B2_RX7N")
	)
	(segment
		(start -39.344597 24.26875)
		(end -39.11346 24.499885)
		(width 0.11176)
		(layer "In5.Cu")
		(net "SAS_B2_RX7N")
	)
	(segment
		(start -39.344597 28.821057)
		(end -39.344597 29.710703)
		(width 0.11176)
		(layer "In5.Cu")
		(net "SAS_B2_RX7N")
	)
	(segment
		(start -39.232837 27.9146)
		(end -39.23062 27.9146)
		(width 0.11176)
		(layer "In5.Cu")
		(net "SAS_B2_RX7N")
	)
	(segment
		(start -35.70745 16.535464)
		(end -35.668189 16.51443)
		(width 0.11176)
		(layer "In5.Cu")
		(net "SAS_B2_RX7N")
	)
	(segment
		(start -35.707447 16.535464)
		(end -35.70745 16.535464)
		(width 0.11176)
		(layer "In5.Cu")
		(net "SAS_B2_RX7N")
	)
	(segment
		(start -39.3446 20.890997)
		(end -39.344597 20.891)
		(width 0.11176)
		(layer "In5.Cu")
		(net "SAS_B2_RX7N")
	)
	(segment
		(start -37.2491 15.720245)
		(end -37.2491 15.832005)
		(width 0.11176)
		(layer "In5.Cu")
		(net "SAS_B2_RX7N")
	)
	(arc
		(start -37.4396 34.8107)
		(mid -37.246601 34.772311)
		(end -37.082984 34.662986)
		(width 0.11176)
		(layer "In5.Cu")
		(net "SAS_B2_RX7N")
	)
	(arc
		(start -39.23062 27.9146)
		(mid -39.148002 27.948822)
		(end -39.11378 28.03144)
		(width 0.11176)
		(layer "In5.Cu")
		(net "SAS_B2_RX7N")
	)
	(arc
		(start -39.25602 29.79928)
		(mid -39.155441 29.840941)
		(end -39.11378 29.94152)
		(width 0.11176)
		(layer "In5.Cu")
		(net "SAS_B2_RX7N")
	)
	(arc
		(start -39.26364 26.28392)
		(mid -39.170245 26.322605)
		(end -39.13156 26.416)
		(width 0.11176)
		(layer "In5.Cu")
		(net "SAS_B2_RX7N")
	)
	(arc
		(start -39.344597 29.710703)
		(mid -39.318653 29.773336)
		(end -39.25602 29.79928)
		(width 0.11176)
		(layer "In5.Cu")
		(net "SAS_B2_RX7N")
	)
	(arc
		(start -35.2987 15.5194)
		(mid -35.314608 15.439423)
		(end -35.359912 15.371623)
		(width 0.11176)
		(layer "In5.Cu")
		(net "SAS_B2_RX7N")
	)
	(arc
		(start -38.644932 34.479332)
		(mid -38.277893 34.72458)
		(end -37.844941 34.8107)
		(width 0.11176)
		(layer "In5.Cu")
		(net "SAS_B2_RX7N")
	)
	(arc
		(start -37.4142 16.2306)
		(mid -38.842905 18.368808)
		(end -39.3446 20.890997)
		(width 0.11176)
		(layer "In5.Cu")
		(net "SAS_B2_RX7N")
	)
	(arc
		(start -39.344597 32.790188)
		(mid -39.16276 33.704346)
		(end -38.644932 34.479332)
		(width 0.11176)
		(layer "In5.Cu")
		(net "SAS_B2_RX7N")
	)
	(arc
		(start -36.692655 15.1638)
		(mid -37.086121 15.326779)
		(end -37.2491 15.720245)
		(width 0.11176)
		(layer "In5.Cu")
		(net "SAS_B2_RX7N")
	)
	(arc
		(start -35.85874 16.489726)
		(mid -35.792568 16.543929)
		(end -35.70745 16.535466)
		(width 0.11176)
		(layer "In5.Cu")
		(net "SAS_B2_RX7N")
	)
	(arc
		(start -39.24078 28.71724)
		(mid -39.31419 28.747647)
		(end -39.344597 28.821057)
		(width 0.11176)
		(layer "In5.Cu")
		(net "SAS_B2_RX7N")
	)
	(arc
		(start -39.13156 26.86304)
		(mid -39.168757 26.952843)
		(end -39.25856 26.99004)
		(width 0.11176)
		(layer "In5.Cu")
		(net "SAS_B2_RX7N")
	)
	(arc
		(start -39.11378 28.59024)
		(mid -39.150977 28.680043)
		(end -39.24078 28.71724)
		(width 0.11176)
		(layer "In5.Cu")
		(net "SAS_B2_RX7N")
	)
	(arc
		(start -39.2738 30.5054)
		(mid -39.323861 30.526136)
		(end -39.344597 30.576197)
		(width 0.11176)
		(layer "In5.Cu")
		(net "SAS_B2_RX7N")
	)
	(arc
		(start -37.2491 15.832005)
		(mid -37.292007 16.047723)
		(end -37.4142 16.2306)
		(width 0.11176)
		(layer "In5.Cu")
		(net "SAS_B2_RX7N")
	)
	(arc
		(start -35.668189 16.51443)
		(mid -35.654347 16.505653)
		(end -35.641938 16.494945)
		(width 0.11176)
		(layer "In5.Cu")
		(net "SAS_B2_RX7N")
	)
	(arc
		(start -35.584163 16.437168)
		(mid -35.372891 16.120975)
		(end -35.298703 15.748)
		(width 0.11176)
		(layer "In5.Cu")
		(net "SAS_B2_RX7N")
	)
	(arc
		(start -39.344597 26.202963)
		(mid -39.320885 26.260208)
		(end -39.26364 26.28392)
		(width 0.11176)
		(layer "In5.Cu")
		(net "SAS_B2_RX7N")
	)
	(arc
		(start -35.433218 15.298318)
		(mid -35.582215 15.19876)
		(end -35.75797 15.1638)
		(width 0.11176)
		(layer "In5.Cu")
		(net "SAS_B2_RX7N")
	)
	(arc
		(start -39.344597 27.80284)
		(mid -39.311863 27.881866)
		(end -39.232837 27.9146)
		(width 0.11176)
		(layer "In5.Cu")
		(net "SAS_B2_RX7N")
	)
	(arc
		(start -39.11378 30.35808)
		(mid -39.156929 30.462251)
		(end -39.2611 30.5054)
		(width 0.11176)
		(layer "In5.Cu")
		(net "SAS_B2_RX7N")
	)
	(arc
		(start -39.25856 26.99004)
		(mid -39.319397 27.01524)
		(end -39.344597 27.076077)
		(width 0.11176)
		(layer "In5.Cu")
		(net "SAS_B2_RX7N")
	)
	(segment
		(start -39.985 28.067)
		(end -39.88562 28.067)
		(width 0.10668)
		(layer "B.Cu")
		(net "SAS_B2_RX6P")
	)
	(segment
		(start -33.278407 13.080426)
		(end -33.278409 13.080426)
		(width 0.10668)
		(layer "B.Cu")
		(net "SAS_B2_RX6P")
	)
	(segment
		(start -33.278409 13.080426)
		(end -33.278412 13.080429)
		(width 0.10668)
		(layer "B.Cu")
		(net "SAS_B2_RX6P")
	)
	(segment
		(start -31.6611 14.52626)
		(end -30.791267 14.52626)
		(width 0.10668)
		(layer "B.Cu")
		(net "SAS_B2_RX6P")
	)
	(segment
		(start -39.88562 28.64358)
		(end -39.985 28.64358)
		(width 0.10668)
		(layer "B.Cu")
		(net "SAS_B2_RX6P")
	)
	(segment
		(start -34.679999 41.160002)
		(end -34.679999 41.116141)
		(width 0.10668)
		(layer "B.Cu")
		(net "SAS_B2_RX6P")
	)
	(segment
		(start -39.77894 28.9052)
		(end -39.77894 28.75026)
		(width 0.10668)
		(layer "B.Cu")
		(net "SAS_B2_RX6P")
	)
	(segment
		(start -39.77894 27.96032)
		(end -39.77894 26.24106)
		(width 0.10668)
		(layer "B.Cu")
		(net "SAS_B2_RX6P")
	)
	(segment
		(start -30.80798 11.45794)
		(end -32.0348 11.45794)
		(width 0.10668)
		(layer "B.Cu")
		(net "SAS_B2_RX6P")
	)
	(segment
		(start -39.77894 25.19394)
		(end -39.77894 16.71066)
		(width 0.10668)
		(layer "B.Cu")
		(net "SAS_B2_RX6P")
	)
	(segment
		(start -30.079 13.813993)
		(end -30.079 12.18692)
		(width 0.10668)
		(layer "B.Cu")
		(net "SAS_B2_RX6P")
	)
	(segment
		(start -39.9596 26.0096)
		(end -39.9596 25.4254)
		(width 0.10668)
		(layer "B.Cu")
		(net "SAS_B2_RX6P")
	)
	(segment
		(start -39.9596 25.4254)
		(end -39.814861 25.280661)
		(width 0.10668)
		(layer "B.Cu")
		(net "SAS_B2_RX6P")
	)
	(segment
		(start -40.1066 28.52198)
		(end -40.1066 28.1886)
		(width 0.10668)
		(layer "B.Cu")
		(net "SAS_B2_RX6P")
	)
	(segment
		(start -33.278407 13.080423)
		(end -33.278407 13.080426)
		(width 0.10668)
		(layer "B.Cu")
		(net "SAS_B2_RX6P")
	)
	(segment
		(start -33.322072 13.22484)
		(end -33.1 13.639371)
		(width 0.10668)
		(layer "B.Cu")
		(net "SAS_B2_RX6P")
	)
	(segment
		(start -33.01002 12.881983)
		(end -33.071209 12.943167)
		(width 0.10668)
		(layer "B.Cu")
		(net "SAS_B2_RX6P")
	)
	(segment
		(start -37.83584 14.76756)
		(end -33.806155 14.76756)
		(width 0.10668)
		(layer "B.Cu")
		(net "SAS_B2_RX6P")
	)
	(segment
		(start -35.1028 40.69334)
		(end -35.2806 40.69334)
		(width 0.10668)
		(layer "B.Cu")
		(net "SAS_B2_RX6P")
	)
	(segment
		(start -33.198278 13.037497)
		(end -33.278407 13.080423)
		(width 0.10668)
		(layer "B.Cu")
		(net "SAS_B2_RX6P")
	)
	(segment
		(start -35.89274 40.0812)
		(end -35.89274 32.16148)
		(width 0.10668)
		(layer "B.Cu")
		(net "SAS_B2_RX6P")
	)
	(segment
		(start -36.576 29.79674)
		(end -38.8874 29.79674)
		(width 0.10668)
		(layer "B.Cu")
		(net "SAS_B2_RX6P")
	)
	(segment
		(start -35.99942 32.0548)
		(end -36.05022 32.0548)
		(width 0.10668)
		(layer "B.Cu")
		(net "SAS_B2_RX6P")
	)
	(segment
		(start -36.1823 31.92272)
		(end -36.1823 31.5595)
		(width 0.10668)
		(layer "B.Cu")
		(net "SAS_B2_RX6P")
	)
	(segment
		(start -35.89274 31.26994)
		(end -35.89274 30.48)
		(width 0.10668)
		(layer "B.Cu")
		(net "SAS_B2_RX6P")
	)
	(segment
		(start -39.814861 26.154339)
		(end -39.9596 26.0096)
		(width 0.10668)
		(layer "B.Cu")
		(net "SAS_B2_RX6P")
	)
	(arc
		(start -34.679999 41.116141)
		(mid -34.803835 40.817176)
		(end -35.1028 40.69334)
		(width 0.10668)
		(layer "B.Cu")
		(net "SAS_B2_RX6P")
	)
	(arc
		(start -39.77894 28.75026)
		(mid -39.810186 28.674826)
		(end -39.88562 28.64358)
		(width 0.10668)
		(layer "B.Cu")
		(net "SAS_B2_RX6P")
	)
	(arc
		(start -33.0835 14.5669)
		(mid -32.37259 14.536422)
		(end -31.6611 14.52626)
		(width 0.10668)
		(layer "B.Cu")
		(net "SAS_B2_RX6P")
	)
	(arc
		(start -39.985 28.64358)
		(mid -40.070984 28.607964)
		(end -40.1066 28.52198)
		(width 0.10668)
		(layer "B.Cu")
		(net "SAS_B2_RX6P")
	)
	(arc
		(start -33.278412 13.080429)
		(mid -33.33015 13.143592)
		(end -33.322072 13.22484)
		(width 0.10668)
		(layer "B.Cu")
		(net "SAS_B2_RX6P")
	)
	(arc
		(start -30.791267 14.52626)
		(mid -30.287618 14.317642)
		(end -30.079 13.813993)
		(width 0.10668)
		(layer "B.Cu")
		(net "SAS_B2_RX6P")
	)
	(arc
		(start -40.1066 28.1886)
		(mid -40.070984 28.102616)
		(end -39.985 28.067)
		(width 0.10668)
		(layer "B.Cu")
		(net "SAS_B2_RX6P")
	)
	(arc
		(start -33.57132 14.715432)
		(mid -33.332666 14.623903)
		(end -33.0835 14.5669)
		(width 0.10668)
		(layer "B.Cu")
		(net "SAS_B2_RX6P")
	)
	(arc
		(start -39.77894 26.24106)
		(mid -39.788276 26.194127)
		(end -39.814861 26.154339)
		(width 0.10668)
		(layer "B.Cu")
		(net "SAS_B2_RX6P")
	)
	(arc
		(start -35.89274 32.16148)
		(mid -35.923986 32.086046)
		(end -35.99942 32.0548)
		(width 0.10668)
		(layer "B.Cu")
		(net "SAS_B2_RX6P")
	)
	(arc
		(start -39.814861 25.280661)
		(mid -39.788275 25.240873)
		(end -39.77894 25.19394)
		(width 0.10668)
		(layer "B.Cu")
		(net "SAS_B2_RX6P")
	)
	(arc
		(start -39.88562 28.067)
		(mid -39.810186 28.035754)
		(end -39.77894 27.96032)
		(width 0.10668)
		(layer "B.Cu")
		(net "SAS_B2_RX6P")
	)
	(arc
		(start -39.77894 16.71066)
		(mid -39.209819 15.336681)
		(end -37.83584 14.76756)
		(width 0.10668)
		(layer "B.Cu")
		(net "SAS_B2_RX6P")
	)
	(arc
		(start -36.05022 32.0548)
		(mid -36.143615 32.016115)
		(end -36.1823 31.92272)
		(width 0.10668)
		(layer "B.Cu")
		(net "SAS_B2_RX6P")
	)
	(arc
		(start -35.89274 30.48)
		(mid -36.092862 29.996862)
		(end -36.576 29.79674)
		(width 0.10668)
		(layer "B.Cu")
		(net "SAS_B2_RX6P")
	)
	(arc
		(start -32.0348 11.45794)
		(mid -32.499976 11.650623)
		(end -32.692658 12.1158)
		(width 0.10668)
		(layer "B.Cu")
		(net "SAS_B2_RX6P")
	)
	(arc
		(start -36.1823 31.5595)
		(mid -36.148822 31.478678)
		(end -36.068 31.4452)
		(width 0.10668)
		(layer "B.Cu")
		(net "SAS_B2_RX6P")
	)
	(arc
		(start -35.2806 40.69334)
		(mid -35.713448 40.514048)
		(end -35.89274 40.0812)
		(width 0.10668)
		(layer "B.Cu")
		(net "SAS_B2_RX6P")
	)
	(arc
		(start -38.8874 29.79674)
		(mid -39.517814 29.535614)
		(end -39.77894 28.9052)
		(width 0.10668)
		(layer "B.Cu")
		(net "SAS_B2_RX6P")
	)
	(arc
		(start -33.071209 12.943167)
		(mid -33.131276 12.995004)
		(end -33.198278 13.037497)
		(width 0.10668)
		(layer "B.Cu")
		(net "SAS_B2_RX6P")
	)
	(arc
		(start -30.079 12.18692)
		(mid -30.292513 11.671453)
		(end -30.80798 11.45794)
		(width 0.10668)
		(layer "B.Cu")
		(net "SAS_B2_RX6P")
	)
	(arc
		(start -36.068 31.4452)
		(mid -35.944072 31.393868)
		(end -35.89274 31.26994)
		(width 0.10668)
		(layer "B.Cu")
		(net "SAS_B2_RX6P")
	)
	(arc
		(start -32.692658 12.1158)
		(mid -32.775137 12.530455)
		(end -33.01002 12.881983)
		(width 0.10668)
		(layer "B.Cu")
		(net "SAS_B2_RX6P")
	)
	(arc
		(start -33.806155 14.76756)
		(mid -33.685879 14.754371)
		(end -33.57132 14.715432)
		(width 0.10668)
		(layer "B.Cu")
		(net "SAS_B2_RX6P")
	)
	(segment
		(start -37.83584 15.2019)
		(end -33.806155 15.2019)
		(width 0.10668)
		(layer "B.Cu")
		(net "SAS_B2_RX6N")
	)
	(segment
		(start -33.483514 12.697562)
		(end -33.483517 12.697562)
		(width 0.10668)
		(layer "B.Cu")
		(net "SAS_B2_RX6N")
	)
	(segment
		(start -30.80798 11.0236)
		(end -32.0348 11.0236)
		(width 0.10668)
		(layer "B.Cu")
		(net "SAS_B2_RX6N")
	)
	(segment
		(start -33.627929 12.653904)
		(end -33.850001 12.239371)
		(width 0.10668)
		(layer "B.Cu")
		(net "SAS_B2_RX6N")
	)
	(segment
		(start -35.1028 40.259)
		(end -35.2806 40.259)
		(width 0.10668)
		(layer "B.Cu")
		(net "SAS_B2_RX6N")
	)
	(segment
		(start -39.3446 28.9052)
		(end -39.3446 16.71066)
		(width 0.10668)
		(layer "B.Cu")
		(net "SAS_B2_RX6N")
	)
	(segment
		(start -34.679999 39.760002)
		(end -34.679999 39.836199)
		(width 0.10668)
		(layer "B.Cu")
		(net "SAS_B2_RX6N")
	)
	(segment
		(start -31.6611 14.9606)
		(end -30.791267 14.9606)
		(width 0.10668)
		(layer "B.Cu")
		(net "SAS_B2_RX6N")
	)
	(segment
		(start -35.4584 40.0812)
		(end -35.4584 30.48)
		(width 0.10668)
		(layer "B.Cu")
		(net "SAS_B2_RX6N")
	)
	(segment
		(start -36.576 29.3624)
		(end -38.8874 29.3624)
		(width 0.10668)
		(layer "B.Cu")
		(net "SAS_B2_RX6N")
	)
	(segment
		(start -33.403383 12.654633)
		(end -33.483514 12.697562)
		(width 0.10668)
		(layer "B.Cu")
		(net "SAS_B2_RX6N")
	)
	(segment
		(start -29.64466 13.813993)
		(end -29.64466 12.18692)
		(width 0.10668)
		(layer "B.Cu")
		(net "SAS_B2_RX6N")
	)
	(segment
		(start -33.317144 12.574854)
		(end -33.378325 12.636033)
		(width 0.10668)
		(layer "B.Cu")
		(net "SAS_B2_RX6N")
	)
	(arc
		(start -35.2806 40.259)
		(mid -35.406324 40.206924)
		(end -35.4584 40.0812)
		(width 0.10668)
		(layer "B.Cu")
		(net "SAS_B2_RX6N")
	)
	(arc
		(start -33.378325 12.636033)
		(mid -33.39017 12.646255)
		(end -33.403383 12.654633)
		(width 0.10668)
		(layer "B.Cu")
		(net "SAS_B2_RX6N")
	)
	(arc
		(start -39.3446 16.71066)
		(mid -38.902694 15.643806)
		(end -37.83584 15.2019)
		(width 0.10668)
		(layer "B.Cu")
		(net "SAS_B2_RX6N")
	)
	(arc
		(start -38.8874 29.3624)
		(mid -39.210689 29.228489)
		(end -39.3446 28.9052)
		(width 0.10668)
		(layer "B.Cu")
		(net "SAS_B2_RX6N")
	)
	(arc
		(start -33.806155 15.2019)
		(mid -33.591754 15.17839)
		(end -33.387543 15.108977)
		(width 0.10668)
		(layer "B.Cu")
		(net "SAS_B2_RX6N")
	)
	(arc
		(start -33.127 12.1158)
		(mid -33.176416 12.364238)
		(end -33.317144 12.574854)
		(width 0.10668)
		(layer "B.Cu")
		(net "SAS_B2_RX6N")
	)
	(arc
		(start -33.387543 15.108977)
		(mid -33.206153 15.03941)
		(end -33.016772 14.996084)
		(width 0.10668)
		(layer "B.Cu")
		(net "SAS_B2_RX6N")
	)
	(arc
		(start -34.679999 39.836199)
		(mid -34.803835 40.135164)
		(end -35.1028 40.259)
		(width 0.10668)
		(layer "B.Cu")
		(net "SAS_B2_RX6N")
	)
	(arc
		(start -33.483517 12.697562)
		(mid -33.564764 12.705641)
		(end -33.627929 12.653904)
		(width 0.10668)
		(layer "B.Cu")
		(net "SAS_B2_RX6N")
	)
	(arc
		(start -35.4584 30.48)
		(mid -35.785737 29.689737)
		(end -36.576 29.3624)
		(width 0.10668)
		(layer "B.Cu")
		(net "SAS_B2_RX6N")
	)
	(arc
		(start -33.016772 14.996084)
		(mid -32.339168 14.969473)
		(end -31.6611 14.9606)
		(width 0.10668)
		(layer "B.Cu")
		(net "SAS_B2_RX6N")
	)
	(arc
		(start -29.64466 12.18692)
		(mid -29.985389 11.364329)
		(end -30.80798 11.0236)
		(width 0.10668)
		(layer "B.Cu")
		(net "SAS_B2_RX6N")
	)
	(arc
		(start -32.0348 11.0236)
		(mid -32.807102 11.343498)
		(end -33.127 12.1158)
		(width 0.10668)
		(layer "B.Cu")
		(net "SAS_B2_RX6N")
	)
	(arc
		(start -30.791267 14.9606)
		(mid -29.980493 14.624767)
		(end -29.64466 13.813993)
		(width 0.10668)
		(layer "B.Cu")
		(net "SAS_B2_RX6N")
	)
	(segment
		(start -31.44266 32.40786)
		(end -31.44266 33.041547)
		(width 0.10668)
		(layer "B.Cu")
		(net "SAS_B2_RX5P")
	)
	(segment
		(start -32.0802 35.15614)
		(end -32.176141 35.15614)
		(width 0.10668)
		(layer "B.Cu")
		(net "SAS_B2_RX5P")
	)
	(segment
		(start -33.466507 16.981195)
		(end -33.490007 16.993784)
		(width 0.10668)
		(layer "B.Cu")
		(net "SAS_B2_RX5P")
	)
	(segment
		(start -31.0896 31.75)
		(end -31.0896 32.0548)
		(width 0.10668)
		(layer "B.Cu")
		(net "SAS_B2_RX5P")
	)
	(segment
		(start -31.44266 28.731012)
		(end -31.44266 29.87834)
		(width 0.10668)
		(layer "B.Cu")
		(net "SAS_B2_RX5P")
	)
	(segment
		(start -31.44266 30.75686)
		(end -31.44266 31.4198)
		(width 0.10668)
		(layer "B.Cu")
		(net "SAS_B2_RX5P")
	)
	(segment
		(start -31.2474 33.609608)
		(end -31.44266 33.804868)
		(width 0.10668)
		(layer "B.Cu")
		(net "SAS_B2_RX5P")
	)
	(segment
		(start -29.6672 19.06778)
		(end -29.6672 25.637292)
		(width 0.10668)
		(layer "B.Cu")
		(net "SAS_B2_RX5P")
	)
	(segment
		(start -33.466486 16.981183)
		(end -33.466486 16.981185)
		(width 0.10668)
		(layer "B.Cu")
		(net "SAS_B2_RX5P")
	)
	(segment
		(start -33.1 17.439371)
		(end -33.322072 17.02484)
		(width 0.10668)
		(layer "B.Cu")
		(net "SAS_B2_RX5P")
	)
	(segment
		(start -30.472568 27.581621)
		(end -31.315873 28.424927)
		(width 0.10668)
		(layer "B.Cu")
		(net "SAS_B2_RX5P")
	)
	(segment
		(start -31.44266 33.041547)
		(end -31.2474 33.236807)
		(width 0.10668)
		(layer "B.Cu")
		(net "SAS_B2_RX5P")
	)
	(segment
		(start -31.115 30.206)
		(end -31.115 30.4292)
		(width 0.10668)
		(layer "B.Cu")
		(net "SAS_B2_RX5P")
	)
	(segment
		(start -33.466486 16.981185)
		(end -33.466507 16.981195)
		(width 0.10668)
		(layer "B.Cu")
		(net "SAS_B2_RX5P")
	)
	(segment
		(start -33.466484 16.981183)
		(end -33.466486 16.981183)
		(width 0.10668)
		(layer "B.Cu")
		(net "SAS_B2_RX5P")
	)
	(segment
		(start -33.505137 18.25752)
		(end -30.47746 18.25752)
		(width 0.10668)
		(layer "B.Cu")
		(net "SAS_B2_RX5P")
	)
	(segment
		(start -33.515069 17.012387)
		(end -33.709188 17.206509)
		(width 0.10668)
		(layer "B.Cu")
		(net "SAS_B2_RX5P")
	)
	(segment
		(start -31.29026 31.5722)
		(end -31.2674 31.5722)
		(width 0.10668)
		(layer "B.Cu")
		(net "SAS_B2_RX5P")
	)
	(segment
		(start -31.44266 33.804868)
		(end -31.44266 34.5186)
		(width 0.10668)
		(layer "B.Cu")
		(net "SAS_B2_RX5P")
	)
	(segment
		(start -31.2474 33.236807)
		(end -31.2474 33.609608)
		(width 0.10668)
		(layer "B.Cu")
		(net "SAS_B2_RX5P")
	)
	(arc
		(start -31.44266 29.87834)
		(mid -31.415228 29.944568)
		(end -31.349 29.972)
		(width 0.10668)
		(layer "B.Cu")
		(net "SAS_B2_RX5P")
	)
	(arc
		(start -31.2928 30.607)
		(mid -31.398767 30.650893)
		(end -31.44266 30.75686)
		(width 0.10668)
		(layer "B.Cu")
		(net "SAS_B2_RX5P")
	)
	(arc
		(start -31.115 30.4292)
		(mid -31.167076 30.554924)
		(end -31.2928 30.607)
		(width 0.10668)
		(layer "B.Cu")
		(net "SAS_B2_RX5P")
	)
	(arc
		(start -31.0896 32.0548)
		(mid -31.149116 32.198484)
		(end -31.2928 32.258)
		(width 0.10668)
		(layer "B.Cu")
		(net "SAS_B2_RX5P")
	)
	(arc
		(start -31.2928 32.258)
		(mid -31.398767 32.301893)
		(end -31.44266 32.40786)
		(width 0.10668)
		(layer "B.Cu")
		(net "SAS_B2_RX5P")
	)
	(arc
		(start -31.315873 28.424927)
		(mid -31.409709 28.56536)
		(end -31.44266 28.731012)
		(width 0.10668)
		(layer "B.Cu")
		(net "SAS_B2_RX5P")
	)
	(arc
		(start -32.176141 35.15614)
		(mid -32.201547 35.156781)
		(end -32.226888 35.158703)
		(width 0.10668)
		(layer "B.Cu")
		(net "SAS_B2_RX5P")
	)
	(arc
		(start -33.709188 17.206509)
		(mid -33.892786 17.481283)
		(end -33.957257 17.8054)
		(width 0.10668)
		(layer "B.Cu")
		(net "SAS_B2_RX5P")
	)
	(arc
		(start -31.44266 34.5186)
		(mid -31.629391 34.969409)
		(end -32.0802 35.15614)
		(width 0.10668)
		(layer "B.Cu")
		(net "SAS_B2_RX5P")
	)
	(arc
		(start -30.47746 18.25752)
		(mid -29.90452 18.49484)
		(end -29.6672 19.06778)
		(width 0.10668)
		(layer "B.Cu")
		(net "SAS_B2_RX5P")
	)
	(arc
		(start -33.490007 16.993784)
		(mid -33.503222 17.002164)
		(end -33.515069 17.012387)
		(width 0.10668)
		(layer "B.Cu")
		(net "SAS_B2_RX5P")
	)
	(arc
		(start -31.349 29.972)
		(mid -31.183537 30.040537)
		(end -31.115 30.206)
		(width 0.10668)
		(layer "B.Cu")
		(net "SAS_B2_RX5P")
	)
	(arc
		(start -33.957257 17.8054)
		(mid -33.824834 18.125097)
		(end -33.505137 18.25752)
		(width 0.10668)
		(layer "B.Cu")
		(net "SAS_B2_RX5P")
	)
	(arc
		(start -32.226888 35.158703)
		(mid -32.549935 35.322136)
		(end -32.680001 35.66)
		(width 0.10668)
		(layer "B.Cu")
		(net "SAS_B2_RX5P")
	)
	(arc
		(start -31.2674 31.5722)
		(mid -31.141676 31.624276)
		(end -31.0896 31.75)
		(width 0.10668)
		(layer "B.Cu")
		(net "SAS_B2_RX5P")
	)
	(arc
		(start -31.44266 31.4198)
		(mid -31.398023 31.527563)
		(end -31.29026 31.5722)
		(width 0.10668)
		(layer "B.Cu")
		(net "SAS_B2_RX5P")
	)
	(arc
		(start -29.6672 25.637292)
		(mid -29.876508 26.689555)
		(end -30.472568 27.581621)
		(width 0.10668)
		(layer "B.Cu")
		(net "SAS_B2_RX5P")
	)
	(arc
		(start -33.322072 17.02484)
		(mid -33.385237 16.973103)
		(end -33.466484 16.981183)
		(width 0.10668)
		(layer "B.Cu")
		(net "SAS_B2_RX5P")
	)
	(segment
		(start -33.850001 16.039371)
		(end -33.627929 16.453904)
		(width 0.10668)
		(layer "B.Cu")
		(net "SAS_B2_RX5N")
	)
	(segment
		(start -33.671589 16.598316)
		(end -33.671591 16.598318)
		(width 0.10668)
		(layer "B.Cu")
		(net "SAS_B2_RX5N")
	)
	(segment
		(start -32.679998 34.356548)
		(end -32.680001 34.26)
		(width 0.10668)
		(layer "B.Cu")
		(net "SAS_B2_RX5N")
	)
	(segment
		(start -31.877 28.731009)
		(end -31.877 34.5186)
		(width 0.10668)
		(layer "B.Cu")
		(net "SAS_B2_RX5N")
	)
	(segment
		(start -30.10154 19.06778)
		(end -30.10154 25.637289)
		(width 0.10668)
		(layer "B.Cu")
		(net "SAS_B2_RX5N")
	)
	(segment
		(start -33.671637 16.598341)
		(end -33.695112 16.610919)
		(width 0.10668)
		(layer "B.Cu")
		(net "SAS_B2_RX5N")
	)
	(segment
		(start -30.779695 27.274495)
		(end -31.623 28.1178)
		(width 0.10668)
		(layer "B.Cu")
		(net "SAS_B2_RX5N")
	)
	(segment
		(start -32.0802 34.7218)
		(end -32.176141 34.7218)
		(width 0.10668)
		(layer "B.Cu")
		(net "SAS_B2_RX5N")
	)
	(segment
		(start -33.505137 18.69186)
		(end -30.47746 18.69186)
		(width 0.10668)
		(layer "B.Cu")
		(net "SAS_B2_RX5N")
	)
	(segment
		(start -33.822193 16.70526)
		(end -34.016315 16.899382)
		(width 0.10668)
		(layer "B.Cu")
		(net "SAS_B2_RX5N")
	)
	(segment
		(start -33.671591 16.598318)
		(end -33.671637 16.598341)
		(width 0.10668)
		(layer "B.Cu")
		(net "SAS_B2_RX5N")
	)
	(arc
		(start -31.623 28.1178)
		(mid -31.810987 28.399143)
		(end -31.877 28.731009)
		(width 0.10668)
		(layer "B.Cu")
		(net "SAS_B2_RX5N")
	)
	(arc
		(start -31.877 34.5186)
		(mid -31.936516 34.662284)
		(end -32.0802 34.7218)
		(width 0.10668)
		(layer "B.Cu")
		(net "SAS_B2_RX5N")
	)
	(arc
		(start -30.47746 18.69186)
		(mid -30.211644 18.801964)
		(end -30.10154 19.06778)
		(width 0.10668)
		(layer "B.Cu")
		(net "SAS_B2_RX5N")
	)
	(arc
		(start -32.270631 34.72657)
		(mid -32.557473 34.632455)
		(end -32.679998 34.356548)
		(width 0.10668)
		(layer "B.Cu")
		(net "SAS_B2_RX5N")
	)
	(arc
		(start -34.3916 17.8054)
		(mid -34.131961 18.432223)
		(end -33.505137 18.69186)
		(width 0.10668)
		(layer "B.Cu")
		(net "SAS_B2_RX5N")
	)
	(arc
		(start -34.016315 16.899382)
		(mid -34.294067 17.315067)
		(end -34.3916 17.8054)
		(width 0.10668)
		(layer "B.Cu")
		(net "SAS_B2_RX5N")
	)
	(arc
		(start -30.10154 25.637289)
		(mid -30.277787 26.523339)
		(end -30.779695 27.274495)
		(width 0.10668)
		(layer "B.Cu")
		(net "SAS_B2_RX5N")
	)
	(arc
		(start -33.627929 16.453904)
		(mid -33.61985 16.535152)
		(end -33.671589 16.598316)
		(width 0.10668)
		(layer "B.Cu")
		(net "SAS_B2_RX5N")
	)
	(arc
		(start -32.176141 34.7218)
		(mid -32.223446 34.722993)
		(end -32.270631 34.72657)
		(width 0.10668)
		(layer "B.Cu")
		(net "SAS_B2_RX5N")
	)
	(arc
		(start -33.695112 16.610919)
		(mid -33.762121 16.653417)
		(end -33.822193 16.70526)
		(width 0.10668)
		(layer "B.Cu")
		(net "SAS_B2_RX5N")
	)
	(segment
		(start -29.33478 31.75)
		(end -29.317 31.75)
		(width 0.10668)
		(layer "B.Cu")
		(net "SAS_B2_RX4P")
	)
	(segment
		(start -24.716483 13.181183)
		(end -24.716486 13.181183)
		(width 0.10668)
		(layer "B.Cu")
		(net "SAS_B2_RX4P")
	)
	(segment
		(start -29.46686 32.49168)
		(end -29.46686 39.96576)
		(width 0.10668)
		(layer "B.Cu")
		(net "SAS_B2_RX4P")
	)
	(segment
		(start -30.2314 40.69334)
		(end -30.4557 40.69334)
		(width 0.10668)
		(layer "B.Cu")
		(net "SAS_B2_RX4P")
	)
	(segment
		(start -29.19 31.877)
		(end -29.19 32.258)
		(width 0.10668)
		(layer "B.Cu")
		(net "SAS_B2_RX4P")
	)
	(segment
		(start -25.893344 13.94714)
		(end -26.64206 13.94714)
		(width 0.10668)
		(layer "B.Cu")
		(net "SAS_B2_RX4P")
	)
	(segment
		(start -24.350002 13.639371)
		(end -24.572072 13.22484)
		(width 0.10668)
		(layer "B.Cu")
		(net "SAS_B2_RX4P")
	)
	(segment
		(start -24.716486 13.181183)
		(end -24.810522 13.231559)
		(width 0.10668)
		(layer "B.Cu")
		(net "SAS_B2_RX4P")
	)
	(segment
		(start -29.317 32.385)
		(end -29.36018 32.385)
		(width 0.10668)
		(layer "B.Cu")
		(net "SAS_B2_RX4P")
	)
	(segment
		(start -28.2448 16.461857)
		(end -28.2448 27.077713)
		(width 0.10668)
		(layer "B.Cu")
		(net "SAS_B2_RX4P")
	)
	(segment
		(start -28.4915 27.6733)
		(end -28.97918 28.16098)
		(width 0.10668)
		(layer "B.Cu")
		(net "SAS_B2_RX4P")
	)
	(segment
		(start -29.46686 29.338344)
		(end -29.46686 31.61792)
		(width 0.10668)
		(layer "B.Cu")
		(net "SAS_B2_RX4P")
	)
	(segment
		(start -30.68 40.91764)
		(end -30.68 41.160002)
		(width 0.10668)
		(layer "B.Cu")
		(net "SAS_B2_RX4P")
	)
	(segment
		(start -27.262115 14.203975)
		(end -27.3431 14.28496)
		(width 0.10668)
		(layer "B.Cu")
		(net "SAS_B2_RX4P")
	)
	(arc
		(start -29.46686 39.96576)
		(mid -29.679629 40.479431)
		(end -30.1933 40.6922)
		(width 0.10668)
		(layer "B.Cu")
		(net "SAS_B2_RX4P")
	)
	(arc
		(start -30.4557 40.69334)
		(mid -30.614304 40.759036)
		(end -30.68 40.91764)
		(width 0.10668)
		(layer "B.Cu")
		(net "SAS_B2_RX4P")
	)
	(arc
		(start -24.872381 13.299603)
		(mid -25.281124 13.783782)
		(end -25.893344 13.94714)
		(width 0.10668)
		(layer "B.Cu")
		(net "SAS_B2_RX4P")
	)
	(arc
		(start -29.46686 31.61792)
		(mid -29.428175 31.711315)
		(end -29.33478 31.75)
		(width 0.10668)
		(layer "B.Cu")
		(net "SAS_B2_RX4P")
	)
	(arc
		(start -29.19 32.258)
		(mid -29.227197 32.347803)
		(end -29.317 32.385)
		(width 0.10668)
		(layer "B.Cu")
		(net "SAS_B2_RX4P")
	)
	(arc
		(start -28.2448 27.077713)
		(mid -28.308915 27.400042)
		(end -28.4915 27.6733)
		(width 0.10668)
		(layer "B.Cu")
		(net "SAS_B2_RX4P")
	)
	(arc
		(start -26.64206 13.94714)
		(mid -26.977631 14.013889)
		(end -27.262115 14.203975)
		(width 0.10668)
		(layer "B.Cu")
		(net "SAS_B2_RX4P")
	)
	(arc
		(start -28.97918 28.16098)
		(mid -29.340116 28.701159)
		(end -29.46686 29.338344)
		(width 0.10668)
		(layer "B.Cu")
		(net "SAS_B2_RX4P")
	)
	(arc
		(start -29.36018 32.385)
		(mid -29.435614 32.416246)
		(end -29.46686 32.49168)
		(width 0.10668)
		(layer "B.Cu")
		(net "SAS_B2_RX4P")
	)
	(arc
		(start -27.3431 14.28496)
		(mid -28.010456 15.283729)
		(end -28.2448 16.461857)
		(width 0.10668)
		(layer "B.Cu")
		(net "SAS_B2_RX4P")
	)
	(arc
		(start -24.572072 13.22484)
		(mid -24.635236 13.173103)
		(end -24.716483 13.181183)
		(width 0.10668)
		(layer "B.Cu")
		(net "SAS_B2_RX4P")
	)
	(arc
		(start -30.1933 40.6922)
		(mid -30.212341 40.693055)
		(end -30.2314 40.69334)
		(width 0.10668)
		(layer "B.Cu")
		(net "SAS_B2_RX4P")
	)
	(arc
		(start -29.317 31.75)
		(mid -29.227197 31.787197)
		(end -29.19 31.877)
		(width 0.10668)
		(layer "B.Cu")
		(net "SAS_B2_RX4P")
	)
	(arc
		(start -24.810522 13.231559)
		(mid -24.847312 13.260253)
		(end -24.872381 13.299603)
		(width 0.10668)
		(layer "B.Cu")
		(net "SAS_B2_RX4P")
	)
	(segment
		(start -29.349913 27.91746)
		(end -28.798627 27.366173)
		(width 0.10668)
		(layer "B.Cu")
		(net "SAS_B2_RX4N")
	)
	(segment
		(start -30.68 39.760002)
		(end -30.68 39.7796)
		(width 0.10668)
		(layer "B.Cu")
		(net "SAS_B2_RX4N")
	)
	(segment
		(start -27.650227 13.977833)
		(end -27.569241 13.896848)
		(width 0.10668)
		(layer "B.Cu")
		(net "SAS_B2_RX4N")
	)
	(segment
		(start -25.015627 12.848694)
		(end -24.921591 12.798318)
		(width 0.10668)
		(layer "B.Cu")
		(net "SAS_B2_RX4N")
	)
	(segment
		(start -26.642063 13.5128)
		(end -25.8826 13.5128)
		(width 0.10668)
		(layer "B.Cu")
		(net "SAS_B2_RX4N")
	)
	(segment
		(start -28.67914 27.077716)
		(end -28.67914 16.461857)
		(width 0.10668)
		(layer "B.Cu")
		(net "SAS_B2_RX4N")
	)
	(segment
		(start -24.921591 12.798318)
		(end -24.921588 12.798316)
		(width 0.10668)
		(layer "B.Cu")
		(net "SAS_B2_RX4N")
	)
	(segment
		(start -24.877928 12.653904)
		(end -25.100001 12.239371)
		(width 0.10668)
		(layer "B.Cu")
		(net "SAS_B2_RX4N")
	)
	(segment
		(start -29.9012 39.940581)
		(end -29.9012 29.248384)
		(width 0.10668)
		(layer "B.Cu")
		(net "SAS_B2_RX4N")
	)
	(arc
		(start -30.219256 40.258637)
		(mid -29.994356 40.165481)
		(end -29.9012 39.940581)
		(width 0.10668)
		(layer "B.Cu")
		(net "SAS_B2_RX4N")
	)
	(arc
		(start -28.67914 16.461857)
		(mid -28.411735 15.117514)
		(end -27.650227 13.977833)
		(width 0.10668)
		(layer "B.Cu")
		(net "SAS_B2_RX4N")
	)
	(arc
		(start -24.921588 12.798316)
		(mid -24.869849 12.735152)
		(end -24.877928 12.653904)
		(width 0.10668)
		(layer "B.Cu")
		(net "SAS_B2_RX4N")
	)
	(arc
		(start -29.9012 29.248384)
		(mid -29.757925 28.528093)
		(end -29.349913 27.91746)
		(width 0.10668)
		(layer "B.Cu")
		(net "SAS_B2_RX4N")
	)
	(arc
		(start -27.569241 13.896848)
		(mid -27.143848 13.612611)
		(end -26.642063 13.5128)
		(width 0.10668)
		(layer "B.Cu")
		(net "SAS_B2_RX4N")
	)
	(arc
		(start -28.798627 27.366173)
		(mid -28.710196 27.233828)
		(end -28.67914 27.077716)
		(width 0.10668)
		(layer "B.Cu")
		(net "SAS_B2_RX4N")
	)
	(arc
		(start -25.273 13.1318)
		(mid -25.168697 12.96808)
		(end -25.015627 12.848694)
		(width 0.10668)
		(layer "B.Cu")
		(net "SAS_B2_RX4N")
	)
	(arc
		(start -25.8826 13.5128)
		(mid -25.517245 13.419188)
		(end -25.273 13.1318)
		(width 0.10668)
		(layer "B.Cu")
		(net "SAS_B2_RX4N")
	)
	(arc
		(start -30.68 39.7796)
		(mid -30.54612 40.111926)
		(end -30.219256 40.258637)
		(width 0.10668)
		(layer "B.Cu")
		(net "SAS_B2_RX4N")
	)
	(segment
		(start -27.8511 46.0756)
		(end -27.8511 43.815)
		(width 0.11176)
		(layer "In5.Cu")
		(net "SAS_B2_RX3P")
	)
	(segment
		(start -18.6744 19.07032)
		(end -18.6744 39.340861)
		(width 0.11176)
		(layer "In5.Cu")
		(net "SAS_B2_RX3P")
	)
	(segment
		(start -20.0279 42.6085)
		(end -20.435392 43.015992)
		(width 0.11176)
		(layer "In5.Cu")
		(net "SAS_B2_RX3P")
	)
	(segment
		(start -23.12702 45.91304)
		(end -23.150703 45.889357)
		(width 0.11176)
		(layer "In5.Cu")
		(net "SAS_B2_RX3P")
	)
	(segment
		(start -21.307397 44.212797)
		(end -21.71732 44.62272)
		(width 0.11176)
		(layer "In5.Cu")
		(net "SAS_B2_RX3P")
	)
	(segment
		(start -21.8494 44.62272)
		(end -21.866733 44.605387)
		(width 0.11176)
		(layer "In5.Cu")
		(net "SAS_B2_RX3P")
	)
	(segment
		(start -28.680001 44.059701)
		(end -28.680001 44.060001)
		(width 0.11176)
		(layer "In5.Cu")
		(net "SAS_B2_RX3P")
	)
	(segment
		(start -24.793237 16.970431)
		(end -24.79325 16.970439)
		(width 0.11176)
		(layer "In5.Cu")
		(net "SAS_B2_RX3P")
	)
	(segment
		(start -25.133079 46.7106)
		(end -27.2161 46.7106)
		(width 0.11176)
		(layer "In5.Cu")
		(net "SAS_B2_RX3P")
	)
	(segment
		(start -24.742554 16.943276)
		(end -24.742557 16.943278)
		(width 0.11176)
		(layer "In5.Cu")
		(net "SAS_B2_RX3P")
	)
	(segment
		(start -21.311743 44.050397)
		(end -21.307397 44.054743)
		(width 0.11176)
		(layer "In5.Cu")
		(net "SAS_B2_RX3P")
	)
	(segment
		(start -22.586823 45.325477)
		(end -22.57838 45.33392)
		(width 0.11176)
		(layer "In5.Cu")
		(net "SAS_B2_RX3P")
	)
	(segment
		(start -23.308757 45.889357)
		(end -23.420715 46.001315)
		(width 0.11176)
		(layer "In5.Cu")
		(net "SAS_B2_RX3P")
	)
	(segment
		(start -24.824875 17.00644)
		(end -25.096381 17.277946)
		(width 0.11176)
		(layer "In5.Cu")
		(net "SAS_B2_RX3P")
	)
	(segment
		(start -21.026806 43.607406)
		(end -21.311743 43.892343)
		(width 0.11176)
		(layer "In5.Cu")
		(net "SAS_B2_RX3P")
	)
	(segment
		(start -20.435392 43.328092)
		(end -20.714706 43.607406)
		(width 0.11176)
		(layer "In5.Cu")
		(net "SAS_B2_RX3P")
	)
	(segment
		(start -24.56942 18.27784)
		(end -19.46688 18.27784)
		(width 0.11176)
		(layer "In5.Cu")
		(net "SAS_B2_RX3P")
	)
	(segment
		(start -20.714706 43.607406)
		(end -21.026806 43.607406)
		(width 0.11176)
		(layer "In5.Cu")
		(net "SAS_B2_RX3P")
	)
	(segment
		(start -24.79323 16.970426)
		(end -24.793237 16.970431)
		(width 0.11176)
		(layer "In5.Cu")
		(net "SAS_B2_RX3P")
	)
	(segment
		(start -22.024787 44.605387)
		(end -22.586823 45.167423)
		(width 0.11176)
		(layer "In5.Cu")
		(net "SAS_B2_RX3P")
	)
	(segment
		(start -20.435392 43.015992)
		(end -20.435392 43.328092)
		(width 0.11176)
		(layer "In5.Cu")
		(net "SAS_B2_RX3P")
	)
	(segment
		(start -24.79325 16.970439)
		(end -24.79327 16.970449)
		(width 0.11176)
		(layer "In5.Cu")
		(net "SAS_B2_RX3P")
	)
	(segment
		(start -22.57838 45.48378)
		(end -23.00764 45.91304)
		(width 0.11176)
		(layer "In5.Cu")
		(net "SAS_B2_RX3P")
	)
	(segment
		(start -24.350002 17.439371)
		(end -24.591264 16.989016)
		(width 0.11176)
		(layer "In5.Cu")
		(net "SAS_B2_RX3P")
	)
	(segment
		(start -24.742557 16.943278)
		(end -24.79323 16.970426)
		(width 0.11176)
		(layer "In5.Cu")
		(net "SAS_B2_RX3P")
	)
	(arc
		(start -19.46688 18.27784)
		(mid -18.906512 18.509952)
		(end -18.6744 19.07032)
		(width 0.11176)
		(layer "In5.Cu")
		(net "SAS_B2_RX3P")
	)
	(arc
		(start -25.096381 17.277946)
		(mid -25.198899 17.431377)
		(end -25.234897 17.61236)
		(width 0.11176)
		(layer "In5.Cu")
		(net "SAS_B2_RX3P")
	)
	(arc
		(start -27.8511 43.815)
		(mid -27.936654 43.608454)
		(end -28.1432 43.5229)
		(width 0.11176)
		(layer "In5.Cu")
		(net "SAS_B2_RX3P")
	)
	(arc
		(start -18.6744 39.340861)
		(mid -19.026163 41.109294)
		(end -20.0279 42.6085)
		(width 0.11176)
		(layer "In5.Cu")
		(net "SAS_B2_RX3P")
	)
	(arc
		(start -21.866733 44.605387)
		(mid -21.94576 44.572652)
		(end -22.024787 44.605387)
		(width 0.11176)
		(layer "In5.Cu")
		(net "SAS_B2_RX3P")
	)
	(arc
		(start -28.1432 43.5229)
		(mid -28.522776 43.680125)
		(end -28.680001 44.059701)
		(width 0.11176)
		(layer "In5.Cu")
		(net "SAS_B2_RX3P")
	)
	(arc
		(start -21.307397 44.054743)
		(mid -21.274662 44.13377)
		(end -21.307397 44.212797)
		(width 0.11176)
		(layer "In5.Cu")
		(net "SAS_B2_RX3P")
	)
	(arc
		(start -24.793273 16.970451)
		(mid -24.80927 16.988273)
		(end -24.824875 17.00644)
		(width 0.11176)
		(layer "In5.Cu")
		(net "SAS_B2_RX3P")
	)
	(arc
		(start -27.2161 46.7106)
		(mid -27.665113 46.524613)
		(end -27.8511 46.0756)
		(width 0.11176)
		(layer "In5.Cu")
		(net "SAS_B2_RX3P")
	)
	(arc
		(start -23.00764 45.91304)
		(mid -23.06733 45.937764)
		(end -23.12702 45.91304)
		(width 0.11176)
		(layer "In5.Cu")
		(net "SAS_B2_RX3P")
	)
	(arc
		(start -23.150703 45.889357)
		(mid -23.22973 45.856622)
		(end -23.308757 45.889357)
		(width 0.11176)
		(layer "In5.Cu")
		(net "SAS_B2_RX3P")
	)
	(arc
		(start -22.586823 45.167423)
		(mid -22.619558 45.24645)
		(end -22.586823 45.325477)
		(width 0.11176)
		(layer "In5.Cu")
		(net "SAS_B2_RX3P")
	)
	(arc
		(start -21.71732 44.62272)
		(mid -21.78336 44.650075)
		(end -21.8494 44.62272)
		(width 0.11176)
		(layer "In5.Cu")
		(net "SAS_B2_RX3P")
	)
	(arc
		(start -25.234897 17.61236)
		(mid -25.039983 18.082924)
		(end -24.56942 18.27784)
		(width 0.11176)
		(layer "In5.Cu")
		(net "SAS_B2_RX3P")
	)
	(arc
		(start -24.591264 16.989016)
		(mid -24.657436 16.934813)
		(end -24.742554 16.943276)
		(width 0.11176)
		(layer "In5.Cu")
		(net "SAS_B2_RX3P")
	)
	(arc
		(start -22.57838 45.33392)
		(mid -22.547343 45.40885)
		(end -22.57838 45.48378)
		(width 0.11176)
		(layer "In5.Cu")
		(net "SAS_B2_RX3P")
	)
	(arc
		(start -24.79327 16.970449)
		(mid -24.793271 16.97045)
		(end -24.793273 16.970451)
		(width 0.11176)
		(layer "In5.Cu")
		(net "SAS_B2_RX3P")
	)
	(arc
		(start -23.420715 46.001315)
		(mid -24.206354 46.526262)
		(end -25.133079 46.7106)
		(width 0.11176)
		(layer "In5.Cu")
		(net "SAS_B2_RX3P")
	)
	(arc
		(start -21.311743 43.892343)
		(mid -21.344478 43.97137)
		(end -21.311743 44.050397)
		(width 0.11176)
		(layer "In5.Cu")
		(net "SAS_B2_RX3P")
	)
	(segment
		(start -24.56942 18.62074)
		(end -19.46688 18.62074)
		(width 0.11176)
		(layer "In5.Cu")
		(net "SAS_B2_RX3N")
	)
	(segment
		(start -28.1432 43.18)
		(end -28.160002 43.18)
		(width 0.11176)
		(layer "In5.Cu")
		(net "SAS_B2_RX3N")
	)
	(segment
		(start -24.904487 16.641023)
		(end -25.002993 16.693794)
		(width 0.11176)
		(layer "In5.Cu")
		(net "SAS_B2_RX3N")
	)
	(segment
		(start -24.904479 16.641018)
		(end -24.904487 16.641023)
		(width 0.11176)
		(layer "In5.Cu")
		(net "SAS_B2_RX3N")
	)
	(segment
		(start -25.100001 16.039371)
		(end -24.858739 16.489728)
		(width 0.11176)
		(layer "In5.Cu")
		(net "SAS_B2_RX3N")
	)
	(segment
		(start -25.077133 16.773764)
		(end -25.33885 17.03548)
		(width 0.11176)
		(layer "In5.Cu")
		(net "SAS_B2_RX3N")
	)
	(segment
		(start -19.0173 19.07032)
		(end -19.0173 39.340864)
		(width 0.11176)
		(layer "In5.Cu")
		(net "SAS_B2_RX3N")
	)
	(segment
		(start -25.133082 46.3677)
		(end -27.2161 46.3677)
		(width 0.11176)
		(layer "In5.Cu")
		(net "SAS_B2_RX3N")
	)
	(segment
		(start -24.904476 16.641018)
		(end -24.904479 16.641018)
		(width 0.11176)
		(layer "In5.Cu")
		(net "SAS_B2_RX3N")
	)
	(segment
		(start -27.5082 46.0756)
		(end -27.5082 43.815)
		(width 0.11176)
		(layer "In5.Cu")
		(net "SAS_B2_RX3N")
	)
	(segment
		(start -20.270368 42.366032)
		(end -23.663184 45.758847)
		(width 0.11176)
		(layer "In5.Cu")
		(net "SAS_B2_RX3N")
	)
	(arc
		(start -25.5778 17.61236)
		(mid -25.282452 18.325392)
		(end -24.56942 18.62074)
		(width 0.11176)
		(layer "In5.Cu")
		(net "SAS_B2_RX3N")
	)
	(arc
		(start -28.160002 43.18)
		(mid -28.527697 43.027696)
		(end -28.680001 42.660001)
		(width 0.11176)
		(layer "In5.Cu")
		(net "SAS_B2_RX3N")
	)
	(arc
		(start -27.5082 43.815)
		(mid -27.694187 43.365987)
		(end -28.1432 43.18)
		(width 0.11176)
		(layer "In5.Cu")
		(net "SAS_B2_RX3N")
	)
	(arc
		(start -25.045952 16.738646)
		(mid -25.061685 16.756078)
		(end -25.077133 16.773764)
		(width 0.11176)
		(layer "In5.Cu")
		(net "SAS_B2_RX3N")
	)
	(arc
		(start -19.0173 39.340864)
		(mid -19.342963 40.978073)
		(end -20.270368 42.366032)
		(width 0.11176)
		(layer "In5.Cu")
		(net "SAS_B2_RX3N")
	)
	(arc
		(start -27.2161 46.3677)
		(mid -27.422646 46.282146)
		(end -27.5082 46.0756)
		(width 0.11176)
		(layer "In5.Cu")
		(net "SAS_B2_RX3N")
	)
	(arc
		(start -24.858739 16.489728)
		(mid -24.850275 16.574845)
		(end -24.904476 16.641018)
		(width 0.11176)
		(layer "In5.Cu")
		(net "SAS_B2_RX3N")
	)
	(arc
		(start -23.663184 45.758847)
		(mid -24.337579 46.209464)
		(end -25.133082 46.3677)
		(width 0.11176)
		(layer "In5.Cu")
		(net "SAS_B2_RX3N")
	)
	(arc
		(start -19.46688 18.62074)
		(mid -19.148979 18.752419)
		(end -19.0173 19.07032)
		(width 0.11176)
		(layer "In5.Cu")
		(net "SAS_B2_RX3N")
	)
	(arc
		(start -25.002993 16.693794)
		(mid -25.024714 16.715989)
		(end -25.045952 16.738646)
		(width 0.11176)
		(layer "In5.Cu")
		(net "SAS_B2_RX3N")
	)
	(arc
		(start -25.33885 17.03548)
		(mid -25.515699 17.300155)
		(end -25.5778 17.61236)
		(width 0.11176)
		(layer "In5.Cu")
		(net "SAS_B2_RX3N")
	)
	(segment
		(start -27.285 34.043574)
		(end -27.285 33.632094)
		(width 0.10668)
		(layer "B.Cu")
		(net "SAS_B2_RX2P")
	)
	(segment
		(start -27.48026 34.5694)
		(end -27.48026 34.238834)
		(width 0.10668)
		(layer "B.Cu")
		(net "SAS_B2_RX2P")
	)
	(segment
		(start -26.777 29.083)
		(end -26.79446 29.083)
		(width 0.10668)
		(layer "B.Cu")
		(net "SAS_B2_RX2P")
	)
	(segment
		(start -22.466485 13.181185)
		(end -22.466485 13.181183)
		(width 0.10668)
		(layer "B.Cu")
		(net "SAS_B2_RX2P")
	)
	(segment
		(start -26.92146 31.816426)
		(end -26.92146 31.54426)
		(width 0.10668)
		(layer "B.Cu")
		(net "SAS_B2_RX2P")
	)
	(segment
		(start -22.70095 13.398271)
		(end -22.515068 13.212387)
		(width 0.10668)
		(layer "B.Cu")
		(net "SAS_B2_RX2P")
	)
	(segment
		(start -26.92146 28.956)
		(end -26.92146 23.712333)
		(width 0.10668)
		(layer "B.Cu")
		(net "SAS_B2_RX2P")
	)
	(segment
		(start -26.5938 31.2166)
		(end -26.5938 30.9172)
		(width 0.10668)
		(layer "B.Cu")
		(net "SAS_B2_RX2P")
	)
	(segment
		(start -26.5938 29.4894)
		(end -26.5938 29.2662)
		(width 0.10668)
		(layer "B.Cu")
		(net "SAS_B2_RX2P")
	)
	(segment
		(start -26.92146 30.62732)
		(end -26.92146 29.81706)
		(width 0.10668)
		(layer "B.Cu")
		(net "SAS_B2_RX2P")
	)
	(segment
		(start -27.48026 34.238834)
		(end -27.285 34.043574)
		(width 0.10668)
		(layer "B.Cu")
		(net "SAS_B2_RX2P")
	)
	(segment
		(start -26.46966 22.621593)
		(end -26.46966 15.81912)
		(width 0.10668)
		(layer "B.Cu")
		(net "SAS_B2_RX2P")
	)
	(segment
		(start -27.48026 33.436834)
		(end -27.48026 33.165491)
		(width 0.10668)
		(layer "B.Cu")
		(net "SAS_B2_RX2P")
	)
	(segment
		(start -25.78894 15.1384)
		(end -23.9957 15.1384)
		(width 0.10668)
		(layer "B.Cu")
		(net "SAS_B2_RX2P")
	)
	(segment
		(start -22.322071 13.22484)
		(end -22.100002 13.639371)
		(width 0.10668)
		(layer "B.Cu")
		(net "SAS_B2_RX2P")
	)
	(segment
		(start -22.8273 13.97)
		(end -22.8273 13.703303)
		(width 0.10668)
		(layer "B.Cu")
		(net "SAS_B2_RX2P")
	)
	(segment
		(start -22.466485 13.181183)
		(end -22.466483 13.181183)
		(width 0.10668)
		(layer "B.Cu")
		(net "SAS_B2_RX2P")
	)
	(segment
		(start -22.466506 13.181195)
		(end -22.466485 13.181185)
		(width 0.10668)
		(layer "B.Cu")
		(net "SAS_B2_RX2P")
	)
	(segment
		(start -28.2194 35.18154)
		(end -28.0924 35.18154)
		(width 0.10668)
		(layer "B.Cu")
		(net "SAS_B2_RX2P")
	)
	(segment
		(start -26.777 30.734)
		(end -26.81478 30.734)
		(width 0.10668)
		(layer "B.Cu")
		(net "SAS_B2_RX2P")
	)
	(segment
		(start -28.680001 35.66)
		(end -28.680001 35.642141)
		(width 0.10668)
		(layer "B.Cu")
		(net "SAS_B2_RX2P")
	)
	(segment
		(start -26.769276 23.344924)
		(end -26.769273 23.344922)
		(width 0.10668)
		(layer "B.Cu")
		(net "SAS_B2_RX2P")
	)
	(segment
		(start -27.285 33.632094)
		(end -27.48026 33.436834)
		(width 0.10668)
		(layer "B.Cu")
		(net "SAS_B2_RX2P")
	)
	(segment
		(start -22.490006 13.193784)
		(end -22.466506 13.181195)
		(width 0.10668)
		(layer "B.Cu")
		(net "SAS_B2_RX2P")
	)
	(arc
		(start -23.9957 15.1384)
		(mid -23.169516 14.796184)
		(end -22.8273 13.97)
		(width 0.10668)
		(layer "B.Cu")
		(net "SAS_B2_RX2P")
	)
	(arc
		(start -28.680001 35.642141)
		(mid -28.545094 35.316447)
		(end -28.2194 35.18154)
		(width 0.10668)
		(layer "B.Cu")
		(net "SAS_B2_RX2P")
	)
	(arc
		(start -26.7716 31.3944)
		(mid -26.645876 31.342324)
		(end -26.5938 31.2166)
		(width 0.10668)
		(layer "B.Cu")
		(net "SAS_B2_RX2P")
	)
	(arc
		(start -26.81478 30.734)
		(mid -26.890214 30.702754)
		(end -26.92146 30.62732)
		(width 0.10668)
		(layer "B.Cu")
		(net "SAS_B2_RX2P")
	)
	(arc
		(start -26.92146 23.712333)
		(mid -26.881909 23.513493)
		(end -26.769276 23.344924)
		(width 0.10668)
		(layer "B.Cu")
		(net "SAS_B2_RX2P")
	)
	(arc
		(start -26.79446 29.083)
		(mid -26.884263 29.045803)
		(end -26.92146 28.956)
		(width 0.10668)
		(layer "B.Cu")
		(net "SAS_B2_RX2P")
	)
	(arc
		(start -26.5938 29.2662)
		(mid -26.647458 29.136658)
		(end -26.777 29.083)
		(width 0.10668)
		(layer "B.Cu")
		(net "SAS_B2_RX2P")
	)
	(arc
		(start -27.48026 33.165491)
		(mid -27.453911 33.033025)
		(end -27.378873 32.920727)
		(width 0.10668)
		(layer "B.Cu")
		(net "SAS_B2_RX2P")
	)
	(arc
		(start -22.466483 13.181183)
		(mid -22.385236 13.173104)
		(end -22.322071 13.22484)
		(width 0.10668)
		(layer "B.Cu")
		(net "SAS_B2_RX2P")
	)
	(arc
		(start -26.7716 29.6672)
		(mid -26.645876 29.615124)
		(end -26.5938 29.4894)
		(width 0.10668)
		(layer "B.Cu")
		(net "SAS_B2_RX2P")
	)
	(arc
		(start -26.92146 31.54426)
		(mid -26.877567 31.438293)
		(end -26.7716 31.3944)
		(width 0.10668)
		(layer "B.Cu")
		(net "SAS_B2_RX2P")
	)
	(arc
		(start -22.515068 13.212387)
		(mid -22.503221 13.202164)
		(end -22.490006 13.193784)
		(width 0.10668)
		(layer "B.Cu")
		(net "SAS_B2_RX2P")
	)
	(arc
		(start -27.378873 32.920727)
		(mid -27.040336 32.414069)
		(end -26.92146 31.816426)
		(width 0.10668)
		(layer "B.Cu")
		(net "SAS_B2_RX2P")
	)
	(arc
		(start -22.8273 13.703303)
		(mid -22.794463 13.53822)
		(end -22.70095 13.398271)
		(width 0.10668)
		(layer "B.Cu")
		(net "SAS_B2_RX2P")
	)
	(arc
		(start -26.5938 30.9172)
		(mid -26.647458 30.787658)
		(end -26.777 30.734)
		(width 0.10668)
		(layer "B.Cu")
		(net "SAS_B2_RX2P")
	)
	(arc
		(start -26.46966 15.81912)
		(mid -26.270282 15.337778)
		(end -25.78894 15.1384)
		(width 0.10668)
		(layer "B.Cu")
		(net "SAS_B2_RX2P")
	)
	(arc
		(start -26.769273 23.344922)
		(mid -26.547527 23.013056)
		(end -26.46966 22.621593)
		(width 0.10668)
		(layer "B.Cu")
		(net "SAS_B2_RX2P")
	)
	(arc
		(start -26.92146 29.81706)
		(mid -26.877567 29.711093)
		(end -26.7716 29.6672)
		(width 0.10668)
		(layer "B.Cu")
		(net "SAS_B2_RX2P")
	)
	(arc
		(start -28.0924 35.18154)
		(mid -27.659552 35.002248)
		(end -27.48026 34.5694)
		(width 0.10668)
		(layer "B.Cu")
		(net "SAS_B2_RX2P")
	)
	(segment
		(start -27.3558 31.816426)
		(end -27.3558 23.71233)
		(width 0.10668)
		(layer "B.Cu")
		(net "SAS_B2_RX2N")
	)
	(segment
		(start -28.680001 34.26)
		(end -28.680001 34.286599)
		(width 0.10668)
		(layer "B.Cu")
		(net "SAS_B2_RX2N")
	)
	(segment
		(start -22.627928 12.653904)
		(end -22.85 12.239371)
		(width 0.10668)
		(layer "B.Cu")
		(net "SAS_B2_RX2N")
	)
	(segment
		(start -22.67159 12.798318)
		(end -22.671588 12.798316)
		(width 0.10668)
		(layer "B.Cu")
		(net "SAS_B2_RX2N")
	)
	(segment
		(start -25.78894 14.70406)
		(end -23.9957 14.70406)
		(width 0.10668)
		(layer "B.Cu")
		(net "SAS_B2_RX2N")
	)
	(segment
		(start -22.695111 12.810919)
		(end -22.671636 12.798341)
		(width 0.10668)
		(layer "B.Cu")
		(net "SAS_B2_RX2N")
	)
	(segment
		(start -22.671636 12.798341)
		(end -22.67159 12.798318)
		(width 0.10668)
		(layer "B.Cu")
		(net "SAS_B2_RX2N")
	)
	(segment
		(start -28.2194 34.7472)
		(end -28.0924 34.7472)
		(width 0.10668)
		(layer "B.Cu")
		(net "SAS_B2_RX2N")
	)
	(segment
		(start -27.9146 34.5694)
		(end -27.9146 33.165489)
		(width 0.10668)
		(layer "B.Cu")
		(net "SAS_B2_RX2N")
	)
	(segment
		(start -23.008077 13.091145)
		(end -22.822192 12.90526)
		(width 0.10668)
		(layer "B.Cu")
		(net "SAS_B2_RX2N")
	)
	(segment
		(start -26.904 22.621591)
		(end -26.904 15.81912)
		(width 0.10668)
		(layer "B.Cu")
		(net "SAS_B2_RX2N")
	)
	(segment
		(start -23.26164 13.97)
		(end -23.26164 13.7033)
		(width 0.10668)
		(layer "B.Cu")
		(net "SAS_B2_RX2N")
	)
	(arc
		(start -23.26164 13.7033)
		(mid -23.195741 13.372004)
		(end -23.008077 13.091145)
		(width 0.10668)
		(layer "B.Cu")
		(net "SAS_B2_RX2N")
	)
	(arc
		(start -28.0924 34.7472)
		(mid -27.966676 34.695124)
		(end -27.9146 34.5694)
		(width 0.10668)
		(layer "B.Cu")
		(net "SAS_B2_RX2N")
	)
	(arc
		(start -27.9146 33.165489)
		(mid -27.855189 32.866809)
		(end -27.686 32.6136)
		(width 0.10668)
		(layer "B.Cu")
		(net "SAS_B2_RX2N")
	)
	(arc
		(start -27.3558 23.71233)
		(mid -27.283186 23.347277)
		(end -27.0764 23.0378)
		(width 0.10668)
		(layer "B.Cu")
		(net "SAS_B2_RX2N")
	)
	(arc
		(start -22.822192 12.90526)
		(mid -22.76212 12.853418)
		(end -22.695111 12.810919)
		(width 0.10668)
		(layer "B.Cu")
		(net "SAS_B2_RX2N")
	)
	(arc
		(start -27.0764 23.0378)
		(mid -26.948806 22.846842)
		(end -26.904 22.621591)
		(width 0.10668)
		(layer "B.Cu")
		(net "SAS_B2_RX2N")
	)
	(arc
		(start -28.680001 34.286599)
		(mid -28.545094 34.612293)
		(end -28.2194 34.7472)
		(width 0.10668)
		(layer "B.Cu")
		(net "SAS_B2_RX2N")
	)
	(arc
		(start -27.686 32.6136)
		(mid -27.441616 32.247853)
		(end -27.3558 31.816426)
		(width 0.10668)
		(layer "B.Cu")
		(net "SAS_B2_RX2N")
	)
	(arc
		(start -22.671588 12.798316)
		(mid -22.619849 12.735152)
		(end -22.627928 12.653904)
		(width 0.10668)
		(layer "B.Cu")
		(net "SAS_B2_RX2N")
	)
	(arc
		(start -23.9957 14.70406)
		(mid -23.476641 14.489059)
		(end -23.26164 13.97)
		(width 0.10668)
		(layer "B.Cu")
		(net "SAS_B2_RX2N")
	)
	(arc
		(start -26.904 15.81912)
		(mid -26.577406 15.030654)
		(end -25.78894 14.70406)
		(width 0.10668)
		(layer "B.Cu")
		(net "SAS_B2_RX2N")
	)
	(segment
		(start -22.946556 39.359606)
		(end -22.946553 39.359606)
		(width 0.10668)
		(layer "B.Cu")
		(net "SAS_B2_RX1P")
	)
	(segment
		(start -17.9578 21.3233)
		(end -17.69951 21.581588)
		(width 0.10668)
		(layer "B.Cu")
		(net "SAS_B2_RX1P")
	)
	(segment
		(start -20.296942 36.709993)
		(end -22.946556 39.359606)
		(width 0.10668)
		(layer "B.Cu")
		(net "SAS_B2_RX1P")
	)
	(segment
		(start -25.472377 40.894)
		(end -25.673037 40.69334)
		(width 0.10668)
		(layer "B.Cu")
		(net "SAS_B2_RX1P")
	)
	(segment
		(start -24.639808 40.69334)
		(end -24.936437 40.69334)
		(width 0.10668)
		(layer "B.Cu")
		(net "SAS_B2_RX1P")
	)
	(segment
		(start -16.63446 24.15285)
		(end -16.63446 29.593243)
		(width 0.10668)
		(layer "B.Cu")
		(net "SAS_B2_RX1P")
	)
	(segment
		(start -22.946553 39.359606)
		(end -23.221 39.634053)
		(width 0.10668)
		(layer "B.Cu")
		(net "SAS_B2_RX1P")
	)
	(segment
		(start -18.64106 19.27098)
		(end -18.641057 19.673768)
		(width 0.10668)
		(layer "B.Cu")
		(net "SAS_B2_RX1P")
	)
	(segment
		(start -22.466485 16.981183)
		(end -22.466485 16.981185)
		(width 0.10668)
		(layer "B.Cu")
		(net "SAS_B2_RX1P")
	)
	(segment
		(start -22.466506 16.981195)
		(end -22.490006 16.993784)
		(width 0.10668)
		(layer "B.Cu")
		(net "SAS_B2_RX1P")
	)
	(segment
		(start -26.357405 40.837404)
		(end -26.68 41.160002)
		(width 0.10668)
		(layer "B.Cu")
		(net "SAS_B2_RX1P")
	)
	(segment
		(start -23.845947 40.259)
		(end -24.026073 40.439127)
		(width 0.10668)
		(layer "B.Cu")
		(net "SAS_B2_RX1P")
	)
	(segment
		(start -23.221 40.0866)
		(end -23.3934 40.259)
		(width 0.10668)
		(layer "B.Cu")
		(net "SAS_B2_RX1P")
	)
	(segment
		(start -24.936437 40.69334)
		(end -25.137097 40.894)
		(width 0.10668)
		(layer "B.Cu")
		(net "SAS_B2_RX1P")
	)
	(segment
		(start -22.448159 18.23466)
		(end -19.67738 18.23466)
		(width 0.10668)
		(layer "B.Cu")
		(net "SAS_B2_RX1P")
	)
	(segment
		(start -22.466483 16.981183)
		(end -22.466485 16.981183)
		(width 0.10668)
		(layer "B.Cu")
		(net "SAS_B2_RX1P")
	)
	(segment
		(start -22.100002 17.439371)
		(end -22.322071 17.02484)
		(width 0.10668)
		(layer "B.Cu")
		(net "SAS_B2_RX1P")
	)
	(segment
		(start -22.515068 17.012387)
		(end -22.722784 17.220105)
		(width 0.10668)
		(layer "B.Cu")
		(net "SAS_B2_RX1P")
	)
	(segment
		(start -25.137097 40.894)
		(end -25.472377 40.894)
		(width 0.10668)
		(layer "B.Cu")
		(net "SAS_B2_RX1P")
	)
	(segment
		(start -17.676073 32.107927)
		(end -18.896023 33.327873)
		(width 0.10668)
		(layer "B.Cu")
		(net "SAS_B2_RX1P")
	)
	(segment
		(start -22.90826 17.667879)
		(end -22.90826 17.774559)
		(width 0.10668)
		(layer "B.Cu")
		(net "SAS_B2_RX1P")
	)
	(segment
		(start -25.673037 40.69334)
		(end -26.0096 40.69334)
		(width 0.10668)
		(layer "B.Cu")
		(net "SAS_B2_RX1P")
	)
	(segment
		(start -22.466485 16.981185)
		(end -22.466506 16.981195)
		(width 0.10668)
		(layer "B.Cu")
		(net "SAS_B2_RX1P")
	)
	(arc
		(start -19.67738 18.23466)
		(mid -18.944591 18.538191)
		(end -18.64106 19.27098)
		(width 0.10668)
		(layer "B.Cu")
		(net "SAS_B2_RX1P")
	)
	(arc
		(start -18.896023 33.327873)
		(mid -19.120894 33.664418)
		(end -19.199857 34.0614)
		(width 0.10668)
		(layer "B.Cu")
		(net "SAS_B2_RX1P")
	)
	(arc
		(start -23.221 39.878)
		(mid -23.177798 39.9823)
		(end -23.221 40.0866)
		(width 0.10668)
		(layer "B.Cu")
		(net "SAS_B2_RX1P")
	)
	(arc
		(start -22.90826 17.774559)
		(mid -22.7735 18.0999)
		(end -22.448159 18.23466)
		(width 0.10668)
		(layer "B.Cu")
		(net "SAS_B2_RX1P")
	)
	(arc
		(start -22.722784 17.220105)
		(mid -22.860056 17.425545)
		(end -22.90826 17.667879)
		(width 0.10668)
		(layer "B.Cu")
		(net "SAS_B2_RX1P")
	)
	(arc
		(start -16.63446 29.593243)
		(mid -16.905166 30.954179)
		(end -17.676073 32.107927)
		(width 0.10668)
		(layer "B.Cu")
		(net "SAS_B2_RX1P")
	)
	(arc
		(start -23.729 40.259)
		(mid -23.787473 40.23478)
		(end -23.845947 40.259)
		(width 0.10668)
		(layer "B.Cu")
		(net "SAS_B2_RX1P")
	)
	(arc
		(start -18.641057 19.673768)
		(mid -18.463484 20.566488)
		(end -17.9578 21.3233)
		(width 0.10668)
		(layer "B.Cu")
		(net "SAS_B2_RX1P")
	)
	(arc
		(start -26.0096 40.69334)
		(mid -26.197831 40.73078)
		(end -26.357405 40.837404)
		(width 0.10668)
		(layer "B.Cu")
		(net "SAS_B2_RX1P")
	)
	(arc
		(start -19.199857 34.0614)
		(mid -19.484981 35.494808)
		(end -20.296942 36.709993)
		(width 0.10668)
		(layer "B.Cu")
		(net "SAS_B2_RX1P")
	)
	(arc
		(start -22.322071 17.02484)
		(mid -22.385236 16.973103)
		(end -22.466483 16.981183)
		(width 0.10668)
		(layer "B.Cu")
		(net "SAS_B2_RX1P")
	)
	(arc
		(start -23.221 39.634053)
		(mid -23.271524 39.756027)
		(end -23.221 39.878)
		(width 0.10668)
		(layer "B.Cu")
		(net "SAS_B2_RX1P")
	)
	(arc
		(start -23.3934 40.259)
		(mid -23.5612 40.328505)
		(end -23.729 40.259)
		(width 0.10668)
		(layer "B.Cu")
		(net "SAS_B2_RX1P")
	)
	(arc
		(start -17.69951 21.581588)
		(mid -16.911257 22.761293)
		(end -16.63446 24.15285)
		(width 0.10668)
		(layer "B.Cu")
		(net "SAS_B2_RX1P")
	)
	(arc
		(start -24.026073 40.439127)
		(mid -24.307657 40.627274)
		(end -24.639808 40.69334)
		(width 0.10668)
		(layer "B.Cu")
		(net "SAS_B2_RX1P")
	)
	(arc
		(start -22.490006 16.993784)
		(mid -22.503221 17.002164)
		(end -22.515068 17.012387)
		(width 0.10668)
		(layer "B.Cu")
		(net "SAS_B2_RX1P")
	)
	(segment
		(start -23.3426 17.667877)
		(end -23.3426 17.774559)
		(width 0.10668)
		(layer "B.Cu")
		(net "SAS_B2_RX1N")
	)
	(segment
		(start -18.264924 21.630427)
		(end -18.006634 21.888714)
		(width 0.10668)
		(layer "B.Cu")
		(net "SAS_B2_RX1N")
	)
	(segment
		(start -22.85 16.039371)
		(end -22.627928 16.453904)
		(width 0.10668)
		(layer "B.Cu")
		(net "SAS_B2_RX1N")
	)
	(segment
		(start -21.666147 37.464947)
		(end -24.3332 40.132)
		(width 0.10668)
		(layer "B.Cu")
		(net "SAS_B2_RX1N")
	)
	(segment
		(start -22.67159 16.598318)
		(end -22.671636 16.598341)
		(width 0.10668)
		(layer "B.Cu")
		(net "SAS_B2_RX1N")
	)
	(segment
		(start -20.604069 36.402866)
		(end -21.666147 37.464947)
		(width 0.10668)
		(layer "B.Cu")
		(net "SAS_B2_RX1N")
	)
	(segment
		(start -19.0754 19.27098)
		(end -19.0754 19.673768)
		(width 0.10668)
		(layer "B.Cu")
		(net "SAS_B2_RX1N")
	)
	(segment
		(start -24.639806 40.259)
		(end -26.0096 40.259)
		(width 0.10668)
		(layer "B.Cu")
		(net "SAS_B2_RX1N")
	)
	(segment
		(start -17.9832 31.8008)
		(end -19.203149 33.020747)
		(width 0.10668)
		(layer "B.Cu")
		(net "SAS_B2_RX1N")
	)
	(segment
		(start -22.671636 16.598341)
		(end -22.695111 16.610919)
		(width 0.10668)
		(layer "B.Cu")
		(net "SAS_B2_RX1N")
	)
	(segment
		(start -26.302203 40.137801)
		(end -26.68 39.760002)
		(width 0.10668)
		(layer "B.Cu")
		(net "SAS_B2_RX1N")
	)
	(segment
		(start -22.671588 16.598316)
		(end -22.67159 16.598318)
		(width 0.10668)
		(layer "B.Cu")
		(net "SAS_B2_RX1N")
	)
	(segment
		(start -22.822192 16.70526)
		(end -23.029911 16.912979)
		(width 0.10668)
		(layer "B.Cu")
		(net "SAS_B2_RX1N")
	)
	(segment
		(start -22.448159 18.669)
		(end -19.67738 18.669)
		(width 0.10668)
		(layer "B.Cu")
		(net "SAS_B2_RX1N")
	)
	(segment
		(start -17.0688 24.15285)
		(end -17.0688 29.593243)
		(width 0.10668)
		(layer "B.Cu")
		(net "SAS_B2_RX1N")
	)
	(arc
		(start -19.203149 33.020747)
		(mid -19.522174 33.498203)
		(end -19.6342 34.0614)
		(width 0.10668)
		(layer "B.Cu")
		(net "SAS_B2_RX1N")
	)
	(arc
		(start -24.3332 40.132)
		(mid -24.473872 40.225994)
		(end -24.639806 40.259)
		(width 0.10668)
		(layer "B.Cu")
		(net "SAS_B2_RX1N")
	)
	(arc
		(start -17.0688 29.593243)
		(mid -17.306445 30.787964)
		(end -17.9832 31.8008)
		(width 0.10668)
		(layer "B.Cu")
		(net "SAS_B2_RX1N")
	)
	(arc
		(start -18.006634 21.888714)
		(mid -17.312534 22.927509)
		(end -17.0688 24.15285)
		(width 0.10668)
		(layer "B.Cu")
		(net "SAS_B2_RX1N")
	)
	(arc
		(start -26.0096 40.259)
		(mid -26.167956 40.227502)
		(end -26.302203 40.137801)
		(width 0.10668)
		(layer "B.Cu")
		(net "SAS_B2_RX1N")
	)
	(arc
		(start -22.695111 16.610919)
		(mid -22.76212 16.653417)
		(end -22.822192 16.70526)
		(width 0.10668)
		(layer "B.Cu")
		(net "SAS_B2_RX1N")
	)
	(arc
		(start -19.6342 34.0614)
		(mid -19.886261 35.328592)
		(end -20.604069 36.402866)
		(width 0.10668)
		(layer "B.Cu")
		(net "SAS_B2_RX1N")
	)
	(arc
		(start -19.67738 18.669)
		(mid -19.251716 18.845316)
		(end -19.0754 19.27098)
		(width 0.10668)
		(layer "B.Cu")
		(net "SAS_B2_RX1N")
	)
	(arc
		(start -19.0754 19.673768)
		(mid -18.864764 20.732704)
		(end -18.264924 21.630427)
		(width 0.10668)
		(layer "B.Cu")
		(net "SAS_B2_RX1N")
	)
	(arc
		(start -22.627928 16.453904)
		(mid -22.619849 16.535152)
		(end -22.671588 16.598316)
		(width 0.10668)
		(layer "B.Cu")
		(net "SAS_B2_RX1N")
	)
	(arc
		(start -23.029911 16.912979)
		(mid -23.261335 17.259329)
		(end -23.3426 17.667877)
		(width 0.10668)
		(layer "B.Cu")
		(net "SAS_B2_RX1N")
	)
	(arc
		(start -23.3426 17.774559)
		(mid -23.080624 18.407024)
		(end -22.448159 18.669)
		(width 0.10668)
		(layer "B.Cu")
		(net "SAS_B2_RX1N")
	)
	(segment
		(start -258.8079 23.164086)
		(end -258.8079 27.4955)
		(width 0.11176)
		(layer "In5.Cu")
		(net "SAS_B1_TX8P")
	)
	(segment
		(start -256.5219 33.7385)
		(end -256.5219 38.7858)
		(width 0.11176)
		(layer "In5.Cu")
		(net "SAS_B1_TX8P")
	)
	(segment
		(start -257.068 39.3319)
		(end -257.20135 39.3319)
		(width 0.11176)
		(layer "In5.Cu")
		(net "SAS_B1_TX8P")
	)
	(segment
		(start -256.35 21.239371)
		(end -256.591262 20.789016)
		(width 0.11176)
		(layer "In5.Cu")
		(net "SAS_B1_TX8P")
	)
	(segment
		(start -256.732176 20.753649)
		(end -257.129023 21.150496)
		(width 0.11176)
		(layer "In5.Cu")
		(net "SAS_B1_TX8P")
	)
	(segment
		(start -258.807903 21.97862)
		(end -258.807903 23.163373)
		(width 0.11176)
		(layer "In5.Cu")
		(net "SAS_B1_TX8P")
	)
	(segment
		(start -256.742552 20.743276)
		(end -256.732176 20.753649)
		(width 0.11176)
		(layer "In5.Cu")
		(net "SAS_B1_TX8P")
	)
	(segment
		(start -257.914143 21.4757)
		(end -258.304983 21.4757)
		(width 0.11176)
		(layer "In5.Cu")
		(net "SAS_B1_TX8P")
	)
	(segment
		(start -256.5219 32.438485)
		(end -256.5219 32.91364)
		(width 0.11176)
		(layer "In5.Cu")
		(net "SAS_B1_TX8P")
	)
	(segment
		(start -256.5219 31.89256)
		(end -256.4765 31.93796)
		(width 0.11176)
		(layer "In5.Cu")
		(net "SAS_B1_TX8P")
	)
	(segment
		(start -258.317352 28.679788)
		(end -257.79984 29.1973)
		(width 0.11176)
		(layer "In5.Cu")
		(net "SAS_B1_TX8P")
	)
	(segment
		(start -256.5219 31.248604)
		(end -256.5219 31.89256)
		(width 0.11176)
		(layer "In5.Cu")
		(net "SAS_B1_TX8P")
	)
	(segment
		(start -258.807903 23.163373)
		(end -258.8079 23.164086)
		(width 0.11176)
		(layer "In5.Cu")
		(net "SAS_B1_TX8P")
	)
	(segment
		(start -256.4765 31.93796)
		(end -256.4765 32.393085)
		(width 0.11176)
		(layer "In5.Cu")
		(net "SAS_B1_TX8P")
	)
	(segment
		(start -257.428992 39.426192)
		(end -257.55074 39.54794)
		(width 0.11176)
		(layer "In5.Cu")
		(net "SAS_B1_TX8P")
	)
	(segment
		(start -256.4765 32.393085)
		(end -256.5219 32.438485)
		(width 0.11176)
		(layer "In5.Cu")
		(net "SAS_B1_TX8P")
	)
	(segment
		(start -256.29076 33.14478)
		(end -256.29076 33.50736)
		(width 0.11176)
		(layer "In5.Cu")
		(net "SAS_B1_TX8P")
	)
	(segment
		(start -257.79984 29.1973)
		(end -257.068752 29.928391)
		(width 0.11176)
		(layer "In5.Cu")
		(net "SAS_B1_TX8P")
	)
	(arc
		(start -257.55074 39.54794)
		(mid -257.646407 39.691115)
		(end -257.68 39.860002)
		(width 0.11176)
		(layer "In5.Cu")
		(net "SAS_B1_TX8P")
	)
	(arc
		(start -258.8079 27.4955)
		(mid -258.680411 28.136432)
		(end -258.317352 28.679788)
		(width 0.11176)
		(layer "In5.Cu")
		(net "SAS_B1_TX8P")
	)
	(arc
		(start -256.44348 33.66008)
		(mid -256.498931 33.683049)
		(end -256.5219 33.7385)
		(width 0.11176)
		(layer "In5.Cu")
		(net "SAS_B1_TX8P")
	)
	(arc
		(start -258.304983 21.4757)
		(mid -258.660601 21.623002)
		(end -258.807903 21.97862)
		(width 0.11176)
		(layer "In5.Cu")
		(net "SAS_B1_TX8P")
	)
	(arc
		(start -256.29076 33.50736)
		(mid -256.335491 33.615349)
		(end -256.44348 33.66008)
		(width 0.11176)
		(layer "In5.Cu")
		(net "SAS_B1_TX8P")
	)
	(arc
		(start -257.129023 21.150496)
		(mid -257.489239 21.391184)
		(end -257.914143 21.4757)
		(width 0.11176)
		(layer "In5.Cu")
		(net "SAS_B1_TX8P")
	)
	(arc
		(start -256.5219 38.7858)
		(mid -256.681849 39.171951)
		(end -257.068 39.3319)
		(width 0.11176)
		(layer "In5.Cu")
		(net "SAS_B1_TX8P")
	)
	(arc
		(start -256.5219 32.91364)
		(mid -256.49298 32.98346)
		(end -256.42316 33.01238)
		(width 0.11176)
		(layer "In5.Cu")
		(net "SAS_B1_TX8P")
	)
	(arc
		(start -256.591262 20.789016)
		(mid -256.657434 20.734813)
		(end -256.742552 20.743276)
		(width 0.11176)
		(layer "In5.Cu")
		(net "SAS_B1_TX8P")
	)
	(arc
		(start -257.068752 29.928391)
		(mid -256.664023 30.53411)
		(end -256.5219 31.248604)
		(width 0.11176)
		(layer "In5.Cu")
		(net "SAS_B1_TX8P")
	)
	(arc
		(start -256.42316 33.01238)
		(mid -256.329539 33.051159)
		(end -256.29076 33.14478)
		(width 0.11176)
		(layer "In5.Cu")
		(net "SAS_B1_TX8P")
	)
	(arc
		(start -257.20135 39.3319)
		(mid -257.324549 39.356406)
		(end -257.428992 39.426192)
		(width 0.11176)
		(layer "In5.Cu")
		(net "SAS_B1_TX8P")
	)
	(segment
		(start -257.100001 19.839371)
		(end -256.85874 20.289728)
		(width 0.11176)
		(layer "In5.Cu")
		(net "SAS_B1_TX8N")
	)
	(segment
		(start -259.150803 23.163985)
		(end -259.1508 23.164698)
		(width 0.11176)
		(layer "In5.Cu")
		(net "SAS_B1_TX8N")
	)
	(segment
		(start -256.904477 20.441018)
		(end -256.90448 20.441018)
		(width 0.11176)
		(layer "In5.Cu")
		(net "SAS_B1_TX8N")
	)
	(segment
		(start -256.8648 32.9111)
		(end -256.8648 38.7858)
		(width 0.11176)
		(layer "In5.Cu")
		(net "SAS_B1_TX8N")
	)
	(segment
		(start -256.90448 20.441018)
		(end -257.371489 20.908028)
		(width 0.11176)
		(layer "In5.Cu")
		(net "SAS_B1_TX8N")
	)
	(segment
		(start -258.559821 28.922256)
		(end -258.042308 29.439768)
		(width 0.11176)
		(layer "In5.Cu")
		(net "SAS_B1_TX8N")
	)
	(segment
		(start -257.068 38.989)
		(end -257.151002 38.989)
		(width 0.11176)
		(layer "In5.Cu")
		(net "SAS_B1_TX8N")
	)
	(segment
		(start -257.91414 21.1328)
		(end -258.304983 21.1328)
		(width 0.11176)
		(layer "In5.Cu")
		(net "SAS_B1_TX8N")
	)
	(segment
		(start -256.864803 31.248604)
		(end -256.8648 32.9111)
		(width 0.11176)
		(layer "In5.Cu")
		(net "SAS_B1_TX8N")
	)
	(segment
		(start -259.150803 21.97862)
		(end -259.150803 23.163985)
		(width 0.11176)
		(layer "In5.Cu")
		(net "SAS_B1_TX8N")
	)
	(segment
		(start -258.042308 29.439768)
		(end -257.31122 30.170859)
		(width 0.11176)
		(layer "In5.Cu")
		(net "SAS_B1_TX8N")
	)
	(segment
		(start -259.1508 23.164698)
		(end -259.1508 27.495497)
		(width 0.11176)
		(layer "In5.Cu")
		(net "SAS_B1_TX8N")
	)
	(arc
		(start -256.85874 20.289728)
		(mid -256.850276 20.374845)
		(end -256.904477 20.441018)
		(width 0.11176)
		(layer "In5.Cu")
		(net "SAS_B1_TX8N")
	)
	(arc
		(start -259.1508 27.495497)
		(mid -258.997211 28.267653)
		(end -258.559821 28.922256)
		(width 0.11176)
		(layer "In5.Cu")
		(net "SAS_B1_TX8N")
	)
	(arc
		(start -258.304983 21.1328)
		(mid -258.903068 21.380535)
		(end -259.150803 21.97862)
		(width 0.11176)
		(layer "In5.Cu")
		(net "SAS_B1_TX8N")
	)
	(arc
		(start -257.151002 38.989)
		(mid -257.52506 38.83406)
		(end -257.68 38.460002)
		(width 0.11176)
		(layer "In5.Cu")
		(net "SAS_B1_TX8N")
	)
	(arc
		(start -257.31122 30.170859)
		(mid -256.980822 30.665332)
		(end -256.864803 31.248604)
		(width 0.11176)
		(layer "In5.Cu")
		(net "SAS_B1_TX8N")
	)
	(arc
		(start -257.371489 20.908028)
		(mid -257.62046 21.074384)
		(end -257.91414 21.1328)
		(width 0.11176)
		(layer "In5.Cu")
		(net "SAS_B1_TX8N")
	)
	(arc
		(start -256.8648 38.7858)
		(mid -256.924316 38.929484)
		(end -257.068 38.989)
		(width 0.11176)
		(layer "In5.Cu")
		(net "SAS_B1_TX8N")
	)
	(segment
		(start -254.528 30.00756)
		(end -254.528 29.531447)
		(width 0.11176)
		(layer "In5.Cu")
		(net "SAS_B1_TX7P")
	)
	(segment
		(start -254.48514 30.516891)
		(end -254.48514 30.05042)
		(width 0.11176)
		(layer "In5.Cu")
		(net "SAS_B1_TX7P")
	)
	(segment
		(start -255.679999 36.96)
		(end -255.679999 36.927899)
		(width 0.11176)
		(layer "In5.Cu")
		(net "SAS_B1_TX7P")
	)
	(segment
		(start -257.1823 25.121347)
		(end -257.1823 25.0952)
		(width 0.11176)
		(layer "In5.Cu")
		(net "SAS_B1_TX7P")
	)
	(segment
		(start -254.48514 30.05042)
		(end -254.528 30.00756)
		(width 0.11176)
		(layer "In5.Cu")
		(net "SAS_B1_TX7P")
	)
	(segment
		(start -254.528 31.12802)
		(end -254.528 30.559751)
		(width 0.11176)
		(layer "In5.Cu")
		(net "SAS_B1_TX7P")
	)
	(segment
		(start -256.659949 26.074751)
		(end -256.8775 25.8572)
		(width 0.11176)
		(layer "In5.Cu")
		(net "SAS_B1_TX7P")
	)
	(segment
		(start -254.7874 28.9052)
		(end -256.081395 27.611205)
		(width 0.11176)
		(layer "In5.Cu")
		(net "SAS_B1_TX7P")
	)
	(segment
		(start -254.528 35.9156)
		(end -254.528 32.01384)
		(width 0.11176)
		(layer "In5.Cu")
		(net "SAS_B1_TX7P")
	)
	(segment
		(start -256.778735 24.562661)
		(end -256.742555 24.543278)
		(width 0.11176)
		(layer "In5.Cu")
		(net "SAS_B1_TX7P")
	)
	(segment
		(start -254.29686 31.7827)
		(end -254.29686 31.35916)
		(width 0.11176)
		(layer "In5.Cu")
		(net "SAS_B1_TX7P")
	)
	(segment
		(start -257.086318 24.863481)
		(end -256.804986 24.582148)
		(width 0.11176)
		(layer "In5.Cu")
		(net "SAS_B1_TX7P")
	)
	(segment
		(start -256.3187 27.0383)
		(end -256.3187 26.8986)
		(width 0.11176)
		(layer "In5.Cu")
		(net "SAS_B1_TX7P")
	)
	(segment
		(start -256.742555 24.543278)
		(end -256.742552 24.543276)
		(width 0.11176)
		(layer "In5.Cu")
		(net "SAS_B1_TX7P")
	)
	(segment
		(start -254.528 30.559751)
		(end -254.48514 30.516891)
		(width 0.11176)
		(layer "In5.Cu")
		(net "SAS_B1_TX7P")
	)
	(segment
		(start -255.1884 36.4363)
		(end -255.0487 36.4363)
		(width 0.11176)
		(layer "In5.Cu")
		(net "SAS_B1_TX7P")
	)
	(segment
		(start -256.591262 24.589016)
		(end -256.35 25.039371)
		(width 0.11176)
		(layer "In5.Cu")
		(net "SAS_B1_TX7P")
	)
	(arc
		(start -256.3187 26.8986)
		(mid -256.407388 26.452736)
		(end -256.659949 26.074751)
		(width 0.11176)
		(layer "In5.Cu")
		(net "SAS_B1_TX7P")
	)
	(arc
		(start -254.528 29.531447)
		(mid -254.595416 29.192525)
		(end -254.7874 28.9052)
		(width 0.11176)
		(layer "In5.Cu")
		(net "SAS_B1_TX7P")
	)
	(arc
		(start -254.528 32.01384)
		(mid -254.49908 31.94402)
		(end -254.42926 31.9151)
		(width 0.11176)
		(layer "In5.Cu")
		(net "SAS_B1_TX7P")
	)
	(arc
		(start -256.804986 24.582148)
		(mid -256.792577 24.571439)
		(end -256.778735 24.562661)
		(width 0.11176)
		(layer "In5.Cu")
		(net "SAS_B1_TX7P")
	)
	(arc
		(start -257.1823 25.0952)
		(mid -257.157355 24.969794)
		(end -257.086318 24.863481)
		(width 0.11176)
		(layer "In5.Cu")
		(net "SAS_B1_TX7P")
	)
	(arc
		(start -256.081395 27.611205)
		(mid -256.257027 27.348354)
		(end -256.3187 27.0383)
		(width 0.11176)
		(layer "In5.Cu")
		(net "SAS_B1_TX7P")
	)
	(arc
		(start -254.42926 31.9151)
		(mid -254.335639 31.876321)
		(end -254.29686 31.7827)
		(width 0.11176)
		(layer "In5.Cu")
		(net "SAS_B1_TX7P")
	)
	(arc
		(start -256.742552 24.543276)
		(mid -256.657434 24.534812)
		(end -256.591262 24.589016)
		(width 0.11176)
		(layer "In5.Cu")
		(net "SAS_B1_TX7P")
	)
	(arc
		(start -254.29686 31.35916)
		(mid -254.341591 31.251171)
		(end -254.44958 31.20644)
		(width 0.11176)
		(layer "In5.Cu")
		(net "SAS_B1_TX7P")
	)
	(arc
		(start -254.44958 31.20644)
		(mid -254.505031 31.183471)
		(end -254.528 31.12802)
		(width 0.11176)
		(layer "In5.Cu")
		(net "SAS_B1_TX7P")
	)
	(arc
		(start -256.8775 25.8572)
		(mid -257.103085 25.519588)
		(end -257.1823 25.121347)
		(width 0.11176)
		(layer "In5.Cu")
		(net "SAS_B1_TX7P")
	)
	(arc
		(start -255.0487 36.4363)
		(mid -254.680509 36.283791)
		(end -254.528 35.9156)
		(width 0.11176)
		(layer "In5.Cu")
		(net "SAS_B1_TX7P")
	)
	(arc
		(start -255.679999 36.927899)
		(mid -255.536013 36.580286)
		(end -255.1884 36.4363)
		(width 0.11176)
		(layer "In5.Cu")
		(net "SAS_B1_TX7P")
	)
	(segment
		(start -255.679999 35.56)
		(end -255.679999 35.601801)
		(width 0.11176)
		(layer "In5.Cu")
		(net "SAS_B1_TX7N")
	)
	(segment
		(start -256.6616 27.038297)
		(end -256.6616 26.898603)
		(width 0.11176)
		(layer "In5.Cu")
		(net "SAS_B1_TX7N")
	)
	(segment
		(start -254.8709 35.9156)
		(end -254.8709 29.531447)
		(width 0.11176)
		(layer "In5.Cu")
		(net "SAS_B1_TX7N")
	)
	(segment
		(start -255.1884 36.0934)
		(end -255.0487 36.0934)
		(width 0.11176)
		(layer "In5.Cu")
		(net "SAS_B1_TX7N")
	)
	(segment
		(start -257.328787 24.621012)
		(end -257.047451 24.339677)
		(width 0.11176)
		(layer "In5.Cu")
		(net "SAS_B1_TX7N")
	)
	(segment
		(start -257.5252 25.121347)
		(end -257.5252 25.095197)
		(width 0.11176)
		(layer "In5.Cu")
		(net "SAS_B1_TX7N")
	)
	(segment
		(start -255.029868 29.147668)
		(end -256.323864 27.853673)
		(width 0.11176)
		(layer "In5.Cu")
		(net "SAS_B1_TX7N")
	)
	(segment
		(start -256.85874 24.089728)
		(end -257.100001 23.639371)
		(width 0.11176)
		(layer "In5.Cu")
		(net "SAS_B1_TX7N")
	)
	(segment
		(start -256.90448 24.241018)
		(end -256.904477 24.241018)
		(width 0.11176)
		(layer "In5.Cu")
		(net "SAS_B1_TX7N")
	)
	(segment
		(start -256.94085 24.260503)
		(end -256.90448 24.241018)
		(width 0.11176)
		(layer "In5.Cu")
		(net "SAS_B1_TX7N")
	)
	(segment
		(start -256.902417 26.317219)
		(end -257.119968 26.099668)
		(width 0.11176)
		(layer "In5.Cu")
		(net "SAS_B1_TX7N")
	)
	(arc
		(start -256.6616 26.898603)
		(mid -256.724186 26.58396)
		(end -256.902417 26.317219)
		(width 0.11176)
		(layer "In5.Cu")
		(net "SAS_B1_TX7N")
	)
	(arc
		(start -257.119968 26.099668)
		(mid -257.419884 25.65081)
		(end -257.5252 25.121347)
		(width 0.11176)
		(layer "In5.Cu")
		(net "SAS_B1_TX7N")
	)
	(arc
		(start -257.047451 24.339677)
		(mid -256.997056 24.296177)
		(end -256.94085 24.260503)
		(width 0.11176)
		(layer "In5.Cu")
		(net "SAS_B1_TX7N")
	)
	(arc
		(start -254.8709 29.531447)
		(mid -254.912215 29.323747)
		(end -255.029868 29.147668)
		(width 0.11176)
		(layer "In5.Cu")
		(net "SAS_B1_TX7N")
	)
	(arc
		(start -256.323864 27.853673)
		(mid -256.573827 27.479575)
		(end -256.6616 27.038297)
		(width 0.11176)
		(layer "In5.Cu")
		(net "SAS_B1_TX7N")
	)
	(arc
		(start -257.5252 25.095197)
		(mid -257.474154 24.83857)
		(end -257.328787 24.621012)
		(width 0.11176)
		(layer "In5.Cu")
		(net "SAS_B1_TX7N")
	)
	(arc
		(start -255.0487 36.0934)
		(mid -254.922976 36.041324)
		(end -254.8709 35.9156)
		(width 0.11176)
		(layer "In5.Cu")
		(net "SAS_B1_TX7N")
	)
	(arc
		(start -255.679999 35.601801)
		(mid -255.536013 35.949414)
		(end -255.1884 36.0934)
		(width 0.11176)
		(layer "In5.Cu")
		(net "SAS_B1_TX7N")
	)
	(arc
		(start -256.904477 24.241018)
		(mid -256.850275 24.174845)
		(end -256.85874 24.089728)
		(width 0.11176)
		(layer "In5.Cu")
		(net "SAS_B1_TX7N")
	)
	(segment
		(start -257.890292 27.9654)
		(end -255.51606 27.9654)
		(width 0.10668)
		(layer "B.Cu")
		(net "SAS_B1_TX6P")
	)
	(segment
		(start -255.32588 22.03704)
		(end -255.32588 22.10308)
		(width 0.10668)
		(layer "B.Cu")
		(net "SAS_B1_TX6P")
	)
	(segment
		(start -254.3248 30.3784)
		(end -254.2994 30.3784)
		(width 0.10668)
		(layer "B.Cu")
		(net "SAS_B1_TX6P")
	)
	(segment
		(start -254.37052 32.258)
		(end -254.381 32.258)
		(width 0.10668)
		(layer "B.Cu")
		(net "SAS_B1_TX6P")
	)
	(segment
		(start -258.399018 27.747328)
		(end -258.386473 27.759873)
		(width 0.10668)
		(layer "B.Cu")
		(net "SAS_B1_TX6P")
	)
	(segment
		(start -255.1122 44.88434)
		(end -255.2392 44.88434)
		(width 0.10668)
		(layer "B.Cu")
		(net "SAS_B1_TX6P")
	)
	(segment
		(start -257.722126 22.993429)
		(end -258.0078 23.2791)
		(width 0.10668)
		(layer "B.Cu")
		(net "SAS_B1_TX6P")
	)
	(segment
		(start -254.254 30.988)
		(end -254.34766 30.988)
		(width 0.10668)
		(layer "B.Cu")
		(net "SAS_B1_TX6P")
	)
	(segment
		(start -254.466484 20.78118)
		(end -254.466486 20.78118)
		(width 0.10668)
		(layer "B.Cu")
		(net "SAS_B1_TX6P")
	)
	(segment
		(start -254.1 21.239371)
		(end -254.322072 20.824838)
		(width 0.10668)
		(layer "B.Cu")
		(net "SAS_B1_TX6P")
	)
	(segment
		(start -255.679999 45.325139)
		(end -255.679999 45.360001)
		(width 0.10668)
		(layer "B.Cu")
		(net "SAS_B1_TX6P")
	)
	(segment
		(start -254.1724 31.8316)
		(end -254.1724 32.05988)
		(width 0.10668)
		(layer "B.Cu")
		(net "SAS_B1_TX6P")
	)
	(segment
		(start -254.47466 29.0068)
		(end -254.47466 30.22854)
		(width 0.10668)
		(layer "B.Cu")
		(net "SAS_B1_TX6P")
	)
	(segment
		(start -254.147 30.5308)
		(end -254.147 30.881)
		(width 0.10668)
		(layer "B.Cu")
		(net "SAS_B1_TX6P")
	)
	(segment
		(start -258.79266 25.17392)
		(end -258.79266 26.797)
		(width 0.10668)
		(layer "B.Cu")
		(net "SAS_B1_TX6P")
	)
	(segment
		(start -254.47466 31.115)
		(end -254.47466 31.52934)
		(width 0.10668)
		(layer "B.Cu")
		(net "SAS_B1_TX6P")
	)
	(segment
		(start -254.47466 32.35166)
		(end -254.47466 44.2468)
		(width 0.10668)
		(layer "B.Cu")
		(net "SAS_B1_TX6P")
	)
	(segment
		(start -254.98552 21.40966)
		(end -255.122926 21.547066)
		(width 0.10668)
		(layer "B.Cu")
		(net "SAS_B1_TX6P")
	)
	(segment
		(start -254.466486 20.78118)
		(end -254.560522 20.831556)
		(width 0.10668)
		(layer "B.Cu")
		(net "SAS_B1_TX6P")
	)
	(segment
		(start -255.9558 22.733)
		(end -257.0934 22.733)
		(width 0.10668)
		(layer "B.Cu")
		(net "SAS_B1_TX6P")
	)
	(arc
		(start -255.32588 22.10308)
		(mid -255.510379 22.548501)
		(end -255.9558 22.733)
		(width 0.10668)
		(layer "B.Cu")
		(net "SAS_B1_TX6P")
	)
	(arc
		(start -254.560522 20.831556)
		(mid -254.628849 20.884708)
		(end -254.67564 20.95754)
		(width 0.10668)
		(layer "B.Cu")
		(net "SAS_B1_TX6P")
	)
	(arc
		(start -254.2994 30.3784)
		(mid -254.191637 30.423037)
		(end -254.147 30.5308)
		(width 0.10668)
		(layer "B.Cu")
		(net "SAS_B1_TX6P")
	)
	(arc
		(start -254.381 31.623)
		(mid -254.233498 31.684098)
		(end -254.1724 31.8316)
		(width 0.10668)
		(layer "B.Cu")
		(net "SAS_B1_TX6P")
	)
	(arc
		(start -258.0078 23.2791)
		(mid -258.588682 24.148451)
		(end -258.79266 25.17392)
		(width 0.10668)
		(layer "B.Cu")
		(net "SAS_B1_TX6P")
	)
	(arc
		(start -258.79266 26.797)
		(mid -258.690355 27.311314)
		(end -258.399018 27.747328)
		(width 0.10668)
		(layer "B.Cu")
		(net "SAS_B1_TX6P")
	)
	(arc
		(start -255.51606 27.9654)
		(mid -254.779679 28.270419)
		(end -254.47466 29.0068)
		(width 0.10668)
		(layer "B.Cu")
		(net "SAS_B1_TX6P")
	)
	(arc
		(start -255.2392 44.88434)
		(mid -255.550892 45.013447)
		(end -255.679999 45.325139)
		(width 0.10668)
		(layer "B.Cu")
		(net "SAS_B1_TX6P")
	)
	(arc
		(start -258.386473 27.759873)
		(mid -258.158823 27.911984)
		(end -257.890292 27.9654)
		(width 0.10668)
		(layer "B.Cu")
		(net "SAS_B1_TX6P")
	)
	(arc
		(start -254.1724 32.05988)
		(mid -254.230428 32.199972)
		(end -254.37052 32.258)
		(width 0.10668)
		(layer "B.Cu")
		(net "SAS_B1_TX6P")
	)
	(arc
		(start -254.67564 20.95754)
		(mid -254.807998 21.199077)
		(end -254.98552 21.40966)
		(width 0.10668)
		(layer "B.Cu")
		(net "SAS_B1_TX6P")
	)
	(arc
		(start -254.381 32.258)
		(mid -254.447228 32.285432)
		(end -254.47466 32.35166)
		(width 0.10668)
		(layer "B.Cu")
		(net "SAS_B1_TX6P")
	)
	(arc
		(start -254.147 30.881)
		(mid -254.17834 30.95666)
		(end -254.254 30.988)
		(width 0.10668)
		(layer "B.Cu")
		(net "SAS_B1_TX6P")
	)
	(arc
		(start -254.47466 31.52934)
		(mid -254.447228 31.595568)
		(end -254.381 31.623)
		(width 0.10668)
		(layer "B.Cu")
		(net "SAS_B1_TX6P")
	)
	(arc
		(start -254.47466 44.2468)
		(mid -254.661391 44.697609)
		(end -255.1122 44.88434)
		(width 0.10668)
		(layer "B.Cu")
		(net "SAS_B1_TX6P")
	)
	(arc
		(start -254.322072 20.824838)
		(mid -254.385236 20.7731)
		(end -254.466484 20.78118)
		(width 0.10668)
		(layer "B.Cu")
		(net "SAS_B1_TX6P")
	)
	(arc
		(start -255.122926 21.547066)
		(mid -255.273134 21.771868)
		(end -255.32588 22.03704)
		(width 0.10668)
		(layer "B.Cu")
		(net "SAS_B1_TX6P")
	)
	(arc
		(start -254.34766 30.988)
		(mid -254.437463 31.025197)
		(end -254.47466 31.115)
		(width 0.10668)
		(layer "B.Cu")
		(net "SAS_B1_TX6P")
	)
	(arc
		(start -257.0934 22.733)
		(mid -257.433664 22.800684)
		(end -257.722126 22.993429)
		(width 0.10668)
		(layer "B.Cu")
		(net "SAS_B1_TX6P")
	)
	(arc
		(start -254.47466 30.22854)
		(mid -254.430767 30.334507)
		(end -254.3248 30.3784)
		(width 0.10668)
		(layer "B.Cu")
		(net "SAS_B1_TX6P")
	)
	(segment
		(start -258.706145 28.054455)
		(end -258.6936 28.067)
		(width 0.10668)
		(layer "B.Cu")
		(net "SAS_B1_TX6N")
	)
	(segment
		(start -254.671589 20.398313)
		(end -254.671591 20.398316)
		(width 0.10668)
		(layer "B.Cu")
		(net "SAS_B1_TX6N")
	)
	(segment
		(start -254.850001 19.839371)
		(end -254.627929 20.253902)
		(width 0.10668)
		(layer "B.Cu")
		(net "SAS_B1_TX6N")
	)
	(segment
		(start -255.290406 21.100296)
		(end -255.430053 21.23994)
		(width 0.10668)
		(layer "B.Cu")
		(net "SAS_B1_TX6N")
	)
	(segment
		(start -255.76022 22.037043)
		(end -255.76022 22.10308)
		(width 0.10668)
		(layer "B.Cu")
		(net "SAS_B1_TX6N")
	)
	(segment
		(start -259.227 25.173917)
		(end -259.227 26.797)
		(width 0.10668)
		(layer "B.Cu")
		(net "SAS_B1_TX6N")
	)
	(segment
		(start -258.029253 22.686302)
		(end -258.314924 22.971973)
		(width 0.10668)
		(layer "B.Cu")
		(net "SAS_B1_TX6N")
	)
	(segment
		(start -255.9558 22.29866)
		(end -257.093403 22.29866)
		(width 0.10668)
		(layer "B.Cu")
		(net "SAS_B1_TX6N")
	)
	(segment
		(start -255.679999 44.009201)
		(end -255.679999 43.960001)
		(width 0.10668)
		(layer "B.Cu")
		(net "SAS_B1_TX6N")
	)
	(segment
		(start -255.288133 21.098088)
		(end -255.290406 21.100296)
		(width 0.10668)
		(layer "B.Cu")
		(net "SAS_B1_TX6N")
	)
	(segment
		(start -254.671591 20.398316)
		(end -254.765627 20.448692)
		(width 0.10668)
		(layer "B.Cu")
		(net "SAS_B1_TX6N")
	)
	(segment
		(start -254.909 29.0068)
		(end -254.909 44.2468)
		(width 0.10668)
		(layer "B.Cu")
		(net "SAS_B1_TX6N")
	)
	(segment
		(start -257.890294 28.39974)
		(end -255.51606 28.39974)
		(width 0.10668)
		(layer "B.Cu")
		(net "SAS_B1_TX6N")
	)
	(segment
		(start -255.1122 44.45)
		(end -255.2392 44.45)
		(width 0.10668)
		(layer "B.Cu")
		(net "SAS_B1_TX6N")
	)
	(arc
		(start -254.627929 20.253902)
		(mid -254.619851 20.33515)
		(end -254.671589 20.398313)
		(width 0.10668)
		(layer "B.Cu")
		(net "SAS_B1_TX6N")
	)
	(arc
		(start -254.909 44.2468)
		(mid -254.968516 44.390484)
		(end -255.1122 44.45)
		(width 0.10668)
		(layer "B.Cu")
		(net "SAS_B1_TX6N")
	)
	(arc
		(start -255.51606 28.39974)
		(mid -255.086804 28.577544)
		(end -254.909 29.0068)
		(width 0.10668)
		(layer "B.Cu")
		(net "SAS_B1_TX6N")
	)
	(arc
		(start -259.227 26.797)
		(mid -259.091634 27.47753)
		(end -258.706145 28.054455)
		(width 0.10668)
		(layer "B.Cu")
		(net "SAS_B1_TX6N")
	)
	(arc
		(start -257.093403 22.29866)
		(mid -257.599881 22.399406)
		(end -258.029253 22.686302)
		(width 0.10668)
		(layer "B.Cu")
		(net "SAS_B1_TX6N")
	)
	(arc
		(start -258.314924 22.971973)
		(mid -258.989959 23.982233)
		(end -259.227 25.173917)
		(width 0.10668)
		(layer "B.Cu")
		(net "SAS_B1_TX6N")
	)
	(arc
		(start -255.2392 44.45)
		(mid -255.550892 44.320893)
		(end -255.679999 44.009201)
		(width 0.10668)
		(layer "B.Cu")
		(net "SAS_B1_TX6N")
	)
	(arc
		(start -255.0754 20.787708)
		(mid -255.166264 20.953523)
		(end -255.288133 21.098088)
		(width 0.10668)
		(layer "B.Cu")
		(net "SAS_B1_TX6N")
	)
	(arc
		(start -258.6936 28.067)
		(mid -258.32504 28.313264)
		(end -257.890294 28.39974)
		(width 0.10668)
		(layer "B.Cu")
		(net "SAS_B1_TX6N")
	)
	(arc
		(start -255.76022 22.10308)
		(mid -255.817504 22.241376)
		(end -255.9558 22.29866)
		(width 0.10668)
		(layer "B.Cu")
		(net "SAS_B1_TX6N")
	)
	(arc
		(start -255.430053 21.23994)
		(mid -255.674414 21.605654)
		(end -255.76022 22.037043)
		(width 0.10668)
		(layer "B.Cu")
		(net "SAS_B1_TX6N")
	)
	(arc
		(start -254.765627 20.448692)
		(mid -254.949491 20.591722)
		(end -255.0754 20.787708)
		(width 0.10668)
		(layer "B.Cu")
		(net "SAS_B1_TX6N")
	)
	(segment
		(start -252.5341 32.357538)
		(end -252.5014 32.324838)
		(width 0.11176)
		(layer "In5.Cu")
		(net "SAS_B1_TX5P")
	)
	(segment
		(start -254.341262 24.589016)
		(end -254.1 25.039371)
		(width 0.11176)
		(layer "In5.Cu")
		(net "SAS_B1_TX5P")
	)
	(segment
		(start -254.68405 24.709788)
		(end -254.558058 24.583796)
		(width 0.11176)
		(layer "In5.Cu")
		(net "SAS_B1_TX5P")
	)
	(segment
		(start -254.53181 24.56431)
		(end -254.492554 24.543278)
		(width 0.11176)
		(layer "In5.Cu")
		(net "SAS_B1_TX5P")
	)
	(segment
		(start -252.5014 31.89192)
		(end -252.5341 31.85922)
		(width 0.11176)
		(layer "In5.Cu")
		(net "SAS_B1_TX5P")
	)
	(segment
		(start -252.5341 38.735)
		(end -252.5341 33.6242)
		(width 0.11176)
		(layer "In5.Cu")
		(net "SAS_B1_TX5P")
	)
	(segment
		(start -253.151899 39.3319)
		(end -253.131 39.3319)
		(width 0.11176)
		(layer "In5.Cu")
		(net "SAS_B1_TX5P")
	)
	(segment
		(start -254.8963 25.397884)
		(end -254.896297 25.2222)
		(width 0.11176)
		(layer "In5.Cu")
		(net "SAS_B1_TX5P")
	)
	(segment
		(start -252.30328 33.39338)
		(end -252.30328 33.00222)
		(width 0.11176)
		(layer "In5.Cu")
		(net "SAS_B1_TX5P")
	)
	(segment
		(start -252.5341 31.85922)
		(end -252.5341 31.10074)
		(width 0.11176)
		(layer "In5.Cu")
		(net "SAS_B1_TX5P")
	)
	(segment
		(start -254.492554 24.543278)
		(end -254.492552 24.543276)
		(width 0.11176)
		(layer "In5.Cu")
		(net "SAS_B1_TX5P")
	)
	(segment
		(start -252.5341 32.7714)
		(end -252.5341 32.357538)
		(width 0.11176)
		(layer "In5.Cu")
		(net "SAS_B1_TX5P")
	)
	(segment
		(start -252.5014 32.324838)
		(end -252.5014 31.89192)
		(width 0.11176)
		(layer "In5.Cu")
		(net "SAS_B1_TX5P")
	)
	(arc
		(start -254.558058 24.583796)
		(mid -254.54565 24.573088)
		(end -254.53181 24.56431)
		(width 0.11176)
		(layer "In5.Cu")
		(net "SAS_B1_TX5P")
	)
	(arc
		(start -253.680001 39.860002)
		(mid -253.525324 39.486577)
		(end -253.151899 39.3319)
		(width 0.11176)
		(layer "In5.Cu")
		(net "SAS_B1_TX5P")
	)
	(arc
		(start -252.4379 32.8676)
		(mid -252.505924 32.839424)
		(end -252.5341 32.7714)
		(width 0.11176)
		(layer "In5.Cu")
		(net "SAS_B1_TX5P")
	)
	(arc
		(start -252.30328 33.00222)
		(mid -252.342709 32.907029)
		(end -252.4379 32.8676)
		(width 0.11176)
		(layer "In5.Cu")
		(net "SAS_B1_TX5P")
	)
	(arc
		(start -254.133132 27.240332)
		(mid -254.697959 26.39501)
		(end -254.8963 25.397884)
		(width 0.11176)
		(layer "In5.Cu")
		(net "SAS_B1_TX5P")
	)
	(arc
		(start -253.131 39.3319)
		(mid -252.708928 39.157072)
		(end -252.5341 38.735)
		(width 0.11176)
		(layer "In5.Cu")
		(net "SAS_B1_TX5P")
	)
	(arc
		(start -254.896297 25.2222)
		(mid -254.841136 24.944885)
		(end -254.68405 24.709788)
		(width 0.11176)
		(layer "In5.Cu")
		(net "SAS_B1_TX5P")
	)
	(arc
		(start -252.5341 33.6242)
		(mid -252.508899 33.563361)
		(end -252.44806 33.53816)
		(width 0.11176)
		(layer "In5.Cu")
		(net "SAS_B1_TX5P")
	)
	(arc
		(start -254.492552 24.543276)
		(mid -254.407434 24.534812)
		(end -254.341262 24.589016)
		(width 0.11176)
		(layer "In5.Cu")
		(net "SAS_B1_TX5P")
	)
	(arc
		(start -252.5341 31.10074)
		(mid -252.949674 29.011502)
		(end -254.133132 27.240332)
		(width 0.11176)
		(layer "In5.Cu")
		(net "SAS_B1_TX5P")
	)
	(arc
		(start -252.44806 33.53816)
		(mid -252.345685 33.495755)
		(end -252.30328 33.39338)
		(width 0.11176)
		(layer "In5.Cu")
		(net "SAS_B1_TX5P")
	)
	(segment
		(start -255.2392 25.397884)
		(end -255.2392 25.2222)
		(width 0.11176)
		(layer "In5.Cu")
		(net "SAS_B1_TX5N")
	)
	(segment
		(start -252.877 38.735)
		(end -252.877 31.10074)
		(width 0.11176)
		(layer "In5.Cu")
		(net "SAS_B1_TX5N")
	)
	(segment
		(start -253.151002 38.989)
		(end -253.131 38.989)
		(width 0.11176)
		(layer "In5.Cu")
		(net "SAS_B1_TX5N")
	)
	(segment
		(start -254.608739 24.089728)
		(end -254.850001 23.639371)
		(width 0.11176)
		(layer "In5.Cu")
		(net "SAS_B1_TX5N")
	)
	(segment
		(start -254.926518 24.46732)
		(end -254.800527 24.341328)
		(width 0.11176)
		(layer "In5.Cu")
		(net "SAS_B1_TX5N")
	)
	(segment
		(start -254.693738 24.26205)
		(end -254.654479 24.241018)
		(width 0.11176)
		(layer "In5.Cu")
		(net "SAS_B1_TX5N")
	)
	(segment
		(start -254.654479 24.241018)
		(end -254.654477 24.241018)
		(width 0.11176)
		(layer "In5.Cu")
		(net "SAS_B1_TX5N")
	)
	(arc
		(start -253.131 38.989)
		(mid -252.951395 38.914605)
		(end -252.877 38.735)
		(width 0.11176)
		(layer "In5.Cu")
		(net "SAS_B1_TX5N")
	)
	(arc
		(start -252.877 31.10074)
		(mid -253.266473 29.142725)
		(end -254.3756 27.4828)
		(width 0.11176)
		(layer "In5.Cu")
		(net "SAS_B1_TX5N")
	)
	(arc
		(start -254.654477 24.241018)
		(mid -254.600275 24.174846)
		(end -254.608739 24.089728)
		(width 0.11176)
		(layer "In5.Cu")
		(net "SAS_B1_TX5N")
	)
	(arc
		(start -254.3756 27.4828)
		(mid -255.014758 26.526232)
		(end -255.2392 25.397884)
		(width 0.11176)
		(layer "In5.Cu")
		(net "SAS_B1_TX5N")
	)
	(arc
		(start -255.2392 25.2222)
		(mid -255.157937 24.813662)
		(end -254.926518 24.46732)
		(width 0.11176)
		(layer "In5.Cu")
		(net "SAS_B1_TX5N")
	)
	(arc
		(start -253.680001 38.460002)
		(mid -253.525061 38.834061)
		(end -253.151002 38.989)
		(width 0.11176)
		(layer "In5.Cu")
		(net "SAS_B1_TX5N")
	)
	(arc
		(start -254.800527 24.341328)
		(mid -254.750047 24.297763)
		(end -254.693738 24.26205)
		(width 0.11176)
		(layer "In5.Cu")
		(net "SAS_B1_TX5N")
	)
	(segment
		(start -245.742557 20.743278)
		(end -245.742554 20.743276)
		(width 0.11176)
		(layer "In5.Cu")
		(net "SAS_B1_TX4P")
	)
	(segment
		(start -245.742554 20.743278)
		(end -245.742557 20.743278)
		(width 0.11176)
		(layer "In5.Cu")
		(net "SAS_B1_TX4P")
	)
	(segment
		(start -250.42622 30.215426)
		(end -250.5275 30.114146)
		(width 0.11176)
		(layer "In5.Cu")
		(net "SAS_B1_TX4P")
	)
	(segment
		(start -251.68 36.96)
		(end -251.68 36.9157)
		(width 0.11176)
		(layer "In5.Cu")
		(net "SAS_B1_TX4P")
	)
	(segment
		(start -250.5275 30.784066)
		(end -250.42622 30.682786)
		(width 0.11176)
		(layer "In5.Cu")
		(net "SAS_B1_TX4P")
	)
	(segment
		(start -250.5275 35.7632)
		(end -250.5275 32.34404)
		(width 0.11176)
		(layer "In5.Cu")
		(net "SAS_B1_TX4P")
	)
	(segment
		(start -246.326645 21.302381)
		(end -245.808058 20.783796)
		(width 0.11176)
		(layer "In5.Cu")
		(net "SAS_B1_TX4P")
	)
	(segment
		(start -250.5275 31.51156)
		(end -250.5275 30.784066)
		(width 0.11176)
		(layer "In5.Cu")
		(net "SAS_B1_TX4P")
	)
	(segment
		(start -250.42622 30.682786)
		(end -250.42622 30.215426)
		(width 0.11176)
		(layer "In5.Cu")
		(net "SAS_B1_TX4P")
	)
	(segment
		(start -245.591264 20.789016)
		(end -245.350002 21.239371)
		(width 0.11176)
		(layer "In5.Cu")
		(net "SAS_B1_TX4P")
	)
	(segment
		(start -245.78181 20.76431)
		(end -245.742554 20.743278)
		(width 0.11176)
		(layer "In5.Cu")
		(net "SAS_B1_TX4P")
	)
	(segment
		(start -250.27096 32.0875)
		(end -250.27096 31.7681)
		(width 0.11176)
		(layer "In5.Cu")
		(net "SAS_B1_TX4P")
	)
	(segment
		(start -250.5275 30.114146)
		(end -250.5275 28.749523)
		(width 0.11176)
		(layer "In5.Cu")
		(net "SAS_B1_TX4P")
	)
	(segment
		(start -247.8986 22.402803)
		(end -247.131604 21.635806)
		(width 0.11176)
		(layer "In5.Cu")
		(net "SAS_B1_TX4P")
	)
	(arc
		(start -245.808058 20.783796)
		(mid -245.79565 20.773088)
		(end -245.78181 20.76431)
		(width 0.11176)
		(layer "In5.Cu")
		(net "SAS_B1_TX4P")
	)
	(arc
		(start -251.68 36.9157)
		(mid -251.539587 36.576713)
		(end -251.2006 36.4363)
		(width 0.11176)
		(layer "In5.Cu")
		(net "SAS_B1_TX4P")
	)
	(arc
		(start -246.806397 21.5011)
		(mid -246.546758 21.449454)
		(end -246.326645 21.302381)
		(width 0.11176)
		(layer "In5.Cu")
		(net "SAS_B1_TX4P")
	)
	(arc
		(start -247.131604 21.635806)
		(mid -246.982398 21.536109)
		(end -246.806397 21.5011)
		(width 0.11176)
		(layer "In5.Cu")
		(net "SAS_B1_TX4P")
	)
	(arc
		(start -250.5275 32.34404)
		(mid -250.503043 32.284997)
		(end -250.444 32.26054)
		(width 0.11176)
		(layer "In5.Cu")
		(net "SAS_B1_TX4P")
	)
	(arc
		(start -251.2006 36.4363)
		(mid -250.724646 36.239154)
		(end -250.5275 35.7632)
		(width 0.11176)
		(layer "In5.Cu")
		(net "SAS_B1_TX4P")
	)
	(arc
		(start -250.5275 28.749523)
		(mid -249.844271 25.314703)
		(end -247.8986 22.402803)
		(width 0.11176)
		(layer "In5.Cu")
		(net "SAS_B1_TX4P")
	)
	(arc
		(start -250.444 32.26054)
		(mid -250.321642 32.209858)
		(end -250.27096 32.0875)
		(width 0.11176)
		(layer "In5.Cu")
		(net "SAS_B1_TX4P")
	)
	(arc
		(start -250.27096 31.7681)
		(mid -250.317922 31.654722)
		(end -250.4313 31.60776)
		(width 0.11176)
		(layer "In5.Cu")
		(net "SAS_B1_TX4P")
	)
	(arc
		(start -250.4313 31.60776)
		(mid -250.499324 31.579584)
		(end -250.5275 31.51156)
		(width 0.11176)
		(layer "In5.Cu")
		(net "SAS_B1_TX4P")
	)
	(arc
		(start -245.742554 20.743276)
		(mid -245.657436 20.734812)
		(end -245.591264 20.789016)
		(width 0.11176)
		(layer "In5.Cu")
		(net "SAS_B1_TX4P")
	)
	(segment
		(start -245.858739 20.289728)
		(end -246.100001 19.839371)
		(width 0.11176)
		(layer "In5.Cu")
		(net "SAS_B1_TX4N")
	)
	(segment
		(start -245.904479 20.441018)
		(end -245.904476 20.441018)
		(width 0.11176)
		(layer "In5.Cu")
		(net "SAS_B1_TX4N")
	)
	(segment
		(start -248.141068 22.160334)
		(end -247.374072 21.393338)
		(width 0.11176)
		(layer "In5.Cu")
		(net "SAS_B1_TX4N")
	)
	(segment
		(start -250.8704 35.7632)
		(end -250.8704 28.749523)
		(width 0.11176)
		(layer "In5.Cu")
		(net "SAS_B1_TX4N")
	)
	(segment
		(start -245.943737 20.46205)
		(end -245.904479 20.441018)
		(width 0.11176)
		(layer "In5.Cu")
		(net "SAS_B1_TX4N")
	)
	(segment
		(start -246.569111 21.059912)
		(end -246.050526 20.541328)
		(width 0.11176)
		(layer "In5.Cu")
		(net "SAS_B1_TX4N")
	)
	(segment
		(start -251.68 35.56)
		(end -251.68 35.614)
		(width 0.11176)
		(layer "In5.Cu")
		(net "SAS_B1_TX4N")
	)
	(arc
		(start -250.8704 28.749523)
		(mid -250.16107 25.183479)
		(end -248.141068 22.160334)
		(width 0.11176)
		(layer "In5.Cu")
		(net "SAS_B1_TX4N")
	)
	(arc
		(start -251.68 35.614)
		(mid -251.539587 35.952987)
		(end -251.2006 36.0934)
		(width 0.11176)
		(layer "In5.Cu")
		(net "SAS_B1_TX4N")
	)
	(arc
		(start -247.374072 21.393338)
		(mid -247.113622 21.219309)
		(end -246.8064 21.158197)
		(width 0.11176)
		(layer "In5.Cu")
		(net "SAS_B1_TX4N")
	)
	(arc
		(start -246.8064 21.158197)
		(mid -246.67798 21.132654)
		(end -246.569111 21.059912)
		(width 0.11176)
		(layer "In5.Cu")
		(net "SAS_B1_TX4N")
	)
	(arc
		(start -251.2006 36.0934)
		(mid -250.967113 35.996687)
		(end -250.8704 35.7632)
		(width 0.11176)
		(layer "In5.Cu")
		(net "SAS_B1_TX4N")
	)
	(arc
		(start -245.904476 20.441018)
		(mid -245.850274 20.374845)
		(end -245.858739 20.289728)
		(width 0.11176)
		(layer "In5.Cu")
		(net "SAS_B1_TX4N")
	)
	(arc
		(start -246.050526 20.541328)
		(mid -246.000046 20.497763)
		(end -245.943737 20.46205)
		(width 0.11176)
		(layer "In5.Cu")
		(net "SAS_B1_TX4N")
	)
	(segment
		(start -248.5082 31.461979)
		(end -248.5082 26.469284)
		(width 0.11176)
		(layer "In5.Cu")
		(net "SAS_B1_TX3P")
	)
	(segment
		(start -247.390603 25.4508)
		(end -247.2944 25.4508)
		(width 0.11176)
		(layer "In5.Cu")
		(net "SAS_B1_TX3P")
	)
	(segment
		(start -245.742557 24.543276)
		(end -245.742554 24.543273)
		(width 0.11176)
		(layer "In5.Cu")
		(net "SAS_B1_TX3P")
	)
	(segment
		(start -245.591264 24.589014)
		(end -245.350002 25.039371)
		(width 0.11176)
		(layer "In5.Cu")
		(net "SAS_B1_TX3P")
	)
	(segment
		(start -248.5082 31.9405)
		(end -248.44502 31.87732)
		(width 0.11176)
		(layer "In5.Cu")
		(net "SAS_B1_TX3P")
	)
	(segment
		(start -248.5082 32.63932)
		(end -248.5082 31.9405)
		(width 0.11176)
		(layer "In5.Cu")
		(net "SAS_B1_TX3P")
	)
	(segment
		(start -248.251177 25.84878)
		(end -248.180306 25.777909)
		(width 0.11176)
		(layer "In5.Cu")
		(net "SAS_B1_TX3P")
	)
	(segment
		(start -245.826504 24.588249)
		(end -245.742557 24.543276)
		(width 0.11176)
		(layer "In5.Cu")
		(net "SAS_B1_TX3P")
	)
	(segment
		(start -248.44502 31.87732)
		(end -248.44502 31.525159)
		(width 0.11176)
		(layer "In5.Cu")
		(net "SAS_B1_TX3P")
	)
	(segment
		(start -246.272558 25.027539)
		(end -245.852754 24.607736)
		(width 0.11176)
		(layer "In5.Cu")
		(net "SAS_B1_TX3P")
	)
	(segment
		(start -249.321 39.3446)
		(end -249.1432 39.3446)
		(width 0.11176)
		(layer "In5.Cu")
		(net "SAS_B1_TX3P")
	)
	(segment
		(start -248.5082 38.7096)
		(end -248.5082 33.43116)
		(width 0.11176)
		(layer "In5.Cu")
		(net "SAS_B1_TX3P")
	)
	(segment
		(start -248.27706 33.20002)
		(end -248.27706 32.87046)
		(width 0.11176)
		(layer "In5.Cu")
		(net "SAS_B1_TX3P")
	)
	(segment
		(start -249.680001 39.860002)
		(end -249.680001 39.703601)
		(width 0.11176)
		(layer "In5.Cu")
		(net "SAS_B1_TX3P")
	)
	(segment
		(start -248.44502 31.525159)
		(end -248.5082 31.461979)
		(width 0.11176)
		(layer "In5.Cu")
		(net "SAS_B1_TX3P")
	)
	(arc
		(start -245.742554 24.543273)
		(mid -245.657436 24.534811)
		(end -245.591264 24.589014)
		(width 0.11176)
		(layer "In5.Cu")
		(net "SAS_B1_TX3P")
	)
	(arc
		(start -248.412 33.33496)
		(mid -248.316583 33.295437)
		(end -248.27706 33.20002)
		(width 0.11176)
		(layer "In5.Cu")
		(net "SAS_B1_TX3P")
	)
	(arc
		(start -249.1432 39.3446)
		(mid -248.694187 39.158613)
		(end -248.5082 38.7096)
		(width 0.11176)
		(layer "In5.Cu")
		(net "SAS_B1_TX3P")
	)
	(arc
		(start -249.680001 39.703601)
		(mid -249.574852 39.449749)
		(end -249.321 39.3446)
		(width 0.11176)
		(layer "In5.Cu")
		(net "SAS_B1_TX3P")
	)
	(arc
		(start -248.27706 32.87046)
		(mid -248.313607 32.782227)
		(end -248.40184 32.74568)
		(width 0.11176)
		(layer "In5.Cu")
		(net "SAS_B1_TX3P")
	)
	(arc
		(start -248.180306 25.777909)
		(mid -247.817987 25.535814)
		(end -247.390603 25.4508)
		(width 0.11176)
		(layer "In5.Cu")
		(net "SAS_B1_TX3P")
	)
	(arc
		(start -245.852754 24.607736)
		(mid -245.840345 24.597028)
		(end -245.826504 24.588249)
		(width 0.11176)
		(layer "In5.Cu")
		(net "SAS_B1_TX3P")
	)
	(arc
		(start -247.2944 25.4508)
		(mid -246.741383 25.340798)
		(end -246.272558 25.027539)
		(width 0.11176)
		(layer "In5.Cu")
		(net "SAS_B1_TX3P")
	)
	(arc
		(start -248.5082 33.43116)
		(mid -248.480024 33.363136)
		(end -248.412 33.33496)
		(width 0.11176)
		(layer "In5.Cu")
		(net "SAS_B1_TX3P")
	)
	(arc
		(start -248.5082 26.469284)
		(mid -248.441401 26.13347)
		(end -248.251177 25.84878)
		(width 0.11176)
		(layer "In5.Cu")
		(net "SAS_B1_TX3P")
	)
	(arc
		(start -248.40184 32.74568)
		(mid -248.477048 32.714528)
		(end -248.5082 32.63932)
		(width 0.11176)
		(layer "In5.Cu")
		(net "SAS_B1_TX3P")
	)
	(segment
		(start -247.3906 25.1079)
		(end -247.294397 25.1079)
		(width 0.11176)
		(layer "In5.Cu")
		(net "SAS_B1_TX3N")
	)
	(segment
		(start -248.8511 38.7096)
		(end -248.8511 26.469282)
		(width 0.11176)
		(layer "In5.Cu")
		(net "SAS_B1_TX3N")
	)
	(segment
		(start -249.680001 38.460002)
		(end -249.680001 38.642699)
		(width 0.11176)
		(layer "In5.Cu")
		(net "SAS_B1_TX3N")
	)
	(segment
		(start -245.988429 24.285989)
		(end -245.958731 24.270078)
		(width 0.11176)
		(layer "In5.Cu")
		(net "SAS_B1_TX3N")
	)
	(segment
		(start -248.493646 25.606312)
		(end -248.422775 25.53544)
		(width 0.11176)
		(layer "In5.Cu")
		(net "SAS_B1_TX3N")
	)
	(segment
		(start -245.858739 24.089726)
		(end -246.100001 23.639371)
		(width 0.11176)
		(layer "In5.Cu")
		(net "SAS_B1_TX3N")
	)
	(segment
		(start -249.321 39.0017)
		(end -249.1432 39.0017)
		(width 0.11176)
		(layer "In5.Cu")
		(net "SAS_B1_TX3N")
	)
	(segment
		(start -245.958731 24.270078)
		(end -245.904479 24.241016)
		(width 0.11176)
		(layer "In5.Cu")
		(net "SAS_B1_TX3N")
	)
	(segment
		(start -246.515026 24.785071)
		(end -246.09522 24.365265)
		(width 0.11176)
		(layer "In5.Cu")
		(net "SAS_B1_TX3N")
	)
	(segment
		(start -245.904479 24.241016)
		(end -245.904476 24.241016)
		(width 0.11176)
		(layer "In5.Cu")
		(net "SAS_B1_TX3N")
	)
	(arc
		(start -247.294397 25.1079)
		(mid -246.872604 25.023998)
		(end -246.515026 24.785071)
		(width 0.11176)
		(layer "In5.Cu")
		(net "SAS_B1_TX3N")
	)
	(arc
		(start -245.904476 24.241016)
		(mid -245.850274 24.174843)
		(end -245.858739 24.089726)
		(width 0.11176)
		(layer "In5.Cu")
		(net "SAS_B1_TX3N")
	)
	(arc
		(start -249.680001 38.642699)
		(mid -249.574852 38.896551)
		(end -249.321 39.0017)
		(width 0.11176)
		(layer "In5.Cu")
		(net "SAS_B1_TX3N")
	)
	(arc
		(start -249.1432 39.0017)
		(mid -248.936654 38.916146)
		(end -248.8511 38.7096)
		(width 0.11176)
		(layer "In5.Cu")
		(net "SAS_B1_TX3N")
	)
	(arc
		(start -248.422775 25.53544)
		(mid -247.949209 25.219013)
		(end -247.3906 25.1079)
		(width 0.11176)
		(layer "In5.Cu")
		(net "SAS_B1_TX3N")
	)
	(arc
		(start -248.8511 26.469282)
		(mid -248.7582 26.002246)
		(end -248.493646 25.606312)
		(width 0.11176)
		(layer "In5.Cu")
		(net "SAS_B1_TX3N")
	)
	(arc
		(start -246.09522 24.365265)
		(mid -246.044739 24.321701)
		(end -245.988429 24.285989)
		(width 0.11176)
		(layer "In5.Cu")
		(net "SAS_B1_TX3N")
	)
	(segment
		(start -240.633113 22.891885)
		(end -240.162415 23.362582)
		(width 0.10668)
		(layer "B.Cu")
		(net "SAS_B1_TX2P")
	)
	(segment
		(start -243.466488 20.78118)
		(end -243.466501 20.781188)
		(width 0.10668)
		(layer "B.Cu")
		(net "SAS_B1_TX2P")
	)
	(segment
		(start -241.660243 31.612294)
		(end -244.524878 34.476931)
		(width 0.10668)
		(layer "B.Cu")
		(net "SAS_B1_TX2P")
	)
	(segment
		(start -243.100001 21.239371)
		(end -243.322074 20.824838)
		(width 0.10668)
		(layer "B.Cu")
		(net "SAS_B1_TX2P")
	)
	(segment
		(start -243.466501 20.781188)
		(end -243.54662 20.824106)
		(width 0.10668)
		(layer "B.Cu")
		(net "SAS_B1_TX2P")
	)
	(segment
		(start -239.6236 24.6634)
		(end -239.6236 26.6954)
		(width 0.10668)
		(layer "B.Cu")
		(net "SAS_B1_TX2P")
	)
	(segment
		(start -244.81583 35.01183)
		(end -245.059777 35.01183)
		(width 0.10668)
		(layer "B.Cu")
		(net "SAS_B1_TX2P")
	)
	(segment
		(start -245.059777 35.01183)
		(end -245.350734 35.302787)
		(width 0.10668)
		(layer "B.Cu")
		(net "SAS_B1_TX2P")
	)
	(segment
		(start -245.885637 35.837691)
		(end -246.321473 36.273527)
		(width 0.10668)
		(layer "B.Cu")
		(net "SAS_B1_TX2P")
	)
	(segment
		(start -245.350734 35.302787)
		(end -245.350734 35.597534)
		(width 0.10668)
		(layer "B.Cu")
		(net "SAS_B1_TX2P")
	)
	(segment
		(start -243.571677 20.842709)
		(end -243.587537 20.858569)
		(width 0.10668)
		(layer "B.Cu")
		(net "SAS_B1_TX2P")
	)
	(segment
		(start -244.524873 34.720873)
		(end -244.81583 35.01183)
		(width 0.10668)
		(layer "B.Cu")
		(net "SAS_B1_TX2P")
	)
	(segment
		(start -245.350734 35.597534)
		(end -245.590891 35.837691)
		(width 0.10668)
		(layer "B.Cu")
		(net "SAS_B1_TX2P")
	)
	(segment
		(start -244.524873 34.598902)
		(end -244.524873 34.720873)
		(width 0.10668)
		(layer "B.Cu")
		(net "SAS_B1_TX2P")
	)
	(segment
		(start -246.812559 36.47694)
		(end -247.19694 36.47694)
		(width 0.10668)
		(layer "B.Cu")
		(net "SAS_B1_TX2P")
	)
	(segment
		(start -244.524878 34.476931)
		(end -244.524873 34.598902)
		(width 0.10668)
		(layer "B.Cu")
		(net "SAS_B1_TX2P")
	)
	(segment
		(start -243.466485 20.78118)
		(end -243.466488 20.78118)
		(width 0.10668)
		(layer "B.Cu")
		(net "SAS_B1_TX2P")
	)
	(segment
		(start -245.590891 35.837691)
		(end -245.885637 35.837691)
		(width 0.10668)
		(layer "B.Cu")
		(net "SAS_B1_TX2P")
	)
	(segment
		(start -243.259155 22.1234)
		(end -242.4884 22.1234)
		(width 0.10668)
		(layer "B.Cu")
		(net "SAS_B1_TX2P")
	)
	(arc
		(start -246.321473 36.273527)
		(mid -246.546785 36.424075)
		(end -246.812559 36.47694)
		(width 0.10668)
		(layer "B.Cu")
		(net "SAS_B1_TX2P")
	)
	(arc
		(start -243.54662 20.824106)
		(mid -243.559832 20.832486)
		(end -243.571677 20.842709)
		(width 0.10668)
		(layer "B.Cu")
		(net "SAS_B1_TX2P")
	)
	(arc
		(start -243.587537 20.858569)
		(mid -243.800741 21.12544)
		(end -243.949751 21.432804)
		(width 0.10668)
		(layer "B.Cu")
		(net "SAS_B1_TX2P")
	)
	(arc
		(start -240.162415 23.362582)
		(mid -239.763633 23.959403)
		(end -239.6236 24.6634)
		(width 0.10668)
		(layer "B.Cu")
		(net "SAS_B1_TX2P")
	)
	(arc
		(start -239.6236 26.6954)
		(mid -240.152906 29.356404)
		(end -241.660243 31.612294)
		(width 0.10668)
		(layer "B.Cu")
		(net "SAS_B1_TX2P")
	)
	(arc
		(start -242.4884 22.1234)
		(mid -241.484326 22.323123)
		(end -240.633113 22.891885)
		(width 0.10668)
		(layer "B.Cu")
		(net "SAS_B1_TX2P")
	)
	(arc
		(start -243.949751 21.432804)
		(mid -243.74748 21.921129)
		(end -243.259155 22.1234)
		(width 0.10668)
		(layer "B.Cu")
		(net "SAS_B1_TX2P")
	)
	(arc
		(start -247.19694 36.47694)
		(mid -247.538515 36.618425)
		(end -247.68 36.96)
		(width 0.10668)
		(layer "B.Cu")
		(net "SAS_B1_TX2P")
	)
	(arc
		(start -243.322074 20.824838)
		(mid -243.385238 20.7731)
		(end -243.466485 20.78118)
		(width 0.10668)
		(layer "B.Cu")
		(net "SAS_B1_TX2P")
	)
	(segment
		(start -247.1974 36.0426)
		(end -246.812562 36.0426)
		(width 0.10668)
		(layer "B.Cu")
		(net "SAS_B1_TX2N")
	)
	(segment
		(start -243.894663 20.551442)
		(end -243.878806 20.535585)
		(width 0.10668)
		(layer "B.Cu")
		(net "SAS_B1_TX2N")
	)
	(segment
		(start -243.714311 20.421199)
		(end -243.671593 20.398316)
		(width 0.10668)
		(layer "B.Cu")
		(net "SAS_B1_TX2N")
	)
	(segment
		(start -243.751725 20.441242)
		(end -243.714311 20.421199)
		(width 0.10668)
		(layer "B.Cu")
		(net "SAS_B1_TX2N")
	)
	(segment
		(start -240.05794 26.6954)
		(end -240.05794 24.663397)
		(width 0.10668)
		(layer "B.Cu")
		(net "SAS_B1_TX2N")
	)
	(segment
		(start -243.671593 20.398316)
		(end -243.67159 20.398313)
		(width 0.10668)
		(layer "B.Cu")
		(net "SAS_B1_TX2N")
	)
	(segment
		(start -246.332502 35.6703)
		(end -241.96737 31.305167)
		(width 0.10668)
		(layer "B.Cu")
		(net "SAS_B1_TX2N")
	)
	(segment
		(start -242.488403 22.55774)
		(end -243.259155 22.55774)
		(width 0.10668)
		(layer "B.Cu")
		(net "SAS_B1_TX2N")
	)
	(segment
		(start -240.469542 23.669709)
		(end -240.940239 23.199011)
		(width 0.10668)
		(layer "B.Cu")
		(net "SAS_B1_TX2N")
	)
	(segment
		(start -243.62793 20.253902)
		(end -243.85 19.839371)
		(width 0.10668)
		(layer "B.Cu")
		(net "SAS_B1_TX2N")
	)
	(segment
		(start -246.455121 35.792921)
		(end -246.332502 35.6703)
		(width 0.10668)
		(layer "B.Cu")
		(net "SAS_B1_TX2N")
	)
	(segment
		(start -246.6286 35.9664)
		(end -246.455121 35.792921)
		(width 0.10668)
		(layer "B.Cu")
		(net "SAS_B1_TX2N")
	)
	(arc
		(start -240.940239 23.199011)
		(mid -241.650543 22.7244)
		(end -242.488403 22.55774)
		(width 0.10668)
		(layer "B.Cu")
		(net "SAS_B1_TX2N")
	)
	(arc
		(start -243.67159 20.398313)
		(mid -243.619851 20.33515)
		(end -243.62793 20.253902)
		(width 0.10668)
		(layer "B.Cu")
		(net "SAS_B1_TX2N")
	)
	(arc
		(start -246.812562 36.0426)
		(mid -246.713002 36.022796)
		(end -246.6286 35.9664)
		(width 0.10668)
		(layer "B.Cu")
		(net "SAS_B1_TX2N")
	)
	(arc
		(start -243.878806 20.535585)
		(mid -243.818734 20.483741)
		(end -243.751725 20.441242)
		(width 0.10668)
		(layer "B.Cu")
		(net "SAS_B1_TX2N")
	)
	(arc
		(start -240.05794 24.663397)
		(mid -240.164868 24.125728)
		(end -240.469374 23.669879)
		(width 0.10668)
		(layer "B.Cu")
		(net "SAS_B1_TX2N")
	)
	(arc
		(start -241.96737 31.305167)
		(mid -240.554186 29.190188)
		(end -240.05794 26.6954)
		(width 0.10668)
		(layer "B.Cu")
		(net "SAS_B1_TX2N")
	)
	(arc
		(start -244.38134 21.354156)
		(mid -244.186471 20.923412)
		(end -243.894663 20.551442)
		(width 0.10668)
		(layer "B.Cu")
		(net "SAS_B1_TX2N")
	)
	(arc
		(start -240.469374 23.669879)
		(mid -240.469458 23.669794)
		(end -240.469542 23.669709)
		(width 0.10668)
		(layer "B.Cu")
		(net "SAS_B1_TX2N")
	)
	(arc
		(start -243.259155 22.55774)
		(mid -244.081942 22.199944)
		(end -244.38134 21.354156)
		(width 0.10668)
		(layer "B.Cu")
		(net "SAS_B1_TX2N")
	)
	(arc
		(start -247.68 35.56)
		(mid -247.53865 35.90125)
		(end -247.1974 36.0426)
		(width 0.10668)
		(layer "B.Cu")
		(net "SAS_B1_TX2N")
	)
	(segment
		(start -244.4823 40.2717)
		(end -244.4823 39.392299)
		(width 0.11176)
		(layer "In5.Cu")
		(net "SAS_B1_TX1P")
	)
	(segment
		(start -243.341263 24.589014)
		(end -243.100001 25.039371)
		(width 0.11176)
		(layer "In5.Cu")
		(net "SAS_B1_TX1P")
	)
	(segment
		(start -247.2128 44.831452)
		(end -246.780997 44.831452)
		(width 0.11176)
		(layer "In5.Cu")
		(net "SAS_B1_TX1P")
	)
	(segment
		(start -244.2918 39.201799)
		(end -244.2918 38.886839)
		(width 0.11176)
		(layer "In5.Cu")
		(net "SAS_B1_TX1P")
	)
	(segment
		(start -245.216812 44.183544)
		(end -244.836732 43.803468)
		(width 0.11176)
		(layer "In5.Cu")
		(net "SAS_B1_TX1P")
	)
	(segment
		(start -244.25624 40.88384)
		(end -244.25624 40.49776)
		(width 0.11176)
		(layer "In5.Cu")
		(net "SAS_B1_TX1P")
	)
	(segment
		(start -244.4823 42.947793)
		(end -244.4823 42.6847)
		(width 0.11176)
		(layer "In5.Cu")
		(net "SAS_B1_TX1P")
	)
	(segment
		(start -244.2918 38.886839)
		(end -244.4823 38.696339)
		(width 0.11176)
		(layer "In5.Cu")
		(net "SAS_B1_TX1P")
	)
	(segment
		(start -243.576503 24.588249)
		(end -243.492556 24.543276)
		(width 0.11176)
		(layer "In5.Cu")
		(net "SAS_B1_TX1P")
	)
	(segment
		(start -244.368 42.037)
		(end -244.37054 42.037)
		(width 0.11176)
		(layer "In5.Cu")
		(net "SAS_B1_TX1P")
	)
	(segment
		(start -244.25624 42.45864)
		(end -244.25624 42.14876)
		(width 0.11176)
		(layer "In5.Cu")
		(net "SAS_B1_TX1P")
	)
	(segment
		(start -244.022557 25.027539)
		(end -243.602754 24.607736)
		(width 0.11176)
		(layer "In5.Cu")
		(net "SAS_B1_TX1P")
	)
	(segment
		(start -244.4823 41.92524)
		(end -244.4823 41.1099)
		(width 0.11176)
		(layer "In5.Cu")
		(net "SAS_B1_TX1P")
	)
	(segment
		(start -244.4823 39.392299)
		(end -244.2918 39.201799)
		(width 0.11176)
		(layer "In5.Cu")
		(net "SAS_B1_TX1P")
	)
	(segment
		(start -243.492556 24.543276)
		(end -243.492553 24.543273)
		(width 0.11176)
		(layer "In5.Cu")
		(net "SAS_B1_TX1P")
	)
	(segment
		(start -244.4823 38.696339)
		(end -244.4823 26.137453)
		(width 0.11176)
		(layer "In5.Cu")
		(net "SAS_B1_TX1P")
	)
	(segment
		(start -247.68 45.360001)
		(end -247.68 45.298652)
		(width 0.11176)
		(layer "In5.Cu")
		(net "SAS_B1_TX1P")
	)
	(arc
		(start -244.4823 26.137453)
		(mid -244.362817 25.536771)
		(end -244.022557 25.027539)
		(width 0.11176)
		(layer "In5.Cu")
		(net "SAS_B1_TX1P")
	)
	(arc
		(start -246.780997 44.831452)
		(mid -245.934467 44.663065)
		(end -245.216812 44.183544)
		(width 0.11176)
		(layer "In5.Cu")
		(net "SAS_B1_TX1P")
	)
	(arc
		(start -243.602754 24.607736)
		(mid -243.590345 24.597027)
		(end -243.576503 24.588249)
		(width 0.11176)
		(layer "In5.Cu")
		(net "SAS_B1_TX1P")
	)
	(arc
		(start -244.3934 42.5958)
		(mid -244.296413 42.555627)
		(end -244.25624 42.45864)
		(width 0.11176)
		(layer "In5.Cu")
		(net "SAS_B1_TX1P")
	)
	(arc
		(start -244.368 40.9956)
		(mid -244.288974 40.962866)
		(end -244.25624 40.88384)
		(width 0.11176)
		(layer "In5.Cu")
		(net "SAS_B1_TX1P")
	)
	(arc
		(start -244.25624 40.49776)
		(mid -244.296413 40.400773)
		(end -244.3934 40.3606)
		(width 0.11176)
		(layer "In5.Cu")
		(net "SAS_B1_TX1P")
	)
	(arc
		(start -244.836732 43.803468)
		(mid -244.574414 43.410881)
		(end -244.4823 42.947793)
		(width 0.11176)
		(layer "In5.Cu")
		(net "SAS_B1_TX1P")
	)
	(arc
		(start -243.492553 24.543273)
		(mid -243.407435 24.534811)
		(end -243.341263 24.589014)
		(width 0.11176)
		(layer "In5.Cu")
		(net "SAS_B1_TX1P")
	)
	(arc
		(start -244.4823 41.1099)
		(mid -244.448822 41.029078)
		(end -244.368 40.9956)
		(width 0.11176)
		(layer "In5.Cu")
		(net "SAS_B1_TX1P")
	)
	(arc
		(start -244.3934 40.3606)
		(mid -244.456262 40.334562)
		(end -244.4823 40.2717)
		(width 0.11176)
		(layer "In5.Cu")
		(net "SAS_B1_TX1P")
	)
	(arc
		(start -244.25624 42.14876)
		(mid -244.288974 42.069734)
		(end -244.368 42.037)
		(width 0.11176)
		(layer "In5.Cu")
		(net "SAS_B1_TX1P")
	)
	(arc
		(start -247.68 45.298652)
		(mid -247.54316 44.968292)
		(end -247.2128 44.831452)
		(width 0.11176)
		(layer "In5.Cu")
		(net "SAS_B1_TX1P")
	)
	(arc
		(start -244.37054 42.037)
		(mid -244.449566 42.004266)
		(end -244.4823 41.92524)
		(width 0.11176)
		(layer "In5.Cu")
		(net "SAS_B1_TX1P")
	)
	(arc
		(start -244.4823 42.6847)
		(mid -244.456262 42.621838)
		(end -244.3934 42.5958)
		(width 0.11176)
		(layer "In5.Cu")
		(net "SAS_B1_TX1P")
	)
	(segment
		(start -247.68 44.021352)
		(end -247.68 43.960001)
		(width 0.11176)
		(layer "In5.Cu")
		(net "SAS_B1_TX1N")
	)
	(segment
		(start -243.654478 24.241016)
		(end -243.70873 24.270078)
		(width 0.11176)
		(layer "In5.Cu")
		(net "SAS_B1_TX1N")
	)
	(segment
		(start -245.0792 43.561)
		(end -245.459278 43.941075)
		(width 0.11176)
		(layer "In5.Cu")
		(net "SAS_B1_TX1N")
	)
	(segment
		(start -246.781 44.488552)
		(end -247.2128 44.488552)
		(width 0.11176)
		(layer "In5.Cu")
		(net "SAS_B1_TX1N")
	)
	(segment
		(start -244.8252 26.137451)
		(end -244.8252 42.947791)
		(width 0.11176)
		(layer "In5.Cu")
		(net "SAS_B1_TX1N")
	)
	(segment
		(start -243.654476 24.241016)
		(end -243.654478 24.241016)
		(width 0.11176)
		(layer "In5.Cu")
		(net "SAS_B1_TX1N")
	)
	(segment
		(start -243.70873 24.270078)
		(end -243.738428 24.285989)
		(width 0.11176)
		(layer "In5.Cu")
		(net "SAS_B1_TX1N")
	)
	(segment
		(start -243.84522 24.365265)
		(end -244.265026 24.785071)
		(width 0.11176)
		(layer "In5.Cu")
		(net "SAS_B1_TX1N")
	)
	(segment
		(start -243.85 23.639371)
		(end -243.608738 24.089726)
		(width 0.11176)
		(layer "In5.Cu")
		(net "SAS_B1_TX1N")
	)
	(arc
		(start -244.265026 24.785071)
		(mid -244.679616 25.405548)
		(end -244.8252 26.137451)
		(width 0.11176)
		(layer "In5.Cu")
		(net "SAS_B1_TX1N")
	)
	(arc
		(start -243.608738 24.089726)
		(mid -243.600274 24.174844)
		(end -243.654476 24.241016)
		(width 0.11176)
		(layer "In5.Cu")
		(net "SAS_B1_TX1N")
	)
	(arc
		(start -245.459278 43.941075)
		(mid -246.065689 44.346267)
		(end -246.781 44.488552)
		(width 0.11176)
		(layer "In5.Cu")
		(net "SAS_B1_TX1N")
	)
	(arc
		(start -247.2128 44.488552)
		(mid -247.54316 44.351712)
		(end -247.68 44.021352)
		(width 0.11176)
		(layer "In5.Cu")
		(net "SAS_B1_TX1N")
	)
	(arc
		(start -243.738428 24.285989)
		(mid -243.794738 24.321701)
		(end -243.84522 24.365265)
		(width 0.11176)
		(layer "In5.Cu")
		(net "SAS_B1_TX1N")
	)
	(arc
		(start -244.8252 42.947791)
		(mid -244.891212 43.279658)
		(end -245.0792 43.561)
		(width 0.11176)
		(layer "In5.Cu")
		(net "SAS_B1_TX1N")
	)
	(segment
		(start -256.520828 13.024498)
		(end -256.520838 13.024503)
		(width 0.11176)
		(layer "In5.Cu")
		(net "SAS_B1_RX8P")
	)
	(segment
		(start -261.8359 41.91)
		(end -261.8359 18.761443)
		(width 0.11176)
		(layer "In5.Cu")
		(net "SAS_B1_RX8P")
	)
	(segment
		(start -256.520838 13.024503)
		(end -256.545522 13.037726)
		(width 0.11176)
		(layer "In5.Cu")
		(net "SAS_B1_RX8P")
	)
	(segment
		(start -258.191 43.5229)
		(end -260.223 43.5229)
		(width 0.11176)
		(layer "In5.Cu")
		(net "SAS_B1_RX8P")
	)
	(segment
		(start -256.591262 13.189016)
		(end -256.35 13.639371)
		(width 0.11176)
		(layer "In5.Cu")
		(net "SAS_B1_RX8P")
	)
	(segment
		(start -257.68 44.060001)
		(end -257.68 44.0339)
		(width 0.11176)
		(layer "In5.Cu")
		(net "SAS_B1_RX8P")
	)
	(segment
		(start -256.179 11.3157)
		(end -255.945312 11.549388)
		(width 0.11176)
		(layer "In5.Cu")
		(net "SAS_B1_RX8P")
	)
	(segment
		(start -258.539376 11.756039)
		(end -258.242633 11.459296)
		(width 0.11176)
		(layer "In5.Cu")
		(net "SAS_B1_RX8P")
	)
	(segment
		(start -259.0419 13.081003)
		(end -259.0419 12.969245)
		(width 0.11176)
		(layer "In5.Cu")
		(net "SAS_B1_RX8P")
	)
	(segment
		(start -260.592468 15.759532)
		(end -259.839493 15.006559)
		(width 0.11176)
		(layer "In5.Cu")
		(net "SAS_B1_RX8P")
	)
	(segment
		(start -255.945312 12.47649)
		(end -256.414041 12.945219)
		(width 0.11176)
		(layer "In5.Cu")
		(net "SAS_B1_RX8P")
	)
	(segment
		(start -256.545522 13.037726)
		(end -256.545525 13.037726)
		(width 0.11176)
		(layer "In5.Cu")
		(net "SAS_B1_RX8P")
	)
	(arc
		(start -258.242633 11.459296)
		(mid -257.689712 11.089835)
		(end -257.037492 10.960097)
		(width 0.11176)
		(layer "In5.Cu")
		(net "SAS_B1_RX8P")
	)
	(arc
		(start -255.945312 11.549388)
		(mid -255.753303 12.012939)
		(end -255.945312 12.47649)
		(width 0.11176)
		(layer "In5.Cu")
		(net "SAS_B1_RX8P")
	)
	(arc
		(start -259.0419 12.969245)
		(mid -258.911299 12.312663)
		(end -258.539376 11.756039)
		(width 0.11176)
		(layer "In5.Cu")
		(net "SAS_B1_RX8P")
	)
	(arc
		(start -257.037492 10.960097)
		(mid -256.572879 11.052516)
		(end -256.179 11.3157)
		(width 0.11176)
		(layer "In5.Cu")
		(net "SAS_B1_RX8P")
	)
	(arc
		(start -259.839493 15.006559)
		(mid -259.249188 14.123106)
		(end -259.0419 13.081003)
		(width 0.11176)
		(layer "In5.Cu")
		(net "SAS_B1_RX8P")
	)
	(arc
		(start -256.414041 12.945219)
		(mid -256.46452 12.988784)
		(end -256.520828 13.024498)
		(width 0.11176)
		(layer "In5.Cu")
		(net "SAS_B1_RX8P")
	)
	(arc
		(start -261.8359 18.761443)
		(mid -261.512743 17.13682)
		(end -260.592468 15.759532)
		(width 0.11176)
		(layer "In5.Cu")
		(net "SAS_B1_RX8P")
	)
	(arc
		(start -256.545525 13.037726)
		(mid -256.599727 13.103899)
		(end -256.591262 13.189016)
		(width 0.11176)
		(layer "In5.Cu")
		(net "SAS_B1_RX8P")
	)
	(arc
		(start -257.68 44.0339)
		(mid -257.829668 43.672568)
		(end -258.191 43.5229)
		(width 0.11176)
		(layer "In5.Cu")
		(net "SAS_B1_RX8P")
	)
	(arc
		(start -260.223 43.5229)
		(mid -261.363493 43.050493)
		(end -261.8359 41.91)
		(width 0.11176)
		(layer "In5.Cu")
		(net "SAS_B1_RX8P")
	)
	(segment
		(start -259.51688 43.13936)
		(end -259.55752 43.18)
		(width 0.11176)
		(layer "In5.Cu")
		(net "SAS_B1_RX8N")
	)
	(segment
		(start -261.493 34.90468)
		(end -261.493 18.761446)
		(width 0.11176)
		(layer "In5.Cu")
		(net "SAS_B1_RX8N")
	)
	(segment
		(start -259.064707 43.13936)
		(end -259.51688 43.13936)
		(width 0.11176)
		(layer "In5.Cu")
		(net "SAS_B1_RX8N")
	)
	(segment
		(start -256.705057 12.734183)
		(end -256.707447 12.735466)
		(width 0.11176)
		(layer "In5.Cu")
		(net "SAS_B1_RX8N")
	)
	(segment
		(start -261.493 41.91)
		(end -261.493 41.45534)
		(width 0.11176)
		(layer "In5.Cu")
		(net "SAS_B1_RX8N")
	)
	(segment
		(start -261.493 40.73144)
		(end -261.493 39.3827)
		(width 0.11176)
		(layer "In5.Cu")
		(net "SAS_B1_RX8N")
	)
	(segment
		(start -257.68 42.660001)
		(end -257.68 42.669)
		(width 0.11176)
		(layer "In5.Cu")
		(net "SAS_B1_RX8N")
	)
	(segment
		(start -261.493 38.49878)
		(end -261.493 37.34816)
		(width 0.11176)
		(layer "In5.Cu")
		(net "SAS_B1_RX8N")
	)
	(segment
		(start -258.296908 11.998508)
		(end -258.0078 11.7094)
		(width 0.11176)
		(layer "In5.Cu")
		(net "SAS_B1_RX8N")
	)
	(segment
		(start -256.707447 12.735466)
		(end -256.70745 12.735469)
		(width 0.11176)
		(layer "In5.Cu")
		(net "SAS_B1_RX8N")
	)
	(segment
		(start -258.699 13.081005)
		(end -258.699 12.969245)
		(width 0.11176)
		(layer "In5.Cu")
		(net "SAS_B1_RX8N")
	)
	(segment
		(start -256.421468 11.558168)
		(end -256.187781 11.791856)
		(width 0.11176)
		(layer "In5.Cu")
		(net "SAS_B1_RX8N")
	)
	(segment
		(start -256.187781 12.234022)
		(end -256.65651 12.702751)
		(width 0.11176)
		(layer "In5.Cu")
		(net "SAS_B1_RX8N")
	)
	(segment
		(start -261.26186 37.11702)
		(end -261.26186 36.69538)
		(width 0.11176)
		(layer "In5.Cu")
		(net "SAS_B1_RX8N")
	)
	(segment
		(start -261.26186 41.2242)
		(end -261.26186 40.96258)
		(width 0.11176)
		(layer "In5.Cu")
		(net "SAS_B1_RX8N")
	)
	(segment
		(start -256.65651 12.702751)
		(end -256.65651 12.702753)
		(width 0.11176)
		(layer "In5.Cu")
		(net "SAS_B1_RX8N")
	)
	(segment
		(start -258.0078 11.7094)
		(end -258.000144 11.701742)
		(width 0.11176)
		(layer "In5.Cu")
		(net "SAS_B1_RX8N")
	)
	(segment
		(start -259.024067 43.18)
		(end -259.064707 43.13936)
		(width 0.11176)
		(layer "In5.Cu")
		(net "SAS_B1_RX8N")
	)
	(segment
		(start -261.26186 35.44062)
		(end -261.26186 35.13582)
		(width 0.11176)
		(layer "In5.Cu")
		(net "SAS_B1_RX8N")
	)
	(segment
		(start -261.26186 39.15156)
		(end -261.26186 38.72992)
		(width 0.11176)
		(layer "In5.Cu")
		(net "SAS_B1_RX8N")
	)
	(segment
		(start -256.85874 12.689728)
		(end -257.100001 12.239371)
		(width 0.11176)
		(layer "In5.Cu")
		(net "SAS_B1_RX8N")
	)
	(segment
		(start -260.35 16.002)
		(end -259.597025 15.249027)
		(width 0.11176)
		(layer "In5.Cu")
		(net "SAS_B1_RX8N")
	)
	(segment
		(start -259.55752 43.18)
		(end -260.223 43.18)
		(width 0.11176)
		(layer "In5.Cu")
		(net "SAS_B1_RX8N")
	)
	(segment
		(start -258.191 43.18)
		(end -259.024067 43.18)
		(width 0.11176)
		(layer "In5.Cu")
		(net "SAS_B1_RX8N")
	)
	(segment
		(start -256.682758 12.722238)
		(end -256.705057 12.734183)
		(width 0.11176)
		(layer "In5.Cu")
		(net "SAS_B1_RX8N")
	)
	(segment
		(start -261.493 36.46424)
		(end -261.493 35.67176)
		(width 0.11176)
		(layer "In5.Cu")
		(net "SAS_B1_RX8N")
	)
	(arc
		(start -257.037492 11.303)
		(mid -256.704102 11.369317)
		(end -256.421468 11.558168)
		(width 0.11176)
		(layer "In5.Cu")
		(net "SAS_B1_RX8N")
	)
	(arc
		(start -261.493 39.3827)
		(mid -261.46473 39.31445)
		(end -261.39648 39.28618)
		(width 0.11176)
		(layer "In5.Cu")
		(net "SAS_B1_RX8N")
	)
	(arc
		(start -261.493 37.34816)
		(mid -261.466218 37.283502)
		(end -261.40156 37.25672)
		(width 0.11176)
		(layer "In5.Cu")
		(net "SAS_B1_RX8N")
	)
	(arc
		(start -258.000144 11.701742)
		(mid -257.558475 11.40663)
		(end -257.037492 11.303)
		(width 0.11176)
		(layer "In5.Cu")
		(net "SAS_B1_RX8N")
	)
	(arc
		(start -261.26186 38.72992)
		(mid -261.302777 38.631137)
		(end -261.40156 38.59022)
		(width 0.11176)
		(layer "In5.Cu")
		(net "SAS_B1_RX8N")
	)
	(arc
		(start -261.26186 36.69538)
		(mid -261.305753 36.589413)
		(end -261.41172 36.54552)
		(width 0.11176)
		(layer "In5.Cu")
		(net "SAS_B1_RX8N")
	)
	(arc
		(start -256.187781 11.791856)
		(mid -256.096205 12.012939)
		(end -256.187781 12.234022)
		(width 0.11176)
		(layer "In5.Cu")
		(net "SAS_B1_RX8N")
	)
	(arc
		(start -261.40156 38.59022)
		(mid -261.466218 38.563438)
		(end -261.493 38.49878)
		(width 0.11176)
		(layer "In5.Cu")
		(net "SAS_B1_RX8N")
	)
	(arc
		(start -256.70745 12.735469)
		(mid -256.792568 12.743931)
		(end -256.85874 12.689728)
		(width 0.11176)
		(layer "In5.Cu")
		(net "SAS_B1_RX8N")
	)
	(arc
		(start -261.39648 39.28618)
		(mid -261.301289 39.246751)
		(end -261.26186 39.15156)
		(width 0.11176)
		(layer "In5.Cu")
		(net "SAS_B1_RX8N")
	)
	(arc
		(start -260.223 43.18)
		(mid -261.121026 42.808026)
		(end -261.493 41.91)
		(width 0.11176)
		(layer "In5.Cu")
		(net "SAS_B1_RX8N")
	)
	(arc
		(start -261.493 18.761446)
		(mid -261.195944 17.268045)
		(end -260.35 16.002)
		(width 0.11176)
		(layer "In5.Cu")
		(net "SAS_B1_RX8N")
	)
	(arc
		(start -261.41172 36.54552)
		(mid -261.469194 36.521714)
		(end -261.493 36.46424)
		(width 0.11176)
		(layer "In5.Cu")
		(net "SAS_B1_RX8N")
	)
	(arc
		(start -261.41934 35.5981)
		(mid -261.307985 35.551975)
		(end -261.26186 35.44062)
		(width 0.11176)
		(layer "In5.Cu")
		(net "SAS_B1_RX8N")
	)
	(arc
		(start -257.68 42.669)
		(mid -257.829668 43.030332)
		(end -258.191 43.18)
		(width 0.11176)
		(layer "In5.Cu")
		(net "SAS_B1_RX8N")
	)
	(arc
		(start -261.493 41.45534)
		(mid -261.467706 41.394274)
		(end -261.40664 41.36898)
		(width 0.11176)
		(layer "In5.Cu")
		(net "SAS_B1_RX8N")
	)
	(arc
		(start -261.26186 35.13582)
		(mid -261.310961 35.017281)
		(end -261.4295 34.96818)
		(width 0.11176)
		(layer "In5.Cu")
		(net "SAS_B1_RX8N")
	)
	(arc
		(start -261.40664 41.36898)
		(mid -261.304265 41.326575)
		(end -261.26186 41.2242)
		(width 0.11176)
		(layer "In5.Cu")
		(net "SAS_B1_RX8N")
	)
	(arc
		(start -261.41426 40.81018)
		(mid -261.469938 40.787118)
		(end -261.493 40.73144)
		(width 0.11176)
		(layer "In5.Cu")
		(net "SAS_B1_RX8N")
	)
	(arc
		(start -261.40156 37.25672)
		(mid -261.302777 37.215803)
		(end -261.26186 37.11702)
		(width 0.11176)
		(layer "In5.Cu")
		(net "SAS_B1_RX8N")
	)
	(arc
		(start -261.26186 40.96258)
		(mid -261.306497 40.854817)
		(end -261.41426 40.81018)
		(width 0.11176)
		(layer "In5.Cu")
		(net "SAS_B1_RX8N")
	)
	(arc
		(start -259.597025 15.249027)
		(mid -258.93239 14.25433)
		(end -258.699 13.081005)
		(width 0.11176)
		(layer "In5.Cu")
		(net "SAS_B1_RX8N")
	)
	(arc
		(start -258.699 12.969245)
		(mid -258.5945 12.443886)
		(end -258.296908 11.998508)
		(width 0.11176)
		(layer "In5.Cu")
		(net "SAS_B1_RX8N")
	)
	(arc
		(start -261.4295 34.96818)
		(mid -261.474401 34.949581)
		(end -261.493 34.90468)
		(width 0.11176)
		(layer "In5.Cu")
		(net "SAS_B1_RX8N")
	)
	(arc
		(start -261.493 35.67176)
		(mid -261.471425 35.619675)
		(end -261.41934 35.5981)
		(width 0.11176)
		(layer "In5.Cu")
		(net "SAS_B1_RX8N")
	)
	(arc
		(start -256.65651 12.702753)
		(mid -256.668918 12.71346)
		(end -256.682758 12.722238)
		(width 0.11176)
		(layer "In5.Cu")
		(net "SAS_B1_RX8N")
	)
	(segment
		(start -255.9558 15.748)
		(end -255.9558 15.5194)
		(width 0.11176)
		(layer "In5.Cu")
		(net "SAS_B1_RX7P")
	)
	(segment
		(start -258.844943 35.1536)
		(end -258.4396 35.1536)
		(width 0.11176)
		(layer "In5.Cu")
		(net "SAS_B1_RX7P")
	)
	(segment
		(start -260.6875 20.890997)
		(end -260.6875 32.790188)
		(width 0.11176)
		(layer "In5.Cu")
		(net "SAS_B1_RX7P")
	)
	(segment
		(start -256.545522 16.837724)
		(end -256.506261 16.81669)
		(width 0.11176)
		(layer "In5.Cu")
		(net "SAS_B1_RX7P")
	)
	(segment
		(start -256.399475 16.737416)
		(end -256.341695 16.679636)
		(width 0.11176)
		(layer "In5.Cu")
		(net "SAS_B1_RX7P")
	)
	(segment
		(start -256.35 17.439371)
		(end -256.591262 16.989014)
		(width 0.11176)
		(layer "In5.Cu")
		(net "SAS_B1_RX7P")
	)
	(segment
		(start -256.545525 16.837724)
		(end -256.545522 16.837724)
		(width 0.11176)
		(layer "In5.Cu")
		(net "SAS_B1_RX7P")
	)
	(segment
		(start -256.117446 15.129154)
		(end -256.19075 15.05585)
		(width 0.11176)
		(layer "In5.Cu")
		(net "SAS_B1_RX7P")
	)
	(segment
		(start -258.592 15.720245)
		(end -258.592 15.832008)
		(width 0.11176)
		(layer "In5.Cu")
		(net "SAS_B1_RX7P")
	)
	(segment
		(start -258.007361 35.33264)
		(end -257.68 35.66)
		(width 0.11176)
		(layer "In5.Cu")
		(net "SAS_B1_RX7P")
	)
	(segment
		(start -256.75797 14.8209)
		(end -257.692655 14.8209)
		(width 0.11176)
		(layer "In5.Cu")
		(net "SAS_B1_RX7P")
	)
	(arc
		(start -256.19075 15.05585)
		(mid -256.450993 14.881961)
		(end -256.75797 14.8209)
		(width 0.11176)
		(layer "In5.Cu")
		(net "SAS_B1_RX7P")
	)
	(arc
		(start -255.9558 15.5194)
		(mid -255.99781 15.3082)
		(end -256.117446 15.129154)
		(width 0.11176)
		(layer "In5.Cu")
		(net "SAS_B1_RX7P")
	)
	(arc
		(start -256.341695 16.679636)
		(mid -256.056091 16.252198)
		(end -255.9558 15.748)
		(width 0.11176)
		(layer "In5.Cu")
		(net "SAS_B1_RX7P")
	)
	(arc
		(start -257.692655 14.8209)
		(mid -258.328588 15.084312)
		(end -258.592 15.720245)
		(width 0.11176)
		(layer "In5.Cu")
		(net "SAS_B1_RX7P")
	)
	(arc
		(start -258.656668 15.988132)
		(mid -260.159704 18.237586)
		(end -260.6875 20.890997)
		(width 0.11176)
		(layer "In5.Cu")
		(net "SAS_B1_RX7P")
	)
	(arc
		(start -258.592 15.832008)
		(mid -258.608807 15.916501)
		(end -258.656668 15.988132)
		(width 0.11176)
		(layer "In5.Cu")
		(net "SAS_B1_RX7P")
	)
	(arc
		(start -256.506261 16.81669)
		(mid -256.449954 16.780979)
		(end -256.399475 16.737416)
		(width 0.11176)
		(layer "In5.Cu")
		(net "SAS_B1_RX7P")
	)
	(arc
		(start -259.8874 34.7218)
		(mid -259.409117 35.041379)
		(end -258.844943 35.1536)
		(width 0.11176)
		(layer "In5.Cu")
		(net "SAS_B1_RX7P")
	)
	(arc
		(start -256.591262 16.989014)
		(mid -256.599727 16.903896)
		(end -256.545525 16.837724)
		(width 0.11176)
		(layer "In5.Cu")
		(net "SAS_B1_RX7P")
	)
	(arc
		(start -258.4396 35.1536)
		(mid -258.205674 35.200131)
		(end -258.007361 35.33264)
		(width 0.11176)
		(layer "In5.Cu")
		(net "SAS_B1_RX7P")
	)
	(arc
		(start -260.6875 32.790188)
		(mid -260.479561 33.835569)
		(end -259.8874 34.7218)
		(width 0.11176)
		(layer "In5.Cu")
		(net "SAS_B1_RX7P")
	)
	(segment
		(start -260.11378 28.03144)
		(end -260.11378 28.59024)
		(width 0.11176)
		(layer "In5.Cu")
		(net "SAS_B1_RX7N")
	)
	(segment
		(start -260.11346 24.499885)
		(end -260.11346 24.814845)
		(width 0.11176)
		(layer "In5.Cu")
		(net "SAS_B1_RX7N")
	)
	(segment
		(start -260.11346 24.814845)
		(end -260.344597 25.04598)
		(width 0.11176)
		(layer "In5.Cu")
		(net "SAS_B1_RX7N")
	)
	(segment
		(start -260.344597 20.891)
		(end -260.344597 24.26875)
		(width 0.11176)
		(layer "In5.Cu")
		(net "SAS_B1_RX7N")
	)
	(segment
		(start -256.70745 16.535466)
		(end -256.707447 16.535464)
		(width 0.11176)
		(layer "In5.Cu")
		(net "SAS_B1_RX7N")
	)
	(segment
		(start -260.11378 29.94152)
		(end -260.11378 30.35808)
		(width 0.11176)
		(layer "In5.Cu")
		(net "SAS_B1_RX7N")
	)
	(segment
		(start -260.2611 30.5054)
		(end -260.2738 30.5054)
		(width 0.11176)
		(layer "In5.Cu")
		(net "SAS_B1_RX7N")
	)
	(segment
		(start -258.844941 34.8107)
		(end -258.4396 34.8107)
		(width 0.11176)
		(layer "In5.Cu")
		(net "SAS_B1_RX7N")
	)
	(segment
		(start -258.082984 34.662986)
		(end -257.68 34.26)
		(width 0.11176)
		(layer "In5.Cu")
		(net "SAS_B1_RX7N")
	)
	(segment
		(start -256.359911 15.371623)
		(end -256.433218 15.298318)
		(width 0.11176)
		(layer "In5.Cu")
		(net "SAS_B1_RX7N")
	)
	(segment
		(start -260.344597 25.04598)
		(end -260.344597 26.202963)
		(width 0.11176)
		(layer "In5.Cu")
		(net "SAS_B1_RX7N")
	)
	(segment
		(start -256.70745 16.535464)
		(end -256.668189 16.51443)
		(width 0.11176)
		(layer "In5.Cu")
		(net "SAS_B1_RX7N")
	)
	(segment
		(start -260.344597 28.821057)
		(end -260.344597 29.710703)
		(width 0.11176)
		(layer "In5.Cu")
		(net "SAS_B1_RX7N")
	)
	(segment
		(start -256.707447 16.535464)
		(end -256.70745 16.535464)
		(width 0.11176)
		(layer "In5.Cu")
		(net "SAS_B1_RX7N")
	)
	(segment
		(start -260.13156 26.416)
		(end -260.13156 26.86304)
		(width 0.11176)
		(layer "In5.Cu")
		(net "SAS_B1_RX7N")
	)
	(segment
		(start -260.232837 27.9146)
		(end -260.23062 27.9146)
		(width 0.11176)
		(layer "In5.Cu")
		(net "SAS_B1_RX7N")
	)
	(segment
		(start -260.3446 20.890997)
		(end -260.344597 20.891)
		(width 0.11176)
		(layer "In5.Cu")
		(net "SAS_B1_RX7N")
	)
	(segment
		(start -256.2987 15.748003)
		(end -256.2987 15.5194)
		(width 0.11176)
		(layer "In5.Cu")
		(net "SAS_B1_RX7N")
	)
	(segment
		(start -256.298703 15.748)
		(end -256.2987 15.748003)
		(width 0.11176)
		(layer "In5.Cu")
		(net "SAS_B1_RX7N")
	)
	(segment
		(start -256.75797 15.1638)
		(end -257.692655 15.1638)
		(width 0.11176)
		(layer "In5.Cu")
		(net "SAS_B1_RX7N")
	)
	(segment
		(start -257.100001 16.039371)
		(end -256.85874 16.489726)
		(width 0.11176)
		(layer "In5.Cu")
		(net "SAS_B1_RX7N")
	)
	(segment
		(start -258.2491 15.720245)
		(end -258.2491 15.832005)
		(width 0.11176)
		(layer "In5.Cu")
		(net "SAS_B1_RX7N")
	)
	(segment
		(start -260.344597 27.076077)
		(end -260.344597 27.80284)
		(width 0.11176)
		(layer "In5.Cu")
		(net "SAS_B1_RX7N")
	)
	(segment
		(start -260.344597 30.576197)
		(end -260.344597 32.790188)
		(width 0.11176)
		(layer "In5.Cu")
		(net "SAS_B1_RX7N")
	)
	(segment
		(start -256.641938 16.494945)
		(end -256.584163 16.437168)
		(width 0.11176)
		(layer "In5.Cu")
		(net "SAS_B1_RX7N")
	)
	(segment
		(start -260.344597 24.26875)
		(end -260.11346 24.499885)
		(width 0.11176)
		(layer "In5.Cu")
		(net "SAS_B1_RX7N")
	)
	(arc
		(start -256.433218 15.298318)
		(mid -256.582215 15.19876)
		(end -256.75797 15.1638)
		(width 0.11176)
		(layer "In5.Cu")
		(net "SAS_B1_RX7N")
	)
	(arc
		(start -260.26364 26.28392)
		(mid -260.170245 26.322605)
		(end -260.13156 26.416)
		(width 0.11176)
		(layer "In5.Cu")
		(net "SAS_B1_RX7N")
	)
	(arc
		(start -260.24078 28.71724)
		(mid -260.31419 28.747647)
		(end -260.344597 28.821057)
		(width 0.11176)
		(layer "In5.Cu")
		(net "SAS_B1_RX7N")
	)
	(arc
		(start -260.344597 26.202963)
		(mid -260.320885 26.260208)
		(end -260.26364 26.28392)
		(width 0.11176)
		(layer "In5.Cu")
		(net "SAS_B1_RX7N")
	)
	(arc
		(start -256.668189 16.51443)
		(mid -256.654347 16.505653)
		(end -256.641938 16.494945)
		(width 0.11176)
		(layer "In5.Cu")
		(net "SAS_B1_RX7N")
	)
	(arc
		(start -260.344597 29.710703)
		(mid -260.318653 29.773336)
		(end -260.25602 29.79928)
		(width 0.11176)
		(layer "In5.Cu")
		(net "SAS_B1_RX7N")
	)
	(arc
		(start -256.85874 16.489726)
		(mid -256.792568 16.543929)
		(end -256.70745 16.535466)
		(width 0.11176)
		(layer "In5.Cu")
		(net "SAS_B1_RX7N")
	)
	(arc
		(start -260.23062 27.9146)
		(mid -260.148002 27.948822)
		(end -260.11378 28.03144)
		(width 0.11176)
		(layer "In5.Cu")
		(net "SAS_B1_RX7N")
	)
	(arc
		(start -258.4396 34.8107)
		(mid -258.246601 34.772311)
		(end -258.082984 34.662986)
		(width 0.11176)
		(layer "In5.Cu")
		(net "SAS_B1_RX7N")
	)
	(arc
		(start -258.2491 15.832005)
		(mid -258.292007 16.047723)
		(end -258.4142 16.2306)
		(width 0.11176)
		(layer "In5.Cu")
		(net "SAS_B1_RX7N")
	)
	(arc
		(start -260.11378 30.35808)
		(mid -260.156929 30.462251)
		(end -260.2611 30.5054)
		(width 0.11176)
		(layer "In5.Cu")
		(net "SAS_B1_RX7N")
	)
	(arc
		(start -260.13156 26.86304)
		(mid -260.168757 26.952843)
		(end -260.25856 26.99004)
		(width 0.11176)
		(layer "In5.Cu")
		(net "SAS_B1_RX7N")
	)
	(arc
		(start -260.344597 32.790188)
		(mid -260.16276 33.704346)
		(end -259.644932 34.479332)
		(width 0.11176)
		(layer "In5.Cu")
		(net "SAS_B1_RX7N")
	)
	(arc
		(start -256.584163 16.437168)
		(mid -256.372891 16.120975)
		(end -256.298703 15.748)
		(width 0.11176)
		(layer "In5.Cu")
		(net "SAS_B1_RX7N")
	)
	(arc
		(start -260.25602 29.79928)
		(mid -260.155441 29.840941)
		(end -260.11378 29.94152)
		(width 0.11176)
		(layer "In5.Cu")
		(net "SAS_B1_RX7N")
	)
	(arc
		(start -260.2738 30.5054)
		(mid -260.323861 30.526136)
		(end -260.344597 30.576197)
		(width 0.11176)
		(layer "In5.Cu")
		(net "SAS_B1_RX7N")
	)
	(arc
		(start -257.692655 15.1638)
		(mid -258.086121 15.326779)
		(end -258.2491 15.720245)
		(width 0.11176)
		(layer "In5.Cu")
		(net "SAS_B1_RX7N")
	)
	(arc
		(start -256.2987 15.5194)
		(mid -256.314608 15.439424)
		(end -256.359911 15.371623)
		(width 0.11176)
		(layer "In5.Cu")
		(net "SAS_B1_RX7N")
	)
	(arc
		(start -259.644932 34.479332)
		(mid -259.277893 34.72458)
		(end -258.844941 34.8107)
		(width 0.11176)
		(layer "In5.Cu")
		(net "SAS_B1_RX7N")
	)
	(arc
		(start -260.11378 28.59024)
		(mid -260.150977 28.680043)
		(end -260.24078 28.71724)
		(width 0.11176)
		(layer "In5.Cu")
		(net "SAS_B1_RX7N")
	)
	(arc
		(start -258.4142 16.2306)
		(mid -259.842905 18.368808)
		(end -260.3446 20.890997)
		(width 0.11176)
		(layer "In5.Cu")
		(net "SAS_B1_RX7N")
	)
	(arc
		(start -260.344597 27.80284)
		(mid -260.311863 27.881866)
		(end -260.232837 27.9146)
		(width 0.11176)
		(layer "In5.Cu")
		(net "SAS_B1_RX7N")
	)
	(arc
		(start -260.25856 26.99004)
		(mid -260.319397 27.01524)
		(end -260.344597 27.076077)
		(width 0.11176)
		(layer "In5.Cu")
		(net "SAS_B1_RX7N")
	)
	(segment
		(start -260.77894 28.9052)
		(end -260.77894 28.75026)
		(width 0.10668)
		(layer "B.Cu")
		(net "SAS_B1_RX6P")
	)
	(segment
		(start -256.89274 31.26994)
		(end -256.89274 30.48)
		(width 0.10668)
		(layer "B.Cu")
		(net "SAS_B1_RX6P")
	)
	(segment
		(start -254.198277 13.037497)
		(end -254.278407 13.080423)
		(width 0.10668)
		(layer "B.Cu")
		(net "SAS_B1_RX6P")
	)
	(segment
		(start -254.278407 13.080426)
		(end -254.278409 13.080426)
		(width 0.10668)
		(layer "B.Cu")
		(net "SAS_B1_RX6P")
	)
	(segment
		(start -254.278407 13.080423)
		(end -254.278407 13.080426)
		(width 0.10668)
		(layer "B.Cu")
		(net "SAS_B1_RX6P")
	)
	(segment
		(start -260.88562 28.64358)
		(end -260.985 28.64358)
		(width 0.10668)
		(layer "B.Cu")
		(net "SAS_B1_RX6P")
	)
	(segment
		(start -252.6611 14.52626)
		(end -251.791267 14.52626)
		(width 0.10668)
		(layer "B.Cu")
		(net "SAS_B1_RX6P")
	)
	(segment
		(start -257.576 29.79674)
		(end -259.8874 29.79674)
		(width 0.10668)
		(layer "B.Cu")
		(net "SAS_B1_RX6P")
	)
	(segment
		(start -258.83584 14.76756)
		(end -254.806155 14.76756)
		(width 0.10668)
		(layer "B.Cu")
		(net "SAS_B1_RX6P")
	)
	(segment
		(start -257.1823 31.92272)
		(end -257.1823 31.5595)
		(width 0.10668)
		(layer "B.Cu")
		(net "SAS_B1_RX6P")
	)
	(segment
		(start -260.77894 25.19394)
		(end -260.77894 16.71066)
		(width 0.10668)
		(layer "B.Cu")
		(net "SAS_B1_RX6P")
	)
	(segment
		(start -260.9596 25.4254)
		(end -260.814861 25.280661)
		(width 0.10668)
		(layer "B.Cu")
		(net "SAS_B1_RX6P")
	)
	(segment
		(start -260.77894 27.96032)
		(end -260.77894 26.24106)
		(width 0.10668)
		(layer "B.Cu")
		(net "SAS_B1_RX6P")
	)
	(segment
		(start -251.80798 11.45794)
		(end -253.0348 11.45794)
		(width 0.10668)
		(layer "B.Cu")
		(net "SAS_B1_RX6P")
	)
	(segment
		(start -256.1028 40.69334)
		(end -256.2806 40.69334)
		(width 0.10668)
		(layer "B.Cu")
		(net "SAS_B1_RX6P")
	)
	(segment
		(start -260.985 28.067)
		(end -260.88562 28.067)
		(width 0.10668)
		(layer "B.Cu")
		(net "SAS_B1_RX6P")
	)
	(segment
		(start -254.278409 13.080426)
		(end -254.278412 13.080429)
		(width 0.10668)
		(layer "B.Cu")
		(net "SAS_B1_RX6P")
	)
	(segment
		(start -260.814861 26.154339)
		(end -260.9596 26.0096)
		(width 0.10668)
		(layer "B.Cu")
		(net "SAS_B1_RX6P")
	)
	(segment
		(start -261.1066 28.52198)
		(end -261.1066 28.1886)
		(width 0.10668)
		(layer "B.Cu")
		(net "SAS_B1_RX6P")
	)
	(segment
		(start -256.99942 32.0548)
		(end -257.05022 32.0548)
		(width 0.10668)
		(layer "B.Cu")
		(net "SAS_B1_RX6P")
	)
	(segment
		(start -254.01002 12.881983)
		(end -254.071209 12.943167)
		(width 0.10668)
		(layer "B.Cu")
		(net "SAS_B1_RX6P")
	)
	(segment
		(start -255.679999 41.160002)
		(end -255.679999 41.116141)
		(width 0.10668)
		(layer "B.Cu")
		(net "SAS_B1_RX6P")
	)
	(segment
		(start -260.9596 26.0096)
		(end -260.9596 25.4254)
		(width 0.10668)
		(layer "B.Cu")
		(net "SAS_B1_RX6P")
	)
	(segment
		(start -251.079 13.813993)
		(end -251.079 12.18692)
		(width 0.10668)
		(layer "B.Cu")
		(net "SAS_B1_RX6P")
	)
	(segment
		(start -254.322072 13.22484)
		(end -254.1 13.639371)
		(width 0.10668)
		(layer "B.Cu")
		(net "SAS_B1_RX6P")
	)
	(segment
		(start -256.89274 40.0812)
		(end -256.89274 32.16148)
		(width 0.10668)
		(layer "B.Cu")
		(net "SAS_B1_RX6P")
	)
	(arc
		(start -254.57132 14.715432)
		(mid -254.332666 14.623903)
		(end -254.0835 14.5669)
		(width 0.10668)
		(layer "B.Cu")
		(net "SAS_B1_RX6P")
	)
	(arc
		(start -260.88562 28.067)
		(mid -260.810186 28.035754)
		(end -260.77894 27.96032)
		(width 0.10668)
		(layer "B.Cu")
		(net "SAS_B1_RX6P")
	)
	(arc
		(start -257.068 31.4452)
		(mid -256.944072 31.393868)
		(end -256.89274 31.26994)
		(width 0.10668)
		(layer "B.Cu")
		(net "SAS_B1_RX6P")
	)
	(arc
		(start -254.806155 14.76756)
		(mid -254.685879 14.754371)
		(end -254.57132 14.715432)
		(width 0.10668)
		(layer "B.Cu")
		(net "SAS_B1_RX6P")
	)
	(arc
		(start -261.1066 28.1886)
		(mid -261.070984 28.102616)
		(end -260.985 28.067)
		(width 0.10668)
		(layer "B.Cu")
		(net "SAS_B1_RX6P")
	)
	(arc
		(start -257.05022 32.0548)
		(mid -257.143615 32.016115)
		(end -257.1823 31.92272)
		(width 0.10668)
		(layer "B.Cu")
		(net "SAS_B1_RX6P")
	)
	(arc
		(start -260.814861 25.280661)
		(mid -260.788275 25.240873)
		(end -260.77894 25.19394)
		(width 0.10668)
		(layer "B.Cu")
		(net "SAS_B1_RX6P")
	)
	(arc
		(start -256.89274 30.48)
		(mid -257.092862 29.996862)
		(end -257.576 29.79674)
		(width 0.10668)
		(layer "B.Cu")
		(net "SAS_B1_RX6P")
	)
	(arc
		(start -254.278412 13.080429)
		(mid -254.33015 13.143592)
		(end -254.322072 13.22484)
		(width 0.10668)
		(layer "B.Cu")
		(net "SAS_B1_RX6P")
	)
	(arc
		(start -255.679999 41.116141)
		(mid -255.803835 40.817176)
		(end -256.1028 40.69334)
		(width 0.10668)
		(layer "B.Cu")
		(net "SAS_B1_RX6P")
	)
	(arc
		(start -259.8874 29.79674)
		(mid -260.517814 29.535614)
		(end -260.77894 28.9052)
		(width 0.10668)
		(layer "B.Cu")
		(net "SAS_B1_RX6P")
	)
	(arc
		(start -253.692657 12.1158)
		(mid -253.775136 12.530456)
		(end -254.01002 12.881983)
		(width 0.10668)
		(layer "B.Cu")
		(net "SAS_B1_RX6P")
	)
	(arc
		(start -257.1823 31.5595)
		(mid -257.148822 31.478678)
		(end -257.068 31.4452)
		(width 0.10668)
		(layer "B.Cu")
		(net "SAS_B1_RX6P")
	)
	(arc
		(start -254.0835 14.5669)
		(mid -253.37259 14.536422)
		(end -252.6611 14.52626)
		(width 0.10668)
		(layer "B.Cu")
		(net "SAS_B1_RX6P")
	)
	(arc
		(start -254.071209 12.943167)
		(mid -254.131275 12.995003)
		(end -254.198277 13.037497)
		(width 0.10668)
		(layer "B.Cu")
		(net "SAS_B1_RX6P")
	)
	(arc
		(start -260.77894 28.75026)
		(mid -260.810186 28.674826)
		(end -260.88562 28.64358)
		(width 0.10668)
		(layer "B.Cu")
		(net "SAS_B1_RX6P")
	)
	(arc
		(start -260.985 28.64358)
		(mid -261.070984 28.607964)
		(end -261.1066 28.52198)
		(width 0.10668)
		(layer "B.Cu")
		(net "SAS_B1_RX6P")
	)
	(arc
		(start -251.079 12.18692)
		(mid -251.292513 11.671453)
		(end -251.80798 11.45794)
		(width 0.10668)
		(layer "B.Cu")
		(net "SAS_B1_RX6P")
	)
	(arc
		(start -260.77894 16.71066)
		(mid -260.209819 15.336681)
		(end -258.83584 14.76756)
		(width 0.10668)
		(layer "B.Cu")
		(net "SAS_B1_RX6P")
	)
	(arc
		(start -256.89274 32.16148)
		(mid -256.923986 32.086046)
		(end -256.99942 32.0548)
		(width 0.10668)
		(layer "B.Cu")
		(net "SAS_B1_RX6P")
	)
	(arc
		(start -260.77894 26.24106)
		(mid -260.788276 26.194127)
		(end -260.814861 26.154339)
		(width 0.10668)
		(layer "B.Cu")
		(net "SAS_B1_RX6P")
	)
	(arc
		(start -256.2806 40.69334)
		(mid -256.713448 40.514048)
		(end -256.89274 40.0812)
		(width 0.10668)
		(layer "B.Cu")
		(net "SAS_B1_RX6P")
	)
	(arc
		(start -253.0348 11.45794)
		(mid -253.499976 11.650623)
		(end -253.692657 12.1158)
		(width 0.10668)
		(layer "B.Cu")
		(net "SAS_B1_RX6P")
	)
	(arc
		(start -251.791267 14.52626)
		(mid -251.287618 14.317642)
		(end -251.079 13.813993)
		(width 0.10668)
		(layer "B.Cu")
		(net "SAS_B1_RX6P")
	)
	(segment
		(start -258.83584 15.2019)
		(end -254.806155 15.2019)
		(width 0.10668)
		(layer "B.Cu")
		(net "SAS_B1_RX6N")
	)
	(segment
		(start -254.627929 12.653904)
		(end -254.850001 12.239371)
		(width 0.10668)
		(layer "B.Cu")
		(net "SAS_B1_RX6N")
	)
	(segment
		(start -254.317144 12.574854)
		(end -254.378325 12.636033)
		(width 0.10668)
		(layer "B.Cu")
		(net "SAS_B1_RX6N")
	)
	(segment
		(start -250.64466 13.813993)
		(end -250.64466 12.18692)
		(width 0.10668)
		(layer "B.Cu")
		(net "SAS_B1_RX6N")
	)
	(segment
		(start -252.6611 14.9606)
		(end -251.791267 14.9606)
		(width 0.10668)
		(layer "B.Cu")
		(net "SAS_B1_RX6N")
	)
	(segment
		(start -256.4584 40.0812)
		(end -256.4584 30.48)
		(width 0.10668)
		(layer "B.Cu")
		(net "SAS_B1_RX6N")
	)
	(segment
		(start -254.483514 12.697562)
		(end -254.483517 12.697562)
		(width 0.10668)
		(layer "B.Cu")
		(net "SAS_B1_RX6N")
	)
	(segment
		(start -257.576 29.3624)
		(end -259.8874 29.3624)
		(width 0.10668)
		(layer "B.Cu")
		(net "SAS_B1_RX6N")
	)
	(segment
		(start -260.3446 28.9052)
		(end -260.3446 16.71066)
		(width 0.10668)
		(layer "B.Cu")
		(net "SAS_B1_RX6N")
	)
	(segment
		(start -256.1028 40.259)
		(end -256.2806 40.259)
		(width 0.10668)
		(layer "B.Cu")
		(net "SAS_B1_RX6N")
	)
	(segment
		(start -254.403382 12.654633)
		(end -254.483514 12.697562)
		(width 0.10668)
		(layer "B.Cu")
		(net "SAS_B1_RX6N")
	)
	(segment
		(start -255.679999 39.760002)
		(end -255.679999 39.836199)
		(width 0.10668)
		(layer "B.Cu")
		(net "SAS_B1_RX6N")
	)
	(segment
		(start -251.80798 11.0236)
		(end -253.0348 11.0236)
		(width 0.10668)
		(layer "B.Cu")
		(net "SAS_B1_RX6N")
	)
	(arc
		(start -259.8874 29.3624)
		(mid -260.210689 29.228489)
		(end -260.3446 28.9052)
		(width 0.10668)
		(layer "B.Cu")
		(net "SAS_B1_RX6N")
	)
	(arc
		(start -256.2806 40.259)
		(mid -256.406324 40.206924)
		(end -256.4584 40.0812)
		(width 0.10668)
		(layer "B.Cu")
		(net "SAS_B1_RX6N")
	)
	(arc
		(start -254.127 12.1158)
		(mid -254.176416 12.364238)
		(end -254.317144 12.574854)
		(width 0.10668)
		(layer "B.Cu")
		(net "SAS_B1_RX6N")
	)
	(arc
		(start -260.3446 16.71066)
		(mid -259.902694 15.643806)
		(end -258.83584 15.2019)
		(width 0.10668)
		(layer "B.Cu")
		(net "SAS_B1_RX6N")
	)
	(arc
		(start -253.0348 11.0236)
		(mid -253.807102 11.343498)
		(end -254.127 12.1158)
		(width 0.10668)
		(layer "B.Cu")
		(net "SAS_B1_RX6N")
	)
	(arc
		(start -254.387543 15.108977)
		(mid -254.206153 15.03941)
		(end -254.016772 14.996084)
		(width 0.10668)
		(layer "B.Cu")
		(net "SAS_B1_RX6N")
	)
	(arc
		(start -251.791267 14.9606)
		(mid -250.980493 14.624767)
		(end -250.64466 13.813993)
		(width 0.10668)
		(layer "B.Cu")
		(net "SAS_B1_RX6N")
	)
	(arc
		(start -254.378325 12.636033)
		(mid -254.39017 12.646254)
		(end -254.403382 12.654633)
		(width 0.10668)
		(layer "B.Cu")
		(net "SAS_B1_RX6N")
	)
	(arc
		(start -254.016772 14.996084)
		(mid -253.339168 14.969473)
		(end -252.6611 14.9606)
		(width 0.10668)
		(layer "B.Cu")
		(net "SAS_B1_RX6N")
	)
	(arc
		(start -255.679999 39.836199)
		(mid -255.803835 40.135164)
		(end -256.1028 40.259)
		(width 0.10668)
		(layer "B.Cu")
		(net "SAS_B1_RX6N")
	)
	(arc
		(start -256.4584 30.48)
		(mid -256.785737 29.689737)
		(end -257.576 29.3624)
		(width 0.10668)
		(layer "B.Cu")
		(net "SAS_B1_RX6N")
	)
	(arc
		(start -254.483517 12.697562)
		(mid -254.564764 12.705641)
		(end -254.627929 12.653904)
		(width 0.10668)
		(layer "B.Cu")
		(net "SAS_B1_RX6N")
	)
	(arc
		(start -254.806155 15.2019)
		(mid -254.591754 15.17839)
		(end -254.387543 15.108977)
		(width 0.10668)
		(layer "B.Cu")
		(net "SAS_B1_RX6N")
	)
	(arc
		(start -250.64466 12.18692)
		(mid -250.985389 11.364329)
		(end -251.80798 11.0236)
		(width 0.10668)
		(layer "B.Cu")
		(net "SAS_B1_RX6N")
	)
	(segment
		(start -254.466507 16.981195)
		(end -254.490007 16.993784)
		(width 0.10668)
		(layer "B.Cu")
		(net "SAS_B1_RX5P")
	)
	(segment
		(start -252.44266 30.75686)
		(end -252.44266 31.4198)
		(width 0.10668)
		(layer "B.Cu")
		(net "SAS_B1_RX5P")
	)
	(segment
		(start -253.0802 35.15614)
		(end -253.176141 35.15614)
		(width 0.10668)
		(layer "B.Cu")
		(net "SAS_B1_RX5P")
	)
	(segment
		(start -254.466484 16.981183)
		(end -254.466486 16.981183)
		(width 0.10668)
		(layer "B.Cu")
		(net "SAS_B1_RX5P")
	)
	(segment
		(start -252.44266 28.731012)
		(end -252.44266 29.87834)
		(width 0.10668)
		(layer "B.Cu")
		(net "SAS_B1_RX5P")
	)
	(segment
		(start -254.466486 16.981185)
		(end -254.466507 16.981195)
		(width 0.10668)
		(layer "B.Cu")
		(net "SAS_B1_RX5P")
	)
	(segment
		(start -252.44266 32.40786)
		(end -252.44266 33.041547)
		(width 0.10668)
		(layer "B.Cu")
		(net "SAS_B1_RX5P")
	)
	(segment
		(start -254.466486 16.981183)
		(end -254.466486 16.981185)
		(width 0.10668)
		(layer "B.Cu")
		(net "SAS_B1_RX5P")
	)
	(segment
		(start -254.505137 18.25752)
		(end -251.47746 18.25752)
		(width 0.10668)
		(layer "B.Cu")
		(net "SAS_B1_RX5P")
	)
	(segment
		(start -254.1 17.439371)
		(end -254.322072 17.02484)
		(width 0.10668)
		(layer "B.Cu")
		(net "SAS_B1_RX5P")
	)
	(segment
		(start -252.44266 33.804868)
		(end -252.44266 34.5186)
		(width 0.10668)
		(layer "B.Cu")
		(net "SAS_B1_RX5P")
	)
	(segment
		(start -252.0896 31.75)
		(end -252.0896 32.0548)
		(width 0.10668)
		(layer "B.Cu")
		(net "SAS_B1_RX5P")
	)
	(segment
		(start -250.6672 19.06778)
		(end -250.6672 25.637292)
		(width 0.10668)
		(layer "B.Cu")
		(net "SAS_B1_RX5P")
	)
	(segment
		(start -252.29026 31.5722)
		(end -252.2674 31.5722)
		(width 0.10668)
		(layer "B.Cu")
		(net "SAS_B1_RX5P")
	)
	(segment
		(start -252.115 30.206)
		(end -252.115 30.4292)
		(width 0.10668)
		(layer "B.Cu")
		(net "SAS_B1_RX5P")
	)
	(segment
		(start -252.44266 33.041547)
		(end -252.2474 33.236807)
		(width 0.10668)
		(layer "B.Cu")
		(net "SAS_B1_RX5P")
	)
	(segment
		(start -251.472568 27.581621)
		(end -252.315873 28.424927)
		(width 0.10668)
		(layer "B.Cu")
		(net "SAS_B1_RX5P")
	)
	(segment
		(start -252.2474 33.236807)
		(end -252.2474 33.609608)
		(width 0.10668)
		(layer "B.Cu")
		(net "SAS_B1_RX5P")
	)
	(segment
		(start -254.515069 17.012387)
		(end -254.709188 17.206509)
		(width 0.10668)
		(layer "B.Cu")
		(net "SAS_B1_RX5P")
	)
	(segment
		(start -252.2474 33.609608)
		(end -252.44266 33.804868)
		(width 0.10668)
		(layer "B.Cu")
		(net "SAS_B1_RX5P")
	)
	(arc
		(start -252.2928 30.607)
		(mid -252.398767 30.650893)
		(end -252.44266 30.75686)
		(width 0.10668)
		(layer "B.Cu")
		(net "SAS_B1_RX5P")
	)
	(arc
		(start -253.176141 35.15614)
		(mid -253.201547 35.156781)
		(end -253.226888 35.158703)
		(width 0.10668)
		(layer "B.Cu")
		(net "SAS_B1_RX5P")
	)
	(arc
		(start -253.226888 35.158703)
		(mid -253.549935 35.322136)
		(end -253.680001 35.66)
		(width 0.10668)
		(layer "B.Cu")
		(net "SAS_B1_RX5P")
	)
	(arc
		(start -252.2674 31.5722)
		(mid -252.141676 31.624276)
		(end -252.0896 31.75)
		(width 0.10668)
		(layer "B.Cu")
		(net "SAS_B1_RX5P")
	)
	(arc
		(start -252.315873 28.424927)
		(mid -252.409709 28.56536)
		(end -252.44266 28.731012)
		(width 0.10668)
		(layer "B.Cu")
		(net "SAS_B1_RX5P")
	)
	(arc
		(start -254.322072 17.02484)
		(mid -254.385237 16.973103)
		(end -254.466484 16.981183)
		(width 0.10668)
		(layer "B.Cu")
		(net "SAS_B1_RX5P")
	)
	(arc
		(start -252.44266 31.4198)
		(mid -252.398023 31.527563)
		(end -252.29026 31.5722)
		(width 0.10668)
		(layer "B.Cu")
		(net "SAS_B1_RX5P")
	)
	(arc
		(start -252.44266 34.5186)
		(mid -252.629391 34.969409)
		(end -253.0802 35.15614)
		(width 0.10668)
		(layer "B.Cu")
		(net "SAS_B1_RX5P")
	)
	(arc
		(start -250.6672 25.637292)
		(mid -250.876508 26.689555)
		(end -251.472568 27.581621)
		(width 0.10668)
		(layer "B.Cu")
		(net "SAS_B1_RX5P")
	)
	(arc
		(start -254.490007 16.993784)
		(mid -254.503222 17.002164)
		(end -254.515069 17.012387)
		(width 0.10668)
		(layer "B.Cu")
		(net "SAS_B1_RX5P")
	)
	(arc
		(start -254.957257 17.8054)
		(mid -254.824834 18.125097)
		(end -254.505137 18.25752)
		(width 0.10668)
		(layer "B.Cu")
		(net "SAS_B1_RX5P")
	)
	(arc
		(start -252.0896 32.0548)
		(mid -252.149116 32.198484)
		(end -252.2928 32.258)
		(width 0.10668)
		(layer "B.Cu")
		(net "SAS_B1_RX5P")
	)
	(arc
		(start -251.47746 18.25752)
		(mid -250.90452 18.49484)
		(end -250.6672 19.06778)
		(width 0.10668)
		(layer "B.Cu")
		(net "SAS_B1_RX5P")
	)
	(arc
		(start -252.115 30.4292)
		(mid -252.167076 30.554924)
		(end -252.2928 30.607)
		(width 0.10668)
		(layer "B.Cu")
		(net "SAS_B1_RX5P")
	)
	(arc
		(start -252.349 29.972)
		(mid -252.183537 30.040537)
		(end -252.115 30.206)
		(width 0.10668)
		(layer "B.Cu")
		(net "SAS_B1_RX5P")
	)
	(arc
		(start -252.44266 29.87834)
		(mid -252.415228 29.944568)
		(end -252.349 29.972)
		(width 0.10668)
		(layer "B.Cu")
		(net "SAS_B1_RX5P")
	)
	(arc
		(start -254.709188 17.206509)
		(mid -254.892786 17.481283)
		(end -254.957257 17.8054)
		(width 0.10668)
		(layer "B.Cu")
		(net "SAS_B1_RX5P")
	)
	(arc
		(start -252.2928 32.258)
		(mid -252.398767 32.301893)
		(end -252.44266 32.40786)
		(width 0.10668)
		(layer "B.Cu")
		(net "SAS_B1_RX5P")
	)
	(segment
		(start -253.679998 34.356548)
		(end -253.680001 34.26)
		(width 0.10668)
		(layer "B.Cu")
		(net "SAS_B1_RX5N")
	)
	(segment
		(start -252.877 28.731009)
		(end -252.877 34.5186)
		(width 0.10668)
		(layer "B.Cu")
		(net "SAS_B1_RX5N")
	)
	(segment
		(start -254.671637 16.598341)
		(end -254.695112 16.610919)
		(width 0.10668)
		(layer "B.Cu")
		(net "SAS_B1_RX5N")
	)
	(segment
		(start -254.671589 16.598316)
		(end -254.671591 16.598318)
		(width 0.10668)
		(layer "B.Cu")
		(net "SAS_B1_RX5N")
	)
	(segment
		(start -254.505137 18.69186)
		(end -251.47746 18.69186)
		(width 0.10668)
		(layer "B.Cu")
		(net "SAS_B1_RX5N")
	)
	(segment
		(start -253.0802 34.7218)
		(end -253.176141 34.7218)
		(width 0.10668)
		(layer "B.Cu")
		(net "SAS_B1_RX5N")
	)
	(segment
		(start -251.10154 19.06778)
		(end -251.10154 25.637289)
		(width 0.10668)
		(layer "B.Cu")
		(net "SAS_B1_RX5N")
	)
	(segment
		(start -254.850001 16.039371)
		(end -254.627929 16.453904)
		(width 0.10668)
		(layer "B.Cu")
		(net "SAS_B1_RX5N")
	)
	(segment
		(start -251.779695 27.274495)
		(end -252.623 28.1178)
		(width 0.10668)
		(layer "B.Cu")
		(net "SAS_B1_RX5N")
	)
	(segment
		(start -254.822193 16.70526)
		(end -255.016315 16.899382)
		(width 0.10668)
		(layer "B.Cu")
		(net "SAS_B1_RX5N")
	)
	(segment
		(start -254.671591 16.598318)
		(end -254.671637 16.598341)
		(width 0.10668)
		(layer "B.Cu")
		(net "SAS_B1_RX5N")
	)
	(arc
		(start -255.3916 17.8054)
		(mid -255.131961 18.432223)
		(end -254.505137 18.69186)
		(width 0.10668)
		(layer "B.Cu")
		(net "SAS_B1_RX5N")
	)
	(arc
		(start -253.176141 34.7218)
		(mid -253.223446 34.722993)
		(end -253.270631 34.72657)
		(width 0.10668)
		(layer "B.Cu")
		(net "SAS_B1_RX5N")
	)
	(arc
		(start -252.623 28.1178)
		(mid -252.810987 28.399143)
		(end -252.877 28.731009)
		(width 0.10668)
		(layer "B.Cu")
		(net "SAS_B1_RX5N")
	)
	(arc
		(start -251.10154 25.637289)
		(mid -251.277787 26.523339)
		(end -251.779695 27.274495)
		(width 0.10668)
		(layer "B.Cu")
		(net "SAS_B1_RX5N")
	)
	(arc
		(start -253.270631 34.72657)
		(mid -253.557473 34.632455)
		(end -253.679998 34.356548)
		(width 0.10668)
		(layer "B.Cu")
		(net "SAS_B1_RX5N")
	)
	(arc
		(start -251.47746 18.69186)
		(mid -251.211644 18.801964)
		(end -251.10154 19.06778)
		(width 0.10668)
		(layer "B.Cu")
		(net "SAS_B1_RX5N")
	)
	(arc
		(start -254.627929 16.453904)
		(mid -254.61985 16.535152)
		(end -254.671589 16.598316)
		(width 0.10668)
		(layer "B.Cu")
		(net "SAS_B1_RX5N")
	)
	(arc
		(start -254.695112 16.610919)
		(mid -254.762121 16.653417)
		(end -254.822193 16.70526)
		(width 0.10668)
		(layer "B.Cu")
		(net "SAS_B1_RX5N")
	)
	(arc
		(start -252.877 34.5186)
		(mid -252.936516 34.662284)
		(end -253.0802 34.7218)
		(width 0.10668)
		(layer "B.Cu")
		(net "SAS_B1_RX5N")
	)
	(arc
		(start -255.016315 16.899382)
		(mid -255.294067 17.315067)
		(end -255.3916 17.8054)
		(width 0.10668)
		(layer "B.Cu")
		(net "SAS_B1_RX5N")
	)
	(segment
		(start -245.350002 13.639371)
		(end -245.572072 13.22484)
		(width 0.10668)
		(layer "B.Cu")
		(net "SAS_B1_RX4P")
	)
	(segment
		(start -245.716486 13.181183)
		(end -245.810522 13.231559)
		(width 0.10668)
		(layer "B.Cu")
		(net "SAS_B1_RX4P")
	)
	(segment
		(start -250.19 31.877)
		(end -250.19 32.258)
		(width 0.10668)
		(layer "B.Cu")
		(net "SAS_B1_RX4P")
	)
	(segment
		(start -250.46686 29.338344)
		(end -250.46686 31.61792)
		(width 0.10668)
		(layer "B.Cu")
		(net "SAS_B1_RX4P")
	)
	(segment
		(start -250.317 32.385)
		(end -250.36018 32.385)
		(width 0.10668)
		(layer "B.Cu")
		(net "SAS_B1_RX4P")
	)
	(segment
		(start -251.2314 40.69334)
		(end -251.4557 40.69334)
		(width 0.10668)
		(layer "B.Cu")
		(net "SAS_B1_RX4P")
	)
	(segment
		(start -245.716483 13.181183)
		(end -245.716486 13.181183)
		(width 0.10668)
		(layer "B.Cu")
		(net "SAS_B1_RX4P")
	)
	(segment
		(start -246.893344 13.94714)
		(end -247.64206 13.94714)
		(width 0.10668)
		(layer "B.Cu")
		(net "SAS_B1_RX4P")
	)
	(segment
		(start -250.46686 32.49168)
		(end -250.46686 39.96576)
		(width 0.10668)
		(layer "B.Cu")
		(net "SAS_B1_RX4P")
	)
	(segment
		(start -251.68 40.91764)
		(end -251.68 41.160002)
		(width 0.10668)
		(layer "B.Cu")
		(net "SAS_B1_RX4P")
	)
	(segment
		(start -248.262115 14.203975)
		(end -248.3431 14.28496)
		(width 0.10668)
		(layer "B.Cu")
		(net "SAS_B1_RX4P")
	)
	(segment
		(start -249.2448 16.461857)
		(end -249.2448 27.077713)
		(width 0.10668)
		(layer "B.Cu")
		(net "SAS_B1_RX4P")
	)
	(segment
		(start -250.33478 31.75)
		(end -250.317 31.75)
		(width 0.10668)
		(layer "B.Cu")
		(net "SAS_B1_RX4P")
	)
	(segment
		(start -249.4915 27.6733)
		(end -249.97918 28.16098)
		(width 0.10668)
		(layer "B.Cu")
		(net "SAS_B1_RX4P")
	)
	(arc
		(start -250.36018 32.385)
		(mid -250.435614 32.416246)
		(end -250.46686 32.49168)
		(width 0.10668)
		(layer "B.Cu")
		(net "SAS_B1_RX4P")
	)
	(arc
		(start -251.1933 40.6922)
		(mid -251.212341 40.693055)
		(end -251.2314 40.69334)
		(width 0.10668)
		(layer "B.Cu")
		(net "SAS_B1_RX4P")
	)
	(arc
		(start -250.46686 31.61792)
		(mid -250.428175 31.711315)
		(end -250.33478 31.75)
		(width 0.10668)
		(layer "B.Cu")
		(net "SAS_B1_RX4P")
	)
	(arc
		(start -250.46686 39.96576)
		(mid -250.679629 40.479431)
		(end -251.1933 40.6922)
		(width 0.10668)
		(layer "B.Cu")
		(net "SAS_B1_RX4P")
	)
	(arc
		(start -245.810522 13.231559)
		(mid -245.847312 13.260253)
		(end -245.872381 13.299603)
		(width 0.10668)
		(layer "B.Cu")
		(net "SAS_B1_RX4P")
	)
	(arc
		(start -245.572072 13.22484)
		(mid -245.635236 13.173103)
		(end -245.716483 13.181183)
		(width 0.10668)
		(layer "B.Cu")
		(net "SAS_B1_RX4P")
	)
	(arc
		(start -248.3431 14.28496)
		(mid -249.010456 15.283729)
		(end -249.2448 16.461857)
		(width 0.10668)
		(layer "B.Cu")
		(net "SAS_B1_RX4P")
	)
	(arc
		(start -250.317 31.75)
		(mid -250.227197 31.787197)
		(end -250.19 31.877)
		(width 0.10668)
		(layer "B.Cu")
		(net "SAS_B1_RX4P")
	)
	(arc
		(start -247.64206 13.94714)
		(mid -247.977631 14.013889)
		(end -248.262115 14.203975)
		(width 0.10668)
		(layer "B.Cu")
		(net "SAS_B1_RX4P")
	)
	(arc
		(start -245.872381 13.299603)
		(mid -246.281124 13.783782)
		(end -246.893344 13.94714)
		(width 0.10668)
		(layer "B.Cu")
		(net "SAS_B1_RX4P")
	)
	(arc
		(start -250.19 32.258)
		(mid -250.227197 32.347803)
		(end -250.317 32.385)
		(width 0.10668)
		(layer "B.Cu")
		(net "SAS_B1_RX4P")
	)
	(arc
		(start -251.4557 40.69334)
		(mid -251.614304 40.759036)
		(end -251.68 40.91764)
		(width 0.10668)
		(layer "B.Cu")
		(net "SAS_B1_RX4P")
	)
	(arc
		(start -249.2448 27.077713)
		(mid -249.308915 27.400042)
		(end -249.4915 27.6733)
		(width 0.10668)
		(layer "B.Cu")
		(net "SAS_B1_RX4P")
	)
	(arc
		(start -249.97918 28.16098)
		(mid -250.340116 28.701159)
		(end -250.46686 29.338344)
		(width 0.10668)
		(layer "B.Cu")
		(net "SAS_B1_RX4P")
	)
	(segment
		(start -249.67914 27.077716)
		(end -249.67914 16.461857)
		(width 0.10668)
		(layer "B.Cu")
		(net "SAS_B1_RX4N")
	)
	(segment
		(start -245.877928 12.653904)
		(end -246.100001 12.239371)
		(width 0.10668)
		(layer "B.Cu")
		(net "SAS_B1_RX4N")
	)
	(segment
		(start -251.68 39.760002)
		(end -251.68 39.7796)
		(width 0.10668)
		(layer "B.Cu")
		(net "SAS_B1_RX4N")
	)
	(segment
		(start -245.921591 12.798318)
		(end -245.921588 12.798316)
		(width 0.10668)
		(layer "B.Cu")
		(net "SAS_B1_RX4N")
	)
	(segment
		(start -248.650227 13.977833)
		(end -248.569241 13.896848)
		(width 0.10668)
		(layer "B.Cu")
		(net "SAS_B1_RX4N")
	)
	(segment
		(start -250.9012 39.940581)
		(end -250.9012 29.248384)
		(width 0.10668)
		(layer "B.Cu")
		(net "SAS_B1_RX4N")
	)
	(segment
		(start -247.642063 13.5128)
		(end -246.8826 13.5128)
		(width 0.10668)
		(layer "B.Cu")
		(net "SAS_B1_RX4N")
	)
	(segment
		(start -246.015627 12.848694)
		(end -245.921591 12.798318)
		(width 0.10668)
		(layer "B.Cu")
		(net "SAS_B1_RX4N")
	)
	(segment
		(start -250.349913 27.91746)
		(end -249.798627 27.366173)
		(width 0.10668)
		(layer "B.Cu")
		(net "SAS_B1_RX4N")
	)
	(arc
		(start -249.798627 27.366173)
		(mid -249.710196 27.233828)
		(end -249.67914 27.077716)
		(width 0.10668)
		(layer "B.Cu")
		(net "SAS_B1_RX4N")
	)
	(arc
		(start -246.8826 13.5128)
		(mid -246.517245 13.419188)
		(end -246.273 13.1318)
		(width 0.10668)
		(layer "B.Cu")
		(net "SAS_B1_RX4N")
	)
	(arc
		(start -249.67914 16.461857)
		(mid -249.411735 15.117514)
		(end -248.650227 13.977833)
		(width 0.10668)
		(layer "B.Cu")
		(net "SAS_B1_RX4N")
	)
	(arc
		(start -246.273 13.1318)
		(mid -246.168697 12.96808)
		(end -246.015627 12.848694)
		(width 0.10668)
		(layer "B.Cu")
		(net "SAS_B1_RX4N")
	)
	(arc
		(start -251.68 39.7796)
		(mid -251.54612 40.111926)
		(end -251.219256 40.258637)
		(width 0.10668)
		(layer "B.Cu")
		(net "SAS_B1_RX4N")
	)
	(arc
		(start -245.921588 12.798316)
		(mid -245.869849 12.735152)
		(end -245.877928 12.653904)
		(width 0.10668)
		(layer "B.Cu")
		(net "SAS_B1_RX4N")
	)
	(arc
		(start -251.219256 40.258637)
		(mid -250.994356 40.165481)
		(end -250.9012 39.940581)
		(width 0.10668)
		(layer "B.Cu")
		(net "SAS_B1_RX4N")
	)
	(arc
		(start -248.569241 13.896848)
		(mid -248.143848 13.612611)
		(end -247.642063 13.5128)
		(width 0.10668)
		(layer "B.Cu")
		(net "SAS_B1_RX4N")
	)
	(arc
		(start -250.9012 29.248384)
		(mid -250.757925 28.528093)
		(end -250.349913 27.91746)
		(width 0.10668)
		(layer "B.Cu")
		(net "SAS_B1_RX4N")
	)
	(segment
		(start -246.133079 46.7106)
		(end -248.2161 46.7106)
		(width 0.11176)
		(layer "In5.Cu")
		(net "SAS_B1_RX3P")
	)
	(segment
		(start -244.308757 45.889357)
		(end -244.420715 46.001315)
		(width 0.11176)
		(layer "In5.Cu")
		(net "SAS_B1_RX3P")
	)
	(segment
		(start -244.12702 45.91304)
		(end -244.150703 45.889357)
		(width 0.11176)
		(layer "In5.Cu")
		(net "SAS_B1_RX3P")
	)
	(segment
		(start -242.026806 43.607406)
		(end -242.311743 43.892343)
		(width 0.11176)
		(layer "In5.Cu")
		(net "SAS_B1_RX3P")
	)
	(segment
		(start -241.435392 43.015992)
		(end -241.435392 43.328092)
		(width 0.11176)
		(layer "In5.Cu")
		(net "SAS_B1_RX3P")
	)
	(segment
		(start -245.79325 16.970439)
		(end -245.79327 16.970449)
		(width 0.11176)
		(layer "In5.Cu")
		(net "SAS_B1_RX3P")
	)
	(segment
		(start -243.586823 45.325477)
		(end -243.57838 45.33392)
		(width 0.11176)
		(layer "In5.Cu")
		(net "SAS_B1_RX3P")
	)
	(segment
		(start -242.307397 44.212797)
		(end -242.71732 44.62272)
		(width 0.11176)
		(layer "In5.Cu")
		(net "SAS_B1_RX3P")
	)
	(segment
		(start -249.680001 44.059701)
		(end -249.680001 44.060001)
		(width 0.11176)
		(layer "In5.Cu")
		(net "SAS_B1_RX3P")
	)
	(segment
		(start -242.311743 44.050397)
		(end -242.307397 44.054743)
		(width 0.11176)
		(layer "In5.Cu")
		(net "SAS_B1_RX3P")
	)
	(segment
		(start -242.8494 44.62272)
		(end -242.866733 44.605387)
		(width 0.11176)
		(layer "In5.Cu")
		(net "SAS_B1_RX3P")
	)
	(segment
		(start -239.6744 19.07032)
		(end -239.6744 39.340861)
		(width 0.11176)
		(layer "In5.Cu")
		(net "SAS_B1_RX3P")
	)
	(segment
		(start -243.024787 44.605387)
		(end -243.586823 45.167423)
		(width 0.11176)
		(layer "In5.Cu")
		(net "SAS_B1_RX3P")
	)
	(segment
		(start -245.824875 17.00644)
		(end -246.096381 17.277946)
		(width 0.11176)
		(layer "In5.Cu")
		(net "SAS_B1_RX3P")
	)
	(segment
		(start -245.56942 18.27784)
		(end -240.46688 18.27784)
		(width 0.11176)
		(layer "In5.Cu")
		(net "SAS_B1_RX3P")
	)
	(segment
		(start -241.0279 42.6085)
		(end -241.435392 43.015992)
		(width 0.11176)
		(layer "In5.Cu")
		(net "SAS_B1_RX3P")
	)
	(segment
		(start -245.79323 16.970426)
		(end -245.793237 16.970431)
		(width 0.11176)
		(layer "In5.Cu")
		(net "SAS_B1_RX3P")
	)
	(segment
		(start -245.742557 16.943278)
		(end -245.79323 16.970426)
		(width 0.11176)
		(layer "In5.Cu")
		(net "SAS_B1_RX3P")
	)
	(segment
		(start -245.742554 16.943276)
		(end -245.742557 16.943278)
		(width 0.11176)
		(layer "In5.Cu")
		(net "SAS_B1_RX3P")
	)
	(segment
		(start -245.793237 16.970431)
		(end -245.79325 16.970439)
		(width 0.11176)
		(layer "In5.Cu")
		(net "SAS_B1_RX3P")
	)
	(segment
		(start -241.714706 43.607406)
		(end -242.026806 43.607406)
		(width 0.11176)
		(layer "In5.Cu")
		(net "SAS_B1_RX3P")
	)
	(segment
		(start -248.8511 46.0756)
		(end -248.8511 43.815)
		(width 0.11176)
		(layer "In5.Cu")
		(net "SAS_B1_RX3P")
	)
	(segment
		(start -245.350002 17.439371)
		(end -245.591264 16.989016)
		(width 0.11176)
		(layer "In5.Cu")
		(net "SAS_B1_RX3P")
	)
	(segment
		(start -243.57838 45.48378)
		(end -244.00764 45.91304)
		(width 0.11176)
		(layer "In5.Cu")
		(net "SAS_B1_RX3P")
	)
	(segment
		(start -241.435392 43.328092)
		(end -241.714706 43.607406)
		(width 0.11176)
		(layer "In5.Cu")
		(net "SAS_B1_RX3P")
	)
	(arc
		(start -246.096381 17.277946)
		(mid -246.198899 17.431377)
		(end -246.234897 17.61236)
		(width 0.11176)
		(layer "In5.Cu")
		(net "SAS_B1_RX3P")
	)
	(arc
		(start -244.420715 46.001315)
		(mid -245.206354 46.526262)
		(end -246.133079 46.7106)
		(width 0.11176)
		(layer "In5.Cu")
		(net "SAS_B1_RX3P")
	)
	(arc
		(start -245.793273 16.970451)
		(mid -245.80927 16.988273)
		(end -245.824875 17.00644)
		(width 0.11176)
		(layer "In5.Cu")
		(net "SAS_B1_RX3P")
	)
	(arc
		(start -245.591264 16.989016)
		(mid -245.657436 16.934813)
		(end -245.742554 16.943276)
		(width 0.11176)
		(layer "In5.Cu")
		(net "SAS_B1_RX3P")
	)
	(arc
		(start -244.00764 45.91304)
		(mid -244.06733 45.937764)
		(end -244.12702 45.91304)
		(width 0.11176)
		(layer "In5.Cu")
		(net "SAS_B1_RX3P")
	)
	(arc
		(start -242.71732 44.62272)
		(mid -242.78336 44.650075)
		(end -242.8494 44.62272)
		(width 0.11176)
		(layer "In5.Cu")
		(net "SAS_B1_RX3P")
	)
	(arc
		(start -243.586823 45.167423)
		(mid -243.619558 45.24645)
		(end -243.586823 45.325477)
		(width 0.11176)
		(layer "In5.Cu")
		(net "SAS_B1_RX3P")
	)
	(arc
		(start -245.79327 16.970449)
		(mid -245.793271 16.97045)
		(end -245.793273 16.970451)
		(width 0.11176)
		(layer "In5.Cu")
		(net "SAS_B1_RX3P")
	)
	(arc
		(start -248.2161 46.7106)
		(mid -248.665113 46.524613)
		(end -248.8511 46.0756)
		(width 0.11176)
		(layer "In5.Cu")
		(net "SAS_B1_RX3P")
	)
	(arc
		(start -239.6744 39.340861)
		(mid -240.026163 41.109294)
		(end -241.0279 42.6085)
		(width 0.11176)
		(layer "In5.Cu")
		(net "SAS_B1_RX3P")
	)
	(arc
		(start -246.234897 17.61236)
		(mid -246.039983 18.082924)
		(end -245.56942 18.27784)
		(width 0.11176)
		(layer "In5.Cu")
		(net "SAS_B1_RX3P")
	)
	(arc
		(start -242.866733 44.605387)
		(mid -242.94576 44.572652)
		(end -243.024787 44.605387)
		(width 0.11176)
		(layer "In5.Cu")
		(net "SAS_B1_RX3P")
	)
	(arc
		(start -242.311743 43.892343)
		(mid -242.344478 43.97137)
		(end -242.311743 44.050397)
		(width 0.11176)
		(layer "In5.Cu")
		(net "SAS_B1_RX3P")
	)
	(arc
		(start -244.150703 45.889357)
		(mid -244.22973 45.856622)
		(end -244.308757 45.889357)
		(width 0.11176)
		(layer "In5.Cu")
		(net "SAS_B1_RX3P")
	)
	(arc
		(start -249.1432 43.5229)
		(mid -249.522776 43.680125)
		(end -249.680001 44.059701)
		(width 0.11176)
		(layer "In5.Cu")
		(net "SAS_B1_RX3P")
	)
	(arc
		(start -242.307397 44.054743)
		(mid -242.274662 44.13377)
		(end -242.307397 44.212797)
		(width 0.11176)
		(layer "In5.Cu")
		(net "SAS_B1_RX3P")
	)
	(arc
		(start -240.46688 18.27784)
		(mid -239.906512 18.509952)
		(end -239.6744 19.07032)
		(width 0.11176)
		(layer "In5.Cu")
		(net "SAS_B1_RX3P")
	)
	(arc
		(start -243.57838 45.33392)
		(mid -243.547343 45.40885)
		(end -243.57838 45.48378)
		(width 0.11176)
		(layer "In5.Cu")
		(net "SAS_B1_RX3P")
	)
	(arc
		(start -248.8511 43.815)
		(mid -248.936654 43.608454)
		(end -249.1432 43.5229)
		(width 0.11176)
		(layer "In5.Cu")
		(net "SAS_B1_RX3P")
	)
	(segment
		(start -246.100001 16.039371)
		(end -245.858739 16.489728)
		(width 0.11176)
		(layer "In5.Cu")
		(net "SAS_B1_RX3N")
	)
	(segment
		(start -245.56942 18.62074)
		(end -240.46688 18.62074)
		(width 0.11176)
		(layer "In5.Cu")
		(net "SAS_B1_RX3N")
	)
	(segment
		(start -248.5082 46.0756)
		(end -248.5082 43.815)
		(width 0.11176)
		(layer "In5.Cu")
		(net "SAS_B1_RX3N")
	)
	(segment
		(start -245.904479 16.641018)
		(end -245.904487 16.641023)
		(width 0.11176)
		(layer "In5.Cu")
		(net "SAS_B1_RX3N")
	)
	(segment
		(start -245.904476 16.641018)
		(end -245.904479 16.641018)
		(width 0.11176)
		(layer "In5.Cu")
		(net "SAS_B1_RX3N")
	)
	(segment
		(start -240.0173 19.07032)
		(end -240.0173 39.340864)
		(width 0.11176)
		(layer "In5.Cu")
		(net "SAS_B1_RX3N")
	)
	(segment
		(start -241.270368 42.366032)
		(end -244.663184 45.758847)
		(width 0.11176)
		(layer "In5.Cu")
		(net "SAS_B1_RX3N")
	)
	(segment
		(start -245.904487 16.641023)
		(end -246.002993 16.693794)
		(width 0.11176)
		(layer "In5.Cu")
		(net "SAS_B1_RX3N")
	)
	(segment
		(start -246.133082 46.3677)
		(end -248.2161 46.3677)
		(width 0.11176)
		(layer "In5.Cu")
		(net "SAS_B1_RX3N")
	)
	(segment
		(start -246.077133 16.773764)
		(end -246.338849 17.03548)
		(width 0.11176)
		(layer "In5.Cu")
		(net "SAS_B1_RX3N")
	)
	(segment
		(start -249.1432 43.18)
		(end -249.160002 43.18)
		(width 0.11176)
		(layer "In5.Cu")
		(net "SAS_B1_RX3N")
	)
	(arc
		(start -246.5778 17.61236)
		(mid -246.282452 18.325392)
		(end -245.56942 18.62074)
		(width 0.11176)
		(layer "In5.Cu")
		(net "SAS_B1_RX3N")
	)
	(arc
		(start -245.858739 16.489728)
		(mid -245.850275 16.574845)
		(end -245.904476 16.641018)
		(width 0.11176)
		(layer "In5.Cu")
		(net "SAS_B1_RX3N")
	)
	(arc
		(start -244.663184 45.758847)
		(mid -245.337579 46.209464)
		(end -246.133082 46.3677)
		(width 0.11176)
		(layer "In5.Cu")
		(net "SAS_B1_RX3N")
	)
	(arc
		(start -248.2161 46.3677)
		(mid -248.422646 46.282146)
		(end -248.5082 46.0756)
		(width 0.11176)
		(layer "In5.Cu")
		(net "SAS_B1_RX3N")
	)
	(arc
		(start -246.045952 16.738646)
		(mid -246.061685 16.756078)
		(end -246.077133 16.773764)
		(width 0.11176)
		(layer "In5.Cu")
		(net "SAS_B1_RX3N")
	)
	(arc
		(start -248.5082 43.815)
		(mid -248.694187 43.365987)
		(end -249.1432 43.18)
		(width 0.11176)
		(layer "In5.Cu")
		(net "SAS_B1_RX3N")
	)
	(arc
		(start -249.160002 43.18)
		(mid -249.527697 43.027696)
		(end -249.680001 42.660001)
		(width 0.11176)
		(layer "In5.Cu")
		(net "SAS_B1_RX3N")
	)
	(arc
		(start -240.0173 39.340864)
		(mid -240.342963 40.978073)
		(end -241.270368 42.366032)
		(width 0.11176)
		(layer "In5.Cu")
		(net "SAS_B1_RX3N")
	)
	(arc
		(start -240.46688 18.62074)
		(mid -240.148979 18.752419)
		(end -240.0173 19.07032)
		(width 0.11176)
		(layer "In5.Cu")
		(net "SAS_B1_RX3N")
	)
	(arc
		(start -246.002993 16.693794)
		(mid -246.024714 16.715989)
		(end -246.045952 16.738646)
		(width 0.11176)
		(layer "In5.Cu")
		(net "SAS_B1_RX3N")
	)
	(arc
		(start -246.338849 17.03548)
		(mid -246.515699 17.300155)
		(end -246.5778 17.61236)
		(width 0.11176)
		(layer "In5.Cu")
		(net "SAS_B1_RX3N")
	)
	(segment
		(start -247.46966 22.621593)
		(end -247.46966 15.81912)
		(width 0.10668)
		(layer "B.Cu")
		(net "SAS_B1_RX2P")
	)
	(segment
		(start -243.490006 13.193784)
		(end -243.466506 13.181195)
		(width 0.10668)
		(layer "B.Cu")
		(net "SAS_B1_RX2P")
	)
	(segment
		(start -247.5938 31.2166)
		(end -247.5938 30.9172)
		(width 0.10668)
		(layer "B.Cu")
		(net "SAS_B1_RX2P")
	)
	(segment
		(start -247.777 30.734)
		(end -247.81478 30.734)
		(width 0.10668)
		(layer "B.Cu")
		(net "SAS_B1_RX2P")
	)
	(segment
		(start -246.78894 15.1384)
		(end -244.9957 15.1384)
		(width 0.10668)
		(layer "B.Cu")
		(net "SAS_B1_RX2P")
	)
	(segment
		(start -248.48026 33.436834)
		(end -248.48026 33.165491)
		(width 0.10668)
		(layer "B.Cu")
		(net "SAS_B1_RX2P")
	)
	(segment
		(start -243.466506 13.181195)
		(end -243.466485 13.181185)
		(width 0.10668)
		(layer "B.Cu")
		(net "SAS_B1_RX2P")
	)
	(segment
		(start -247.92146 28.956)
		(end -247.92146 23.712333)
		(width 0.10668)
		(layer "B.Cu")
		(net "SAS_B1_RX2P")
	)
	(segment
		(start -249.680001 35.66)
		(end -249.680001 35.642141)
		(width 0.10668)
		(layer "B.Cu")
		(net "SAS_B1_RX2P")
	)
	(segment
		(start -247.769276 23.344924)
		(end -247.769273 23.344922)
		(width 0.10668)
		(layer "B.Cu")
		(net "SAS_B1_RX2P")
	)
	(segment
		(start -247.92146 30.62732)
		(end -247.92146 29.81706)
		(width 0.10668)
		(layer "B.Cu")
		(net "SAS_B1_RX2P")
	)
	(segment
		(start -243.322071 13.22484)
		(end -243.100001 13.639371)
		(width 0.10668)
		(layer "B.Cu")
		(net "SAS_B1_RX2P")
	)
	(segment
		(start -247.92146 31.816426)
		(end -247.92146 31.54426)
		(width 0.10668)
		(layer "B.Cu")
		(net "SAS_B1_RX2P")
	)
	(segment
		(start -249.2194 35.18154)
		(end -249.0924 35.18154)
		(width 0.10668)
		(layer "B.Cu")
		(net "SAS_B1_RX2P")
	)
	(segment
		(start -247.777 29.083)
		(end -247.79446 29.083)
		(width 0.10668)
		(layer "B.Cu")
		(net "SAS_B1_RX2P")
	)
	(segment
		(start -243.466485 13.181185)
		(end -243.466485 13.181183)
		(width 0.10668)
		(layer "B.Cu")
		(net "SAS_B1_RX2P")
	)
	(segment
		(start -248.48026 34.238834)
		(end -248.285 34.043574)
		(width 0.10668)
		(layer "B.Cu")
		(net "SAS_B1_RX2P")
	)
	(segment
		(start -243.70095 13.398271)
		(end -243.515068 13.212387)
		(width 0.10668)
		(layer "B.Cu")
		(net "SAS_B1_RX2P")
	)
	(segment
		(start -247.5938 29.4894)
		(end -247.5938 29.2662)
		(width 0.10668)
		(layer "B.Cu")
		(net "SAS_B1_RX2P")
	)
	(segment
		(start -243.8273 13.97)
		(end -243.8273 13.703303)
		(width 0.10668)
		(layer "B.Cu")
		(net "SAS_B1_RX2P")
	)
	(segment
		(start -248.285 33.632094)
		(end -248.48026 33.436834)
		(width 0.10668)
		(layer "B.Cu")
		(net "SAS_B1_RX2P")
	)
	(segment
		(start -243.466485 13.181183)
		(end -243.466483 13.181183)
		(width 0.10668)
		(layer "B.Cu")
		(net "SAS_B1_RX2P")
	)
	(segment
		(start -248.48026 34.5694)
		(end -248.48026 34.238834)
		(width 0.10668)
		(layer "B.Cu")
		(net "SAS_B1_RX2P")
	)
	(segment
		(start -248.285 34.043574)
		(end -248.285 33.632094)
		(width 0.10668)
		(layer "B.Cu")
		(net "SAS_B1_RX2P")
	)
	(arc
		(start -247.92146 31.54426)
		(mid -247.877567 31.438293)
		(end -247.7716 31.3944)
		(width 0.10668)
		(layer "B.Cu")
		(net "SAS_B1_RX2P")
	)
	(arc
		(start -247.92146 23.712333)
		(mid -247.881909 23.513493)
		(end -247.769276 23.344924)
		(width 0.10668)
		(layer "B.Cu")
		(net "SAS_B1_RX2P")
	)
	(arc
		(start -248.48026 33.165491)
		(mid -248.453911 33.033025)
		(end -248.378873 32.920727)
		(width 0.10668)
		(layer "B.Cu")
		(net "SAS_B1_RX2P")
	)
	(arc
		(start -243.466483 13.181183)
		(mid -243.385236 13.173104)
		(end -243.322071 13.22484)
		(width 0.10668)
		(layer "B.Cu")
		(net "SAS_B1_RX2P")
	)
	(arc
		(start -243.8273 13.703303)
		(mid -243.794463 13.53822)
		(end -243.70095 13.398271)
		(width 0.10668)
		(layer "B.Cu")
		(net "SAS_B1_RX2P")
	)
	(arc
		(start -244.9957 15.1384)
		(mid -244.169516 14.796184)
		(end -243.8273 13.97)
		(width 0.10668)
		(layer "B.Cu")
		(net "SAS_B1_RX2P")
	)
	(arc
		(start -243.515068 13.212387)
		(mid -243.503221 13.202164)
		(end -243.490006 13.193784)
		(width 0.10668)
		(layer "B.Cu")
		(net "SAS_B1_RX2P")
	)
	(arc
		(start -247.5938 30.9172)
		(mid -247.647458 30.787658)
		(end -247.777 30.734)
		(width 0.10668)
		(layer "B.Cu")
		(net "SAS_B1_RX2P")
	)
	(arc
		(start -248.378873 32.920727)
		(mid -248.040336 32.414069)
		(end -247.92146 31.816426)
		(width 0.10668)
		(layer "B.Cu")
		(net "SAS_B1_RX2P")
	)
	(arc
		(start -247.79446 29.083)
		(mid -247.884263 29.045803)
		(end -247.92146 28.956)
		(width 0.10668)
		(layer "B.Cu")
		(net "SAS_B1_RX2P")
	)
	(arc
		(start -249.0924 35.18154)
		(mid -248.659552 35.002248)
		(end -248.48026 34.5694)
		(width 0.10668)
		(layer "B.Cu")
		(net "SAS_B1_RX2P")
	)
	(arc
		(start -247.5938 29.2662)
		(mid -247.647458 29.136658)
		(end -247.777 29.083)
		(width 0.10668)
		(layer "B.Cu")
		(net "SAS_B1_RX2P")
	)
	(arc
		(start -249.680001 35.642141)
		(mid -249.545094 35.316447)
		(end -249.2194 35.18154)
		(width 0.10668)
		(layer "B.Cu")
		(net "SAS_B1_RX2P")
	)
	(arc
		(start -247.46966 15.81912)
		(mid -247.270282 15.337778)
		(end -246.78894 15.1384)
		(width 0.10668)
		(layer "B.Cu")
		(net "SAS_B1_RX2P")
	)
	(arc
		(start -247.769273 23.344922)
		(mid -247.547527 23.013056)
		(end -247.46966 22.621593)
		(width 0.10668)
		(layer "B.Cu")
		(net "SAS_B1_RX2P")
	)
	(arc
		(start -247.7716 29.6672)
		(mid -247.645876 29.615124)
		(end -247.5938 29.4894)
		(width 0.10668)
		(layer "B.Cu")
		(net "SAS_B1_RX2P")
	)
	(arc
		(start -247.7716 31.3944)
		(mid -247.645876 31.342324)
		(end -247.5938 31.2166)
		(width 0.10668)
		(layer "B.Cu")
		(net "SAS_B1_RX2P")
	)
	(arc
		(start -247.81478 30.734)
		(mid -247.890214 30.702754)
		(end -247.92146 30.62732)
		(width 0.10668)
		(layer "B.Cu")
		(net "SAS_B1_RX2P")
	)
	(arc
		(start -247.92146 29.81706)
		(mid -247.877567 29.711093)
		(end -247.7716 29.6672)
		(width 0.10668)
		(layer "B.Cu")
		(net "SAS_B1_RX2P")
	)
	(segment
		(start -248.9146 34.5694)
		(end -248.9146 33.165489)
		(width 0.10668)
		(layer "B.Cu")
		(net "SAS_B1_RX2N")
	)
	(segment
		(start -247.904 22.621591)
		(end -247.904 15.81912)
		(width 0.10668)
		(layer "B.Cu")
		(net "SAS_B1_RX2N")
	)
	(segment
		(start -243.671636 12.798341)
		(end -243.67159 12.798318)
		(width 0.10668)
		(layer "B.Cu")
		(net "SAS_B1_RX2N")
	)
	(segment
		(start -243.627928 12.653904)
		(end -243.85 12.239371)
		(width 0.10668)
		(layer "B.Cu")
		(net "SAS_B1_RX2N")
	)
	(segment
		(start -246.78894 14.70406)
		(end -244.9957 14.70406)
		(width 0.10668)
		(layer "B.Cu")
		(net "SAS_B1_RX2N")
	)
	(segment
		(start -244.008077 13.091145)
		(end -243.822192 12.90526)
		(width 0.10668)
		(layer "B.Cu")
		(net "SAS_B1_RX2N")
	)
	(segment
		(start -243.67159 12.798318)
		(end -243.671588 12.798316)
		(width 0.10668)
		(layer "B.Cu")
		(net "SAS_B1_RX2N")
	)
	(segment
		(start -243.695111 12.810919)
		(end -243.671636 12.798341)
		(width 0.10668)
		(layer "B.Cu")
		(net "SAS_B1_RX2N")
	)
	(segment
		(start -249.2194 34.7472)
		(end -249.0924 34.7472)
		(width 0.10668)
		(layer "B.Cu")
		(net "SAS_B1_RX2N")
	)
	(segment
		(start -249.680001 34.26)
		(end -249.680001 34.286599)
		(width 0.10668)
		(layer "B.Cu")
		(net "SAS_B1_RX2N")
	)
	(segment
		(start -244.26164 13.97)
		(end -244.26164 13.7033)
		(width 0.10668)
		(layer "B.Cu")
		(net "SAS_B1_RX2N")
	)
	(segment
		(start -248.3558 31.816426)
		(end -248.3558 23.71233)
		(width 0.10668)
		(layer "B.Cu")
		(net "SAS_B1_RX2N")
	)
	(arc
		(start -243.822192 12.90526)
		(mid -243.76212 12.853418)
		(end -243.695111 12.810919)
		(width 0.10668)
		(layer "B.Cu")
		(net "SAS_B1_RX2N")
	)
	(arc
		(start -248.686 32.6136)
		(mid -248.441616 32.247853)
		(end -248.3558 31.816426)
		(width 0.10668)
		(layer "B.Cu")
		(net "SAS_B1_RX2N")
	)
	(arc
		(start -248.9146 33.165489)
		(mid -248.855189 32.866809)
		(end -248.686 32.6136)
		(width 0.10668)
		(layer "B.Cu")
		(net "SAS_B1_RX2N")
	)
	(arc
		(start -243.671588 12.798316)
		(mid -243.619849 12.735152)
		(end -243.627928 12.653904)
		(width 0.10668)
		(layer "B.Cu")
		(net "SAS_B1_RX2N")
	)
	(arc
		(start -248.0764 23.0378)
		(mid -247.948806 22.846842)
		(end -247.904 22.621591)
		(width 0.10668)
		(layer "B.Cu")
		(net "SAS_B1_RX2N")
	)
	(arc
		(start -244.9957 14.70406)
		(mid -244.476641 14.489059)
		(end -244.26164 13.97)
		(width 0.10668)
		(layer "B.Cu")
		(net "SAS_B1_RX2N")
	)
	(arc
		(start -249.0924 34.7472)
		(mid -248.966676 34.695124)
		(end -248.9146 34.5694)
		(width 0.10668)
		(layer "B.Cu")
		(net "SAS_B1_RX2N")
	)
	(arc
		(start -249.680001 34.286599)
		(mid -249.545094 34.612293)
		(end -249.2194 34.7472)
		(width 0.10668)
		(layer "B.Cu")
		(net "SAS_B1_RX2N")
	)
	(arc
		(start -247.904 15.81912)
		(mid -247.577406 15.030654)
		(end -246.78894 14.70406)
		(width 0.10668)
		(layer "B.Cu")
		(net "SAS_B1_RX2N")
	)
	(arc
		(start -244.26164 13.7033)
		(mid -244.195741 13.372004)
		(end -244.008077 13.091145)
		(width 0.10668)
		(layer "B.Cu")
		(net "SAS_B1_RX2N")
	)
	(arc
		(start -248.3558 23.71233)
		(mid -248.283186 23.347277)
		(end -248.0764 23.0378)
		(width 0.10668)
		(layer "B.Cu")
		(net "SAS_B1_RX2N")
	)
	(segment
		(start -237.63446 24.15285)
		(end -237.63446 29.593243)
		(width 0.10668)
		(layer "B.Cu")
		(net "SAS_B1_RX1P")
	)
	(segment
		(start -243.448159 18.23466)
		(end -240.67738 18.23466)
		(width 0.10668)
		(layer "B.Cu")
		(net "SAS_B1_RX1P")
	)
	(segment
		(start -243.90826 17.667879)
		(end -243.90826 17.774559)
		(width 0.10668)
		(layer "B.Cu")
		(net "SAS_B1_RX1P")
	)
	(segment
		(start -243.946553 39.359606)
		(end -244.221 39.634053)
		(width 0.10668)
		(layer "B.Cu")
		(net "SAS_B1_RX1P")
	)
	(segment
		(start -247.357405 40.837404)
		(end -247.68 41.160002)
		(width 0.10668)
		(layer "B.Cu")
		(net "SAS_B1_RX1P")
	)
	(segment
		(start -243.466485 16.981183)
		(end -243.466485 16.981185)
		(width 0.10668)
		(layer "B.Cu")
		(net "SAS_B1_RX1P")
	)
	(segment
		(start -243.466506 16.981195)
		(end -243.490006 16.993784)
		(width 0.10668)
		(layer "B.Cu")
		(net "SAS_B1_RX1P")
	)
	(segment
		(start -246.673037 40.69334)
		(end -247.0096 40.69334)
		(width 0.10668)
		(layer "B.Cu")
		(net "SAS_B1_RX1P")
	)
	(segment
		(start -243.946556 39.359606)
		(end -243.946553 39.359606)
		(width 0.10668)
		(layer "B.Cu")
		(net "SAS_B1_RX1P")
	)
	(segment
		(start -243.466483 16.981183)
		(end -243.466485 16.981183)
		(width 0.10668)
		(layer "B.Cu")
		(net "SAS_B1_RX1P")
	)
	(segment
		(start -238.676073 32.107927)
		(end -239.896023 33.327873)
		(width 0.10668)
		(layer "B.Cu")
		(net "SAS_B1_RX1P")
	)
	(segment
		(start -239.64106 19.27098)
		(end -239.641057 19.673768)
		(width 0.10668)
		(layer "B.Cu")
		(net "SAS_B1_RX1P")
	)
	(segment
		(start -244.221 40.0866)
		(end -244.3934 40.259)
		(width 0.10668)
		(layer "B.Cu")
		(net "SAS_B1_RX1P")
	)
	(segment
		(start -246.472377 40.894)
		(end -246.673037 40.69334)
		(width 0.10668)
		(layer "B.Cu")
		(net "SAS_B1_RX1P")
	)
	(segment
		(start -245.639808 40.69334)
		(end -245.936437 40.69334)
		(width 0.10668)
		(layer "B.Cu")
		(net "SAS_B1_RX1P")
	)
	(segment
		(start -243.466485 16.981185)
		(end -243.466506 16.981195)
		(width 0.10668)
		(layer "B.Cu")
		(net "SAS_B1_RX1P")
	)
	(segment
		(start -238.9578 21.3233)
		(end -238.69951 21.581588)
		(width 0.10668)
		(layer "B.Cu")
		(net "SAS_B1_RX1P")
	)
	(segment
		(start -243.515068 17.012387)
		(end -243.722784 17.220105)
		(width 0.10668)
		(layer "B.Cu")
		(net "SAS_B1_RX1P")
	)
	(segment
		(start -243.100001 17.439371)
		(end -243.322071 17.02484)
		(width 0.10668)
		(layer "B.Cu")
		(net "SAS_B1_RX1P")
	)
	(segment
		(start -245.936437 40.69334)
		(end -246.137097 40.894)
		(width 0.10668)
		(layer "B.Cu")
		(net "SAS_B1_RX1P")
	)
	(segment
		(start -244.845947 40.259)
		(end -245.026073 40.439127)
		(width 0.10668)
		(layer "B.Cu")
		(net "SAS_B1_RX1P")
	)
	(segment
		(start -241.296942 36.709993)
		(end -243.946556 39.359606)
		(width 0.10668)
		(layer "B.Cu")
		(net "SAS_B1_RX1P")
	)
	(segment
		(start -246.137097 40.894)
		(end -246.472377 40.894)
		(width 0.10668)
		(layer "B.Cu")
		(net "SAS_B1_RX1P")
	)
	(arc
		(start -243.90826 17.774559)
		(mid -243.7735 18.0999)
		(end -243.448159 18.23466)
		(width 0.10668)
		(layer "B.Cu")
		(net "SAS_B1_RX1P")
	)
	(arc
		(start -238.69951 21.581588)
		(mid -237.911257 22.761293)
		(end -237.63446 24.15285)
		(width 0.10668)
		(layer "B.Cu")
		(net "SAS_B1_RX1P")
	)
	(arc
		(start -244.729 40.259)
		(mid -244.787473 40.23478)
		(end -244.845947 40.259)
		(width 0.10668)
		(layer "B.Cu")
		(net "SAS_B1_RX1P")
	)
	(arc
		(start -244.3934 40.259)
		(mid -244.5612 40.328505)
		(end -244.729 40.259)
		(width 0.10668)
		(layer "B.Cu")
		(net "SAS_B1_RX1P")
	)
	(arc
		(start -247.0096 40.69334)
		(mid -247.197831 40.73078)
		(end -247.357405 40.837404)
		(width 0.10668)
		(layer "B.Cu")
		(net "SAS_B1_RX1P")
	)
	(arc
		(start -244.221 39.634053)
		(mid -244.271524 39.756027)
		(end -244.221 39.878)
		(width 0.10668)
		(layer "B.Cu")
		(net "SAS_B1_RX1P")
	)
	(arc
		(start -243.490006 16.993784)
		(mid -243.503221 17.002164)
		(end -243.515068 17.012387)
		(width 0.10668)
		(layer "B.Cu")
		(net "SAS_B1_RX1P")
	)
	(arc
		(start -240.199857 34.0614)
		(mid -240.484981 35.494808)
		(end -241.296942 36.709993)
		(width 0.10668)
		(layer "B.Cu")
		(net "SAS_B1_RX1P")
	)
	(arc
		(start -243.722784 17.220105)
		(mid -243.860056 17.425545)
		(end -243.90826 17.667879)
		(width 0.10668)
		(layer "B.Cu")
		(net "SAS_B1_RX1P")
	)
	(arc
		(start -240.67738 18.23466)
		(mid -239.944591 18.538191)
		(end -239.64106 19.27098)
		(width 0.10668)
		(layer "B.Cu")
		(net "SAS_B1_RX1P")
	)
	(arc
		(start -239.641057 19.673768)
		(mid -239.463484 20.566488)
		(end -238.9578 21.3233)
		(width 0.10668)
		(layer "B.Cu")
		(net "SAS_B1_RX1P")
	)
	(arc
		(start -237.63446 29.593243)
		(mid -237.905166 30.954179)
		(end -238.676073 32.107927)
		(width 0.10668)
		(layer "B.Cu")
		(net "SAS_B1_RX1P")
	)
	(arc
		(start -239.896023 33.327873)
		(mid -240.120894 33.664418)
		(end -240.199857 34.0614)
		(width 0.10668)
		(layer "B.Cu")
		(net "SAS_B1_RX1P")
	)
	(arc
		(start -245.026073 40.439127)
		(mid -245.307657 40.627274)
		(end -245.639808 40.69334)
		(width 0.10668)
		(layer "B.Cu")
		(net "SAS_B1_RX1P")
	)
	(arc
		(start -244.221 39.878)
		(mid -244.177798 39.9823)
		(end -244.221 40.0866)
		(width 0.10668)
		(layer "B.Cu")
		(net "SAS_B1_RX1P")
	)
	(arc
		(start -243.322071 17.02484)
		(mid -243.385236 16.973103)
		(end -243.466483 16.981183)
		(width 0.10668)
		(layer "B.Cu")
		(net "SAS_B1_RX1P")
	)
	(segment
		(start -238.9832 31.8008)
		(end -240.203149 33.020747)
		(width 0.10668)
		(layer "B.Cu")
		(net "SAS_B1_RX1N")
	)
	(segment
		(start -243.671636 16.598341)
		(end -243.695111 16.610919)
		(width 0.10668)
		(layer "B.Cu")
		(net "SAS_B1_RX1N")
	)
	(segment
		(start -243.85 16.039371)
		(end -243.627928 16.453904)
		(width 0.10668)
		(layer "B.Cu")
		(net "SAS_B1_RX1N")
	)
	(segment
		(start -247.302203 40.137801)
		(end -247.68 39.760002)
		(width 0.10668)
		(layer "B.Cu")
		(net "SAS_B1_RX1N")
	)
	(segment
		(start -242.666147 37.464947)
		(end -245.3332 40.132)
		(width 0.10668)
		(layer "B.Cu")
		(net "SAS_B1_RX1N")
	)
	(segment
		(start -243.448159 18.669)
		(end -240.67738 18.669)
		(width 0.10668)
		(layer "B.Cu")
		(net "SAS_B1_RX1N")
	)
	(segment
		(start -241.604068 36.402866)
		(end -242.666147 37.464947)
		(width 0.10668)
		(layer "B.Cu")
		(net "SAS_B1_RX1N")
	)
	(segment
		(start -239.264924 21.630427)
		(end -239.006634 21.888714)
		(width 0.10668)
		(layer "B.Cu")
		(net "SAS_B1_RX1N")
	)
	(segment
		(start -243.67159 16.598318)
		(end -243.671636 16.598341)
		(width 0.10668)
		(layer "B.Cu")
		(net "SAS_B1_RX1N")
	)
	(segment
		(start -245.639806 40.259)
		(end -247.0096 40.259)
		(width 0.10668)
		(layer "B.Cu")
		(net "SAS_B1_RX1N")
	)
	(segment
		(start -243.822192 16.70526)
		(end -244.029911 16.912979)
		(width 0.10668)
		(layer "B.Cu")
		(net "SAS_B1_RX1N")
	)
	(segment
		(start -243.671588 16.598316)
		(end -243.67159 16.598318)
		(width 0.10668)
		(layer "B.Cu")
		(net "SAS_B1_RX1N")
	)
	(segment
		(start -240.0754 19.27098)
		(end -240.0754 19.673768)
		(width 0.10668)
		(layer "B.Cu")
		(net "SAS_B1_RX1N")
	)
	(segment
		(start -244.3426 17.667877)
		(end -244.3426 17.774559)
		(width 0.10668)
		(layer "B.Cu")
		(net "SAS_B1_RX1N")
	)
	(segment
		(start -238.0688 24.15285)
		(end -238.0688 29.593243)
		(width 0.10668)
		(layer "B.Cu")
		(net "SAS_B1_RX1N")
	)
	(arc
		(start -239.006634 21.888714)
		(mid -238.312534 22.927509)
		(end -238.0688 24.15285)
		(width 0.10668)
		(layer "B.Cu")
		(net "SAS_B1_RX1N")
	)
	(arc
		(start -238.0688 29.593243)
		(mid -238.306445 30.787964)
		(end -238.9832 31.8008)
		(width 0.10668)
		(layer "B.Cu")
		(net "SAS_B1_RX1N")
	)
	(arc
		(start -240.6342 34.0614)
		(mid -240.886261 35.328592)
		(end -241.604068 36.402866)
		(width 0.10668)
		(layer "B.Cu")
		(net "SAS_B1_RX1N")
	)
	(arc
		(start -240.0754 19.673768)
		(mid -239.864764 20.732704)
		(end -239.264924 21.630427)
		(width 0.10668)
		(layer "B.Cu")
		(net "SAS_B1_RX1N")
	)
	(arc
		(start -244.3426 17.774559)
		(mid -244.080624 18.407024)
		(end -243.448159 18.669)
		(width 0.10668)
		(layer "B.Cu")
		(net "SAS_B1_RX1N")
	)
	(arc
		(start -245.3332 40.132)
		(mid -245.473872 40.225994)
		(end -245.639806 40.259)
		(width 0.10668)
		(layer "B.Cu")
		(net "SAS_B1_RX1N")
	)
	(arc
		(start -243.695111 16.610919)
		(mid -243.76212 16.653417)
		(end -243.822192 16.70526)
		(width 0.10668)
		(layer "B.Cu")
		(net "SAS_B1_RX1N")
	)
	(arc
		(start -247.0096 40.259)
		(mid -247.167956 40.227502)
		(end -247.302203 40.137801)
		(width 0.10668)
		(layer "B.Cu")
		(net "SAS_B1_RX1N")
	)
	(arc
		(start -243.627928 16.453904)
		(mid -243.619849 16.535152)
		(end -243.671588 16.598316)
		(width 0.10668)
		(layer "B.Cu")
		(net "SAS_B1_RX1N")
	)
	(arc
		(start -240.67738 18.669)
		(mid -240.251716 18.845316)
		(end -240.0754 19.27098)
		(width 0.10668)
		(layer "B.Cu")
		(net "SAS_B1_RX1N")
	)
	(arc
		(start -240.203149 33.020747)
		(mid -240.522174 33.498203)
		(end -240.6342 34.0614)
		(width 0.10668)
		(layer "B.Cu")
		(net "SAS_B1_RX1N")
	)
	(arc
		(start -244.029911 16.912979)
		(mid -244.261335 17.259329)
		(end -244.3426 17.667877)
		(width 0.10668)
		(layer "B.Cu")
		(net "SAS_B1_RX1N")
	)
	(segment
		(start -150.904999 18.894999)
		(end -151.539999 18.259999)
		(width 0.127)
		(layer "F.Cu")
		(net "PCIE_WAKE_B2_N")
	)
	(via
		(at -151.539999 18.259999)
		(size 0.5588)
		(drill 0.254)
		(layers "F.Cu" "B.Cu")
		(net "PCIE_WAKE_B2_N")
	)
	(segment
		(start -151.872 18.8087)
		(end -151.872 18.592)
		(width 0.12954)
		(layer "In3.Cu")
		(net "PCIE_WAKE_B2_N")
	)
	(segment
		(start -156.3932 20.0914)
		(end -155.9868 19.685)
		(width 0.12954)
		(layer "In3.Cu")
		(net "PCIE_WAKE_B2_N")
	)
	(segment
		(start -174.719331 22.79653)
		(end -161.960911 22.79653)
		(width 0.12954)
		(layer "In3.Cu")
		(net "PCIE_WAKE_B2_N")
	)
	(segment
		(start -161.960911 22.79653)
		(end -160.58166 21.41728)
		(width 0.12954)
		(layer "In3.Cu")
		(net "PCIE_WAKE_B2_N")
	)
	(segment
		(start -160.58166 21.41728)
		(end -158.17628 21.41728)
		(width 0.12954)
		(layer "In3.Cu")
		(net "PCIE_WAKE_B2_N")
	)
	(segment
		(start -177.460001 35.56)
		(end -176.3068 34.406799)
		(width 0.12954)
		(layer "In3.Cu")
		(net "PCIE_WAKE_B2_N")
	)
	(segment
		(start -176.3068 24.384)
		(end -174.719331 22.79653)
		(width 0.12954)
		(layer "In3.Cu")
		(net "PCIE_WAKE_B2_N")
	)
	(segment
		(start -176.3068 34.406799)
		(end -176.3068 24.384)
		(width 0.12954)
		(layer "In3.Cu")
		(net "PCIE_WAKE_B2_N")
	)
	(segment
		(start -156.8504 20.0914)
		(end -156.3932 20.0914)
		(width 0.12954)
		(layer "In3.Cu")
		(net "PCIE_WAKE_B2_N")
	)
	(segment
		(start -158.17628 21.41728)
		(end -156.8504 20.0914)
		(width 0.12954)
		(layer "In3.Cu")
		(net "PCIE_WAKE_B2_N")
	)
	(segment
		(start -155.9868 19.685)
		(end -155.9868 19.431)
		(width 0.12954)
		(layer "In3.Cu")
		(net "PCIE_WAKE_B2_N")
	)
	(segment
		(start -155.6058 19.05)
		(end -152.1133 19.05)
		(width 0.12954)
		(layer "In3.Cu")
		(net "PCIE_WAKE_B2_N")
	)
	(segment
		(start -155.9868 19.431)
		(end -155.6058 19.05)
		(width 0.12954)
		(layer "In3.Cu")
		(net "PCIE_WAKE_B2_N")
	)
	(segment
		(start -151.872 18.592)
		(end -151.539999 18.259999)
		(width 0.12954)
		(layer "In3.Cu")
		(net "PCIE_WAKE_B2_N")
	)
	(segment
		(start -152.1133 19.05)
		(end -151.872 18.8087)
		(width 0.12954)
		(layer "In3.Cu")
		(net "PCIE_WAKE_B2_N")
	)
	(segment
		(start -371.904999 18.894999)
		(end -372.539999 18.259999)
		(width 0.127)
		(layer "F.Cu")
		(net "PCIE_WAKE_B1_N")
	)
	(via
		(at -372.539999 18.259999)
		(size 0.5588)
		(drill 0.254)
		(layers "F.Cu" "B.Cu")
		(net "PCIE_WAKE_B1_N")
	)
	(segment
		(start -376.9868 19.685)
		(end -376.9868 19.431)
		(width 0.12954)
		(layer "In3.Cu")
		(net "PCIE_WAKE_B1_N")
	)
	(segment
		(start -397.3068 34.406799)
		(end -397.3068 24.384)
		(width 0.12954)
		(layer "In3.Cu")
		(net "PCIE_WAKE_B1_N")
	)
	(segment
		(start -397.3068 24.384)
		(end -395.71933 22.79653)
		(width 0.12954)
		(layer "In3.Cu")
		(net "PCIE_WAKE_B1_N")
	)
	(segment
		(start -381.58166 21.41728)
		(end -379.17628 21.41728)
		(width 0.12954)
		(layer "In3.Cu")
		(net "PCIE_WAKE_B1_N")
	)
	(segment
		(start -398.460001 35.56)
		(end -397.3068 34.406799)
		(width 0.12954)
		(layer "In3.Cu")
		(net "PCIE_WAKE_B1_N")
	)
	(segment
		(start -395.71933 22.79653)
		(end -382.96091 22.79653)
		(width 0.12954)
		(layer "In3.Cu")
		(net "PCIE_WAKE_B1_N")
	)
	(segment
		(start -382.96091 22.79653)
		(end -381.58166 21.41728)
		(width 0.12954)
		(layer "In3.Cu")
		(net "PCIE_WAKE_B1_N")
	)
	(segment
		(start -373.1133 19.05)
		(end -372.872 18.8087)
		(width 0.12954)
		(layer "In3.Cu")
		(net "PCIE_WAKE_B1_N")
	)
	(segment
		(start -379.17628 21.41728)
		(end -377.8504 20.0914)
		(width 0.12954)
		(layer "In3.Cu")
		(net "PCIE_WAKE_B1_N")
	)
	(segment
		(start -372.872 18.8087)
		(end -372.872 18.592)
		(width 0.12954)
		(layer "In3.Cu")
		(net "PCIE_WAKE_B1_N")
	)
	(segment
		(start -377.8504 20.0914)
		(end -377.3932 20.0914)
		(width 0.12954)
		(layer "In3.Cu")
		(net "PCIE_WAKE_B1_N")
	)
	(segment
		(start -372.872 18.592)
		(end -372.539999 18.259999)
		(width 0.12954)
		(layer "In3.Cu")
		(net "PCIE_WAKE_B1_N")
	)
	(segment
		(start -377.3932 20.0914)
		(end -376.9868 19.685)
		(width 0.12954)
		(layer "In3.Cu")
		(net "PCIE_WAKE_B1_N")
	)
	(segment
		(start -376.9868 19.431)
		(end -376.6058 19.05)
		(width 0.12954)
		(layer "In3.Cu")
		(net "PCIE_WAKE_B1_N")
	)
	(segment
		(start -376.6058 19.05)
		(end -373.1133 19.05)
		(width 0.12954)
		(layer "In3.Cu")
		(net "PCIE_WAKE_B1_N")
	)
	(segment
		(start -154.714999 27.784999)
		(end -155.349999 27.149999)
		(width 0.127)
		(layer "F.Cu")
		(net "PCIE_T2B_B2_RX_DP<9>")
	)
	(via
		(at -155.349999 27.149999)
		(size 0.5588)
		(drill 0.254)
		(layers "F.Cu" "B.Cu")
		(net "PCIE_T2B_B2_RX_DP<9>")
	)
	(segment
		(start -167.727655 18.316057)
		(end -177.502619 18.316057)
		(width 0.127)
		(layer "In2.Cu")
		(net "PCIE_T2B_B2_RX_DP<9>")
	)
	(segment
		(start -182.316163 40.185818)
		(end -182.636399 40.506053)
		(width 0.127)
		(layer "In2.Cu")
		(net "PCIE_T2B_B2_RX_DP<9>")
	)
	(segment
		(start -158.983177 25.742232)
		(end -158.983177 25.742227)
		(width 0.127)
		(layer "In2.Cu")
		(net "PCIE_T2B_B2_RX_DP<9>")
	)
	(segment
		(start -155.349999 27.149999)
		(end -155.838949 26.661049)
		(width 0.127)
		(layer "In2.Cu")
		(net "PCIE_T2B_B2_RX_DP<9>")
	)
	(segment
		(start -182.316163 23.129601)
		(end -182.316163 40.185818)
		(width 0.127)
		(layer "In2.Cu")
		(net "PCIE_T2B_B2_RX_DP<9>")
	)
	(segment
		(start -182.90605 40.506053)
		(end -183.459999 41.060002)
		(width 0.127)
		(layer "In2.Cu")
		(net "PCIE_T2B_B2_RX_DP<9>")
	)
	(segment
		(start -177.502619 18.316057)
		(end -182.316163 23.129601)
		(width 0.127)
		(layer "In2.Cu")
		(net "PCIE_T2B_B2_RX_DP<9>")
	)
	(segment
		(start -155.838949 26.661049)
		(end -158.06436 26.661049)
		(width 0.127)
		(layer "In2.Cu")
		(net "PCIE_T2B_B2_RX_DP<9>")
	)
	(segment
		(start -158.983177 25.742227)
		(end -160.301485 25.742227)
		(width 0.127)
		(layer "In2.Cu")
		(net "PCIE_T2B_B2_RX_DP<9>")
	)
	(segment
		(start -158.06436 26.661049)
		(end -158.983177 25.742232)
		(width 0.127)
		(layer "In2.Cu")
		(net "PCIE_T2B_B2_RX_DP<9>")
	)
	(segment
		(start -182.636399 40.506053)
		(end -182.90605 40.506053)
		(width 0.127)
		(layer "In2.Cu")
		(net "PCIE_T2B_B2_RX_DP<9>")
	)
	(segment
		(start -160.301485 25.742227)
		(end -167.727655 18.316057)
		(width 0.127)
		(layer "In2.Cu")
		(net "PCIE_T2B_B2_RX_DP<9>")
	)
	(segment
		(start -155.984999 25.244999)
		(end -156.619999 24.609999)
		(width 0.127)
		(layer "F.Cu")
		(net "PCIE_T2B_B2_RX_DP<8>")
	)
	(via
		(at -156.619999 24.609999)
		(size 0.5588)
		(drill 0.254)
		(layers "F.Cu" "B.Cu")
		(net "PCIE_T2B_B2_RX_DP<8>")
	)
	(segment
		(start -159.802548 24.121049)
		(end -157.108949 24.121049)
		(width 0.127)
		(layer "In2.Cu")
		(net "PCIE_T2B_B2_RX_DP<8>")
	)
	(segment
		(start -157.108949 24.121049)
		(end -156.619999 24.609999)
		(width 0.127)
		(layer "In2.Cu")
		(net "PCIE_T2B_B2_RX_DP<8>")
	)
	(segment
		(start -184.3297 38.877692)
		(end -184.3297 23.094488)
		(width 0.127)
		(layer "In2.Cu")
		(net "PCIE_T2B_B2_RX_DP<8>")
	)
	(segment
		(start -184.658058 39.206051)
		(end -184.3297 38.877692)
		(width 0.127)
		(layer "In2.Cu")
		(net "PCIE_T2B_B2_RX_DP<8>")
	)
	(segment
		(start -184.906049 39.206051)
		(end -184.658058 39.206051)
		(width 0.127)
		(layer "In2.Cu")
		(net "PCIE_T2B_B2_RX_DP<8>")
	)
	(segment
		(start -178.217264 16.982051)
		(end -166.941546 16.982051)
		(width 0.127)
		(layer "In2.Cu")
		(net "PCIE_T2B_B2_RX_DP<8>")
	)
	(segment
		(start -184.3297 23.094488)
		(end -178.217264 16.982051)
		(width 0.127)
		(layer "In2.Cu")
		(net "PCIE_T2B_B2_RX_DP<8>")
	)
	(segment
		(start -166.941546 16.982051)
		(end -159.802548 24.121049)
		(width 0.127)
		(layer "In2.Cu")
		(net "PCIE_T2B_B2_RX_DP<8>")
	)
	(segment
		(start -185.46 39.760002)
		(end -184.906049 39.206051)
		(width 0.127)
		(layer "In2.Cu")
		(net "PCIE_T2B_B2_RX_DP<8>")
	)
	(segment
		(start -157.737599 42.542399)
		(end -157.254999 43.024999)
		(width 0.127)
		(layer "F.Cu")
		(net "PCIE_T2B_B2_RX_DP<7>")
	)
	(segment
		(start -171.46 45.260001)
		(end -170.912401 44.712402)
		(width 0.127)
		(layer "F.Cu")
		(net "PCIE_T2B_B2_RX_DP<7>")
	)
	(segment
		(start -162.039117 44.712402)
		(end -159.869114 42.542399)
		(width 0.127)
		(layer "F.Cu")
		(net "PCIE_T2B_B2_RX_DP<7>")
	)
	(segment
		(start -170.912401 44.712402)
		(end -162.039117 44.712402)
		(width 0.127)
		(layer "F.Cu")
		(net "PCIE_T2B_B2_RX_DP<7>")
	)
	(segment
		(start -159.869114 42.542399)
		(end -157.737599 42.542399)
		(width 0.127)
		(layer "F.Cu")
		(net "PCIE_T2B_B2_RX_DP<7>")
	)
	(segment
		(start -172.298426 43.051682)
		(end -172.659147 43.412402)
		(width 0.127)
		(layer "F.Cu")
		(net "PCIE_T2B_B2_RX_DP<6>")
	)
	(segment
		(start -159.794001 40.002399)
		(end -160.8836 38.9128)
		(width 0.127)
		(layer "F.Cu")
		(net "PCIE_T2B_B2_RX_DP<6>")
	)
	(segment
		(start -166.768099 34.3916)
		(end -170.147808 31.011891)
		(width 0.127)
		(layer "F.Cu")
		(net "PCIE_T2B_B2_RX_DP<6>")
	)
	(segment
		(start -170.663189 24.78913)
		(end -171.833083 24.78913)
		(width 0.127)
		(layer "F.Cu")
		(net "PCIE_T2B_B2_RX_DP<6>")
	)
	(segment
		(start -170.147808 25.304511)
		(end -170.663189 24.78913)
		(width 0.127)
		(layer "F.Cu")
		(net "PCIE_T2B_B2_RX_DP<6>")
	)
	(segment
		(start -163.943096 34.3916)
		(end -166.768099 34.3916)
		(width 0.127)
		(layer "F.Cu")
		(net "PCIE_T2B_B2_RX_DP<6>")
	)
	(segment
		(start -170.147808 31.011891)
		(end -170.147808 25.304511)
		(width 0.127)
		(layer "F.Cu")
		(net "PCIE_T2B_B2_RX_DP<6>")
	)
	(segment
		(start -171.833083 24.78913)
		(end -172.298426 25.254473)
		(width 0.127)
		(layer "F.Cu")
		(net "PCIE_T2B_B2_RX_DP<6>")
	)
	(segment
		(start -158.524999 40.484999)
		(end -159.007599 40.002399)
		(width 0.127)
		(layer "F.Cu")
		(net "PCIE_T2B_B2_RX_DP<6>")
	)
	(segment
		(start -159.007599 40.002399)
		(end -159.794001 40.002399)
		(width 0.127)
		(layer "F.Cu")
		(net "PCIE_T2B_B2_RX_DP<6>")
	)
	(segment
		(start -172.298426 25.254473)
		(end -172.298426 43.051682)
		(width 0.127)
		(layer "F.Cu")
		(net "PCIE_T2B_B2_RX_DP<6>")
	)
	(segment
		(start -160.8836 38.9128)
		(end -160.8836 37.451096)
		(width 0.127)
		(layer "F.Cu")
		(net "PCIE_T2B_B2_RX_DP<6>")
	)
	(segment
		(start -160.8836 37.451096)
		(end -163.943096 34.3916)
		(width 0.127)
		(layer "F.Cu")
		(net "PCIE_T2B_B2_RX_DP<6>")
	)
	(segment
		(start -172.659147 43.412402)
		(end -172.912402 43.412402)
		(width 0.127)
		(layer "F.Cu")
		(net "PCIE_T2B_B2_RX_DP<6>")
	)
	(segment
		(start -172.912402 43.412402)
		(end -173.460001 43.960001)
		(width 0.127)
		(layer "F.Cu")
		(net "PCIE_T2B_B2_RX_DP<6>")
	)
	(segment
		(start -174.298201 24.012771)
		(end -173.807232 23.521802)
		(width 0.127)
		(layer "F.Cu")
		(net "PCIE_T2B_B2_RX_DP<5>")
	)
	(segment
		(start -174.298201 24.079365)
		(end -174.298201 24.012771)
		(width 0.127)
		(layer "F.Cu")
		(net "PCIE_T2B_B2_RX_DP<5>")
	)
	(segment
		(start -168.8338 27.374632)
		(end -168.833864 27.374695)
		(width 0.127)
		(layer "F.Cu")
		(net "PCIE_T2B_B2_RX_DP<5>")
	)
	(segment
		(start -173.807232 23.521802)
		(end -173.11277 23.521802)
		(width 0.127)
		(layer "F.Cu")
		(net "PCIE_T2B_B2_RX_DP<5>")
	)
	(segment
		(start -160.3248 36.136138)
		(end -160.3248 36.1442)
		(width 0.127)
		(layer "F.Cu")
		(net "PCIE_T2B_B2_RX_DP<5>")
	)
	(segment
		(start -173.11277 23.521802)
		(end -173.111886 23.522686)
		(width 0.127)
		(layer "F.Cu")
		(net "PCIE_T2B_B2_RX_DP<5>")
	)
	(segment
		(start -174.3002 44.353457)
		(end -174.3002 24.081364)
		(width 0.127)
		(layer "F.Cu")
		(net "PCIE_T2B_B2_RX_DP<5>")
	)
	(segment
		(start -168.8338 24.376578)
		(end -168.8338 27.374632)
		(width 0.127)
		(layer "F.Cu")
		(net "PCIE_T2B_B2_RX_DP<5>")
	)
	(segment
		(start -163.288538 33.1724)
		(end -160.3248 36.136138)
		(width 0.127)
		(layer "F.Cu")
		(net "PCIE_T2B_B2_RX_DP<5>")
	)
	(segment
		(start -175.46 45.260001)
		(end -174.912401 44.712402)
		(width 0.127)
		(layer "F.Cu")
		(net "PCIE_T2B_B2_RX_DP<5>")
	)
	(segment
		(start -173.111886 23.522686)
		(end -169.687692 23.522686)
		(width 0.127)
		(layer "F.Cu")
		(net "PCIE_T2B_B2_RX_DP<5>")
	)
	(segment
		(start -159.006601 37.462399)
		(end -157.737599 37.462399)
		(width 0.127)
		(layer "F.Cu")
		(net "PCIE_T2B_B2_RX_DP<5>")
	)
	(segment
		(start -160.3248 36.1442)
		(end -159.006601 37.462399)
		(width 0.127)
		(layer "F.Cu")
		(net "PCIE_T2B_B2_RX_DP<5>")
	)
	(segment
		(start -157.737599 37.462399)
		(end -157.254999 37.944999)
		(width 0.127)
		(layer "F.Cu")
		(net "PCIE_T2B_B2_RX_DP<5>")
	)
	(segment
		(start -174.659145 44.712402)
		(end -174.3002 44.353457)
		(width 0.127)
		(layer "F.Cu")
		(net "PCIE_T2B_B2_RX_DP<5>")
	)
	(segment
		(start -174.912401 44.712402)
		(end -174.659145 44.712402)
		(width 0.127)
		(layer "F.Cu")
		(net "PCIE_T2B_B2_RX_DP<5>")
	)
	(segment
		(start -168.833864 27.374695)
		(end -168.833864 30.47919)
		(width 0.127)
		(layer "F.Cu")
		(net "PCIE_T2B_B2_RX_DP<5>")
	)
	(segment
		(start -166.140653 33.1724)
		(end -163.288538 33.1724)
		(width 0.127)
		(layer "F.Cu")
		(net "PCIE_T2B_B2_RX_DP<5>")
	)
	(segment
		(start -174.3002 24.081364)
		(end -174.298201 24.079365)
		(width 0.127)
		(layer "F.Cu")
		(net "PCIE_T2B_B2_RX_DP<5>")
	)
	(segment
		(start -169.687692 23.522686)
		(end -168.8338 24.376578)
		(width 0.127)
		(layer "F.Cu")
		(net "PCIE_T2B_B2_RX_DP<5>")
	)
	(segment
		(start -168.833864 30.47919)
		(end -166.140653 33.1724)
		(width 0.127)
		(layer "F.Cu")
		(net "PCIE_T2B_B2_RX_DP<5>")
	)
	(segment
		(start -176.912402 43.412402)
		(end -177.460001 43.960001)
		(width 0.127)
		(layer "F.Cu")
		(net "PCIE_T2B_B2_RX_DP<4>")
	)
	(segment
		(start -176.3068 24.266413)
		(end -176.3068 43.060056)
		(width 0.127)
		(layer "F.Cu")
		(net "PCIE_T2B_B2_RX_DP<4>")
	)
	(segment
		(start -162.4584 32.278135)
		(end -162.4584 30.530053)
		(width 0.127)
		(layer "F.Cu")
		(net "PCIE_T2B_B2_RX_DP<4>")
	)
	(segment
		(start -158.524999 35.404999)
		(end -159.007599 34.922399)
		(width 0.127)
		(layer "F.Cu")
		(net "PCIE_T2B_B2_RX_DP<4>")
	)
	(segment
		(start -167.386 25.602453)
		(end -167.386 24.100168)
		(width 0.127)
		(layer "F.Cu")
		(net "PCIE_T2B_B2_RX_DP<4>")
	)
	(segment
		(start -174.262085 22.221698)
		(end -176.3068 24.266413)
		(width 0.127)
		(layer "F.Cu")
		(net "PCIE_T2B_B2_RX_DP<4>")
	)
	(segment
		(start -176.3068 43.060056)
		(end -176.659146 43.412402)
		(width 0.127)
		(layer "F.Cu")
		(net "PCIE_T2B_B2_RX_DP<4>")
	)
	(segment
		(start -162.4584 30.530053)
		(end -167.386 25.602453)
		(width 0.127)
		(layer "F.Cu")
		(net "PCIE_T2B_B2_RX_DP<4>")
	)
	(segment
		(start -159.814133 34.922399)
		(end -162.4584 32.278135)
		(width 0.127)
		(layer "F.Cu")
		(net "PCIE_T2B_B2_RX_DP<4>")
	)
	(segment
		(start -176.659146 43.412402)
		(end -176.912402 43.412402)
		(width 0.127)
		(layer "F.Cu")
		(net "PCIE_T2B_B2_RX_DP<4>")
	)
	(segment
		(start -167.386 24.100168)
		(end -169.26447 22.221698)
		(width 0.127)
		(layer "F.Cu")
		(net "PCIE_T2B_B2_RX_DP<4>")
	)
	(segment
		(start -169.26447 22.221698)
		(end -174.262085 22.221698)
		(width 0.127)
		(layer "F.Cu")
		(net "PCIE_T2B_B2_RX_DP<4>")
	)
	(segment
		(start -159.007599 34.922399)
		(end -159.814133 34.922399)
		(width 0.127)
		(layer "F.Cu")
		(net "PCIE_T2B_B2_RX_DP<4>")
	)
	(segment
		(start -160.346024 32.382399)
		(end -161.036 31.692423)
		(width 0.127)
		(layer "F.Cu")
		(net "PCIE_T2B_B2_RX_DP<3>")
	)
	(segment
		(start -161.036 30.1752)
		(end -165.989 25.2222)
		(width 0.127)
		(layer "F.Cu")
		(net "PCIE_T2B_B2_RX_DP<3>")
	)
	(segment
		(start -178.912401 44.712402)
		(end -179.459999 45.260001)
		(width 0.127)
		(layer "F.Cu")
		(net "PCIE_T2B_B2_RX_DP<3>")
	)
	(segment
		(start -157.737599 32.382399)
		(end -160.346024 32.382399)
		(width 0.127)
		(layer "F.Cu")
		(net "PCIE_T2B_B2_RX_DP<3>")
	)
	(segment
		(start -161.036 31.692423)
		(end -161.036 30.1752)
		(width 0.127)
		(layer "F.Cu")
		(net "PCIE_T2B_B2_RX_DP<3>")
	)
	(segment
		(start -178.659145 44.712402)
		(end -178.912401 44.712402)
		(width 0.127)
		(layer "F.Cu")
		(net "PCIE_T2B_B2_RX_DP<3>")
	)
	(segment
		(start -175.441407 20.989798)
		(end -178.3134 23.861791)
		(width 0.127)
		(layer "F.Cu")
		(net "PCIE_T2B_B2_RX_DP<3>")
	)
	(segment
		(start -178.3134 23.861791)
		(end -178.3134 44.366658)
		(width 0.127)
		(layer "F.Cu")
		(net "PCIE_T2B_B2_RX_DP<3>")
	)
	(segment
		(start -165.989 23.772957)
		(end -168.772159 20.989798)
		(width 0.127)
		(layer "F.Cu")
		(net "PCIE_T2B_B2_RX_DP<3>")
	)
	(segment
		(start -168.772159 20.989798)
		(end -175.441407 20.989798)
		(width 0.127)
		(layer "F.Cu")
		(net "PCIE_T2B_B2_RX_DP<3>")
	)
	(segment
		(start -178.3134 44.366658)
		(end -178.659145 44.712402)
		(width 0.127)
		(layer "F.Cu")
		(net "PCIE_T2B_B2_RX_DP<3>")
	)
	(segment
		(start -165.989 25.2222)
		(end -165.989 23.772957)
		(width 0.127)
		(layer "F.Cu")
		(net "PCIE_T2B_B2_RX_DP<3>")
	)
	(segment
		(start -157.254999 32.864999)
		(end -157.737599 32.382399)
		(width 0.127)
		(layer "F.Cu")
		(net "PCIE_T2B_B2_RX_DP<3>")
	)
	(segment
		(start -181.46 43.960001)
		(end -180.912402 43.412402)
		(width 0.127)
		(layer "F.Cu")
		(net "PCIE_T2B_B2_RX_DP<2>")
	)
	(segment
		(start -180.912402 43.412402)
		(end -180.659146 43.412402)
		(width 0.127)
		(layer "F.Cu")
		(net "PCIE_T2B_B2_RX_DP<2>")
	)
	(segment
		(start -163.23342 24.498823)
		(end -163.23342 25.92038)
		(width 0.127)
		(layer "F.Cu")
		(net "PCIE_T2B_B2_RX_DP<2>")
	)
	(segment
		(start -180.309413 43.06267)
		(end -180.309413 23.637337)
		(width 0.127)
		(layer "F.Cu")
		(net "PCIE_T2B_B2_RX_DP<2>")
	)
	(segment
		(start -167.974091 19.758152)
		(end -163.23342 24.498823)
		(width 0.127)
		(layer "F.Cu")
		(net "PCIE_T2B_B2_RX_DP<2>")
	)
	(segment
		(start -163.23342 25.92038)
		(end -159.311401 29.842399)
		(width 0.127)
		(layer "F.Cu")
		(net "PCIE_T2B_B2_RX_DP<2>")
	)
	(segment
		(start -159.311401 29.842399)
		(end -159.007599 29.842399)
		(width 0.127)
		(layer "F.Cu")
		(net "PCIE_T2B_B2_RX_DP<2>")
	)
	(segment
		(start -176.430229 19.758152)
		(end -167.974091 19.758152)
		(width 0.127)
		(layer "F.Cu")
		(net "PCIE_T2B_B2_RX_DP<2>")
	)
	(segment
		(start -180.659146 43.412402)
		(end -180.309413 43.06267)
		(width 0.127)
		(layer "F.Cu")
		(net "PCIE_T2B_B2_RX_DP<2>")
	)
	(segment
		(start -180.309413 23.637337)
		(end -176.430229 19.758152)
		(width 0.127)
		(layer "F.Cu")
		(net "PCIE_T2B_B2_RX_DP<2>")
	)
	(segment
		(start -159.007599 29.842399)
		(end -158.524999 30.324999)
		(width 0.127)
		(layer "F.Cu")
		(net "PCIE_T2B_B2_RX_DP<2>")
	)
	(segment
		(start -167.280163 18.457164)
		(end -161.966976 23.770351)
		(width 0.127)
		(layer "F.Cu")
		(net "PCIE_T2B_B2_RX_DP<1>")
	)
	(segment
		(start -161.966976 23.770351)
		(end -161.966976 25.402614)
		(width 0.127)
		(layer "F.Cu")
		(net "PCIE_T2B_B2_RX_DP<1>")
	)
	(segment
		(start -161.966976 25.402614)
		(end -160.067191 27.302399)
		(width 0.127)
		(layer "F.Cu")
		(net "PCIE_T2B_B2_RX_DP<1>")
	)
	(segment
		(start -182.659144 44.712402)
		(end -182.3012 44.354458)
		(width 0.127)
		(layer "F.Cu")
		(net "PCIE_T2B_B2_RX_DP<1>")
	)
	(segment
		(start -157.737599 27.302399)
		(end -157.254999 27.784999)
		(width 0.127)
		(layer "F.Cu")
		(net "PCIE_T2B_B2_RX_DP<1>")
	)
	(segment
		(start -182.3012 44.354458)
		(end -182.3012 23.512541)
		(width 0.127)
		(layer "F.Cu")
		(net "PCIE_T2B_B2_RX_DP<1>")
	)
	(segment
		(start -183.459999 45.260001)
		(end -182.9124 44.712402)
		(width 0.127)
		(layer "F.Cu")
		(net "PCIE_T2B_B2_RX_DP<1>")
	)
	(segment
		(start -182.9124 44.712402)
		(end -182.659144 44.712402)
		(width 0.127)
		(layer "F.Cu")
		(net "PCIE_T2B_B2_RX_DP<1>")
	)
	(segment
		(start -182.3012 23.512541)
		(end -177.245823 18.457164)
		(width 0.127)
		(layer "F.Cu")
		(net "PCIE_T2B_B2_RX_DP<1>")
	)
	(segment
		(start -177.245823 18.457164)
		(end -167.280163 18.457164)
		(width 0.127)
		(layer "F.Cu")
		(net "PCIE_T2B_B2_RX_DP<1>")
	)
	(segment
		(start -160.067191 27.302399)
		(end -157.737599 27.302399)
		(width 0.127)
		(layer "F.Cu")
		(net "PCIE_T2B_B2_RX_DP<1>")
	)
	(segment
		(start -154.714999 43.024999)
		(end -155.349999 42.389999)
		(width 0.127)
		(layer "F.Cu")
		(net "PCIE_T2B_B2_RX_DP<15>")
	)
	(via
		(at -155.349999 42.389999)
		(size 0.5588)
		(drill 0.254)
		(layers "F.Cu" "B.Cu")
		(net "PCIE_T2B_B2_RX_DP<15>")
	)
	(segment
		(start -171.46 41.060002)
		(end -170.906049 40.506051)
		(width 0.127)
		(layer "In2.Cu")
		(net "PCIE_T2B_B2_RX_DP<15>")
	)
	(segment
		(start -170.906049 40.506051)
		(end -170.502618 40.506051)
		(width 0.127)
		(layer "In2.Cu")
		(net "PCIE_T2B_B2_RX_DP<15>")
	)
	(segment
		(start -167.487483 44.614798)
		(end -167.245619 44.614798)
		(width 0.127)
		(layer "In2.Cu")
		(net "PCIE_T2B_B2_RX_DP<15>")
	)
	(segment
		(start -159.55313 44.614737)
		(end -156.839442 41.901049)
		(width 0.127)
		(layer "In2.Cu")
		(net "PCIE_T2B_B2_RX_DP<15>")
	)
	(segment
		(start -170.158694 41.943586)
		(end -167.487483 44.614798)
		(width 0.127)
		(layer "In2.Cu")
		(net "PCIE_T2B_B2_RX_DP<15>")
	)
	(segment
		(start -156.839442 41.901049)
		(end -155.838949 41.901049)
		(width 0.127)
		(layer "In2.Cu")
		(net "PCIE_T2B_B2_RX_DP<15>")
	)
	(segment
		(start -167.245558 44.614737)
		(end -159.55313 44.614737)
		(width 0.127)
		(layer "In2.Cu")
		(net "PCIE_T2B_B2_RX_DP<15>")
	)
	(segment
		(start -167.245619 44.614798)
		(end -167.245558 44.614737)
		(width 0.127)
		(layer "In2.Cu")
		(net "PCIE_T2B_B2_RX_DP<15>")
	)
	(segment
		(start -170.158694 40.849974)
		(end -170.158694 41.943586)
		(width 0.127)
		(layer "In2.Cu")
		(net "PCIE_T2B_B2_RX_DP<15>")
	)
	(segment
		(start -170.502618 40.506051)
		(end -170.158694 40.849974)
		(width 0.127)
		(layer "In2.Cu")
		(net "PCIE_T2B_B2_RX_DP<15>")
	)
	(segment
		(start -155.838949 41.901049)
		(end -155.349999 42.389999)
		(width 0.127)
		(layer "In2.Cu")
		(net "PCIE_T2B_B2_RX_DP<15>")
	)
	(segment
		(start -155.984999 40.484999)
		(end -156.619999 39.849999)
		(width 0.127)
		(layer "F.Cu")
		(net "PCIE_T2B_B2_RX_DP<14>")
	)
	(via
		(at -156.619999 39.849999)
		(size 0.5588)
		(drill 0.254)
		(layers "F.Cu" "B.Cu")
		(net "PCIE_T2B_B2_RX_DP<14>")
	)
	(segment
		(start -172.90605 39.206051)
		(end -172.566297 39.206051)
		(width 0.127)
		(layer "In2.Cu")
		(net "PCIE_T2B_B2_RX_DP<14>")
	)
	(segment
		(start -159.705444 39.361049)
		(end -157.108949 39.361049)
		(width 0.127)
		(layer "In2.Cu")
		(net "PCIE_T2B_B2_RX_DP<14>")
	)
	(segment
		(start -171.886692 24.801467)
		(end -170.951395 24.801467)
		(width 0.127)
		(layer "In2.Cu")
		(net "PCIE_T2B_B2_RX_DP<14>")
	)
	(segment
		(start -172.2982 38.937954)
		(end -172.2982 25.212975)
		(width 0.127)
		(layer "In2.Cu")
		(net "PCIE_T2B_B2_RX_DP<14>")
	)
	(segment
		(start -173.460001 39.760002)
		(end -172.90605 39.206051)
		(width 0.127)
		(layer "In2.Cu")
		(net "PCIE_T2B_B2_RX_DP<14>")
	)
	(segment
		(start -170.951335 24.801406)
		(end -170.830464 24.801406)
		(width 0.127)
		(layer "In2.Cu")
		(net "PCIE_T2B_B2_RX_DP<14>")
	)
	(segment
		(start -172.566297 39.206051)
		(end -172.2982 38.937954)
		(width 0.127)
		(layer "In2.Cu")
		(net "PCIE_T2B_B2_RX_DP<14>")
	)
	(segment
		(start -172.2982 25.212975)
		(end -171.886692 24.801467)
		(width 0.127)
		(layer "In2.Cu")
		(net "PCIE_T2B_B2_RX_DP<14>")
	)
	(segment
		(start -170.951395 24.801467)
		(end -170.951335 24.801406)
		(width 0.127)
		(layer "In2.Cu")
		(net "PCIE_T2B_B2_RX_DP<14>")
	)
	(segment
		(start -169.756552 29.309941)
		(end -159.705444 39.361049)
		(width 0.127)
		(layer "In2.Cu")
		(net "PCIE_T2B_B2_RX_DP<14>")
	)
	(segment
		(start -157.108949 39.361049)
		(end -156.619999 39.849999)
		(width 0.127)
		(layer "In2.Cu")
		(net "PCIE_T2B_B2_RX_DP<14>")
	)
	(segment
		(start -170.830464 24.801406)
		(end -169.756552 25.875318)
		(width 0.127)
		(layer "In2.Cu")
		(net "PCIE_T2B_B2_RX_DP<14>")
	)
	(segment
		(start -169.756552 25.875318)
		(end -169.756552 29.309941)
		(width 0.127)
		(layer "In2.Cu")
		(net "PCIE_T2B_B2_RX_DP<14>")
	)
	(segment
		(start -154.714999 37.944999)
		(end -155.349999 37.309999)
		(width 0.127)
		(layer "F.Cu")
		(net "PCIE_T2B_B2_RX_DP<13>")
	)
	(via
		(at -155.349999 37.309999)
		(size 0.5588)
		(drill 0.254)
		(layers "F.Cu" "B.Cu")
		(net "PCIE_T2B_B2_RX_DP<13>")
	)
	(segment
		(start -155.838949 36.821049)
		(end -159.756244 36.821049)
		(width 0.127)
		(layer "In2.Cu")
		(net "PCIE_T2B_B2_RX_DP<13>")
	)
	(segment
		(start -174.298201 23.925606)
		(end -174.298201 40.253089)
		(width 0.127)
		(layer "In2.Cu")
		(net "PCIE_T2B_B2_RX_DP<13>")
	)
	(segment
		(start -161.19362 35.3949)
		(end -167.844874 28.743646)
		(width 0.127)
		(layer "In2.Cu")
		(net "PCIE_T2B_B2_RX_DP<13>")
	)
	(segment
		(start -167.844874 25.797817)
		(end -167.930342 25.712349)
		(width 0.127)
		(layer "In2.Cu")
		(net "PCIE_T2B_B2_RX_DP<13>")
	)
	(segment
		(start -167.930342 25.712349)
		(end -167.930426 25.712349)
		(width 0.127)
		(layer "In2.Cu")
		(net "PCIE_T2B_B2_RX_DP<13>")
	)
	(segment
		(start -167.844874 28.743646)
		(end -167.844874 25.797817)
		(width 0.127)
		(layer "In2.Cu")
		(net "PCIE_T2B_B2_RX_DP<13>")
	)
	(segment
		(start -161.182393 35.3949)
		(end -161.19362 35.3949)
		(width 0.127)
		(layer "In2.Cu")
		(net "PCIE_T2B_B2_RX_DP<13>")
	)
	(segment
		(start -174.298201 40.253089)
		(end -174.551162 40.506051)
		(width 0.127)
		(layer "In2.Cu")
		(net "PCIE_T2B_B2_RX_DP<13>")
	)
	(segment
		(start -174.551162 40.506051)
		(end -174.906048 40.506051)
		(width 0.127)
		(layer "In2.Cu")
		(net "PCIE_T2B_B2_RX_DP<13>")
	)
	(segment
		(start -173.780506 23.407911)
		(end -174.298201 23.925606)
		(width 0.127)
		(layer "In2.Cu")
		(net "PCIE_T2B_B2_RX_DP<13>")
	)
	(segment
		(start -167.930426 25.712349)
		(end -170.234864 23.407911)
		(width 0.127)
		(layer "In2.Cu")
		(net "PCIE_T2B_B2_RX_DP<13>")
	)
	(segment
		(start -159.756244 36.821049)
		(end -161.182393 35.3949)
		(width 0.127)
		(layer "In2.Cu")
		(net "PCIE_T2B_B2_RX_DP<13>")
	)
	(segment
		(start -155.349999 37.309999)
		(end -155.838949 36.821049)
		(width 0.127)
		(layer "In2.Cu")
		(net "PCIE_T2B_B2_RX_DP<13>")
	)
	(segment
		(start -170.234864 23.407911)
		(end -173.780506 23.407911)
		(width 0.127)
		(layer "In2.Cu")
		(net "PCIE_T2B_B2_RX_DP<13>")
	)
	(segment
		(start -174.906048 40.506051)
		(end -175.46 41.060002)
		(width 0.127)
		(layer "In2.Cu")
		(net "PCIE_T2B_B2_RX_DP<13>")
	)
	(segment
		(start -155.984999 35.404999)
		(end -156.619999 34.769999)
		(width 0.127)
		(layer "F.Cu")
		(net "PCIE_T2B_B2_RX_DP<12>")
	)
	(via
		(at -156.619999 34.769999)
		(size 0.5588)
		(drill 0.254)
		(layers "F.Cu" "B.Cu")
		(net "PCIE_T2B_B2_RX_DP<12>")
	)
	(segment
		(start -156.619999 34.769999)
		(end -157.108949 34.281049)
		(width 0.127)
		(layer "In2.Cu")
		(net "PCIE_T2B_B2_RX_DP<12>")
	)
	(segment
		(start -174.596392 22.365716)
		(end -176.2982 24.067524)
		(width 0.127)
		(layer "In2.Cu")
		(net "PCIE_T2B_B2_RX_DP<12>")
	)
	(segment
		(start -157.108949 34.281049)
		(end -159.603844 34.281049)
		(width 0.127)
		(layer "In2.Cu")
		(net "PCIE_T2B_B2_RX_DP<12>")
	)
	(segment
		(start -166.540932 25.243683)
		(end -166.6264 25.158215)
		(width 0.127)
		(layer "In2.Cu")
		(net "PCIE_T2B_B2_RX_DP<12>")
	)
	(segment
		(start -176.2982 24.067524)
		(end -176.2982 38.846191)
		(width 0.127)
		(layer "In2.Cu")
		(net "PCIE_T2B_B2_RX_DP<12>")
	)
	(segment
		(start -166.626484 25.158215)
		(end -169.418983 22.365716)
		(width 0.127)
		(layer "In2.Cu")
		(net "PCIE_T2B_B2_RX_DP<12>")
	)
	(segment
		(start -166.540932 27.343961)
		(end -166.540932 25.243683)
		(width 0.127)
		(layer "In2.Cu")
		(net "PCIE_T2B_B2_RX_DP<12>")
	)
	(segment
		(start -176.90605 39.206051)
		(end -177.460001 39.760002)
		(width 0.127)
		(layer "In2.Cu")
		(net "PCIE_T2B_B2_RX_DP<12>")
	)
	(segment
		(start -176.658059 39.206051)
		(end -176.90605 39.206051)
		(width 0.127)
		(layer "In2.Cu")
		(net "PCIE_T2B_B2_RX_DP<12>")
	)
	(segment
		(start -159.603844 34.281049)
		(end -166.540932 27.343961)
		(width 0.127)
		(layer "In2.Cu")
		(net "PCIE_T2B_B2_RX_DP<12>")
	)
	(segment
		(start -169.418983 22.365716)
		(end -174.596392 22.365716)
		(width 0.127)
		(layer "In2.Cu")
		(net "PCIE_T2B_B2_RX_DP<12>")
	)
	(segment
		(start -176.2982 38.846191)
		(end -176.658059 39.206051)
		(width 0.127)
		(layer "In2.Cu")
		(net "PCIE_T2B_B2_RX_DP<12>")
	)
	(segment
		(start -166.6264 25.158215)
		(end -166.626484 25.158215)
		(width 0.127)
		(layer "In2.Cu")
		(net "PCIE_T2B_B2_RX_DP<12>")
	)
	(segment
		(start -154.714999 32.864999)
		(end -155.349999 32.229999)
		(width 0.127)
		(layer "F.Cu")
		(net "PCIE_T2B_B2_RX_DP<11>")
	)
	(via
		(at -155.349999 32.229999)
		(size 0.5588)
		(drill 0.254)
		(layers "F.Cu" "B.Cu")
		(net "PCIE_T2B_B2_RX_DP<11>")
	)
	(segment
		(start -179.459999 41.060002)
		(end -178.906051 40.506053)
		(width 0.127)
		(layer "In2.Cu")
		(net "PCIE_T2B_B2_RX_DP<11>")
	)
	(segment
		(start -158.740244 31.741049)
		(end -155.838949 31.741049)
		(width 0.127)
		(layer "In2.Cu")
		(net "PCIE_T2B_B2_RX_DP<11>")
	)
	(segment
		(start -155.838949 31.741049)
		(end -155.349999 32.229999)
		(width 0.127)
		(layer "In2.Cu")
		(net "PCIE_T2B_B2_RX_DP<11>")
	)
	(segment
		(start -178.574832 40.506053)
		(end -178.298201 40.229422)
		(width 0.127)
		(layer "In2.Cu")
		(net "PCIE_T2B_B2_RX_DP<11>")
	)
	(segment
		(start -178.298201 23.756836)
		(end -175.406324 20.86496)
		(width 0.127)
		(layer "In2.Cu")
		(net "PCIE_T2B_B2_RX_DP<11>")
	)
	(segment
		(start -178.906051 40.506053)
		(end -178.574832 40.506053)
		(width 0.127)
		(layer "In2.Cu")
		(net "PCIE_T2B_B2_RX_DP<11>")
	)
	(segment
		(start -168.990195 20.86496)
		(end -165.3921 24.463055)
		(width 0.127)
		(layer "In2.Cu")
		(net "PCIE_T2B_B2_RX_DP<11>")
	)
	(segment
		(start -163.087393 27.3939)
		(end -158.740244 31.741049)
		(width 0.127)
		(layer "In2.Cu")
		(net "PCIE_T2B_B2_RX_DP<11>")
	)
	(segment
		(start -165.3921 25.8445)
		(end -163.8427 27.3939)
		(width 0.127)
		(layer "In2.Cu")
		(net "PCIE_T2B_B2_RX_DP<11>")
	)
	(segment
		(start -163.8427 27.3939)
		(end -163.087393 27.3939)
		(width 0.127)
		(layer "In2.Cu")
		(net "PCIE_T2B_B2_RX_DP<11>")
	)
	(segment
		(start -175.406324 20.86496)
		(end -168.990195 20.86496)
		(width 0.127)
		(layer "In2.Cu")
		(net "PCIE_T2B_B2_RX_DP<11>")
	)
	(segment
		(start -178.298201 40.229422)
		(end -178.298201 23.756836)
		(width 0.127)
		(layer "In2.Cu")
		(net "PCIE_T2B_B2_RX_DP<11>")
	)
	(segment
		(start -165.3921 24.463055)
		(end -165.3921 25.8445)
		(width 0.127)
		(layer "In2.Cu")
		(net "PCIE_T2B_B2_RX_DP<11>")
	)
	(segment
		(start -155.984999 30.324999)
		(end -156.619999 29.689999)
		(width 0.127)
		(layer "F.Cu")
		(net "PCIE_T2B_B2_RX_DP<10>")
	)
	(via
		(at -156.619999 29.689999)
		(size 0.5588)
		(drill 0.254)
		(layers "F.Cu" "B.Cu")
		(net "PCIE_T2B_B2_RX_DP<10>")
	)
	(segment
		(start -168.073067 19.685795)
		(end -176.204344 19.685795)
		(width 0.127)
		(layer "In2.Cu")
		(net "PCIE_T2B_B2_RX_DP<10>")
	)
	(segment
		(start -156.619999 29.689999)
		(end -157.108949 29.201049)
		(width 0.127)
		(layer "In2.Cu")
		(net "PCIE_T2B_B2_RX_DP<10>")
	)
	(segment
		(start -159.454901 29.201049)
		(end -163.753815 24.902135)
		(width 0.127)
		(layer "In2.Cu")
		(net "PCIE_T2B_B2_RX_DP<10>")
	)
	(segment
		(start -180.906049 39.206051)
		(end -181.46 39.760002)
		(width 0.127)
		(layer "In2.Cu")
		(net "PCIE_T2B_B2_RX_DP<10>")
	)
	(segment
		(start -180.3297 38.877692)
		(end -180.658059 39.206051)
		(width 0.127)
		(layer "In2.Cu")
		(net "PCIE_T2B_B2_RX_DP<10>")
	)
	(segment
		(start -163.753815 24.005047)
		(end -168.073067 19.685795)
		(width 0.127)
		(layer "In2.Cu")
		(net "PCIE_T2B_B2_RX_DP<10>")
	)
	(segment
		(start -180.658059 39.206051)
		(end -180.906049 39.206051)
		(width 0.127)
		(layer "In2.Cu")
		(net "PCIE_T2B_B2_RX_DP<10>")
	)
	(segment
		(start -176.204344 19.685795)
		(end -180.3297 23.811151)
		(width 0.127)
		(layer "In2.Cu")
		(net "PCIE_T2B_B2_RX_DP<10>")
	)
	(segment
		(start -157.108949 29.201049)
		(end -159.454901 29.201049)
		(width 0.127)
		(layer "In2.Cu")
		(net "PCIE_T2B_B2_RX_DP<10>")
	)
	(segment
		(start -163.753815 24.902135)
		(end -163.753815 24.005047)
		(width 0.127)
		(layer "In2.Cu")
		(net "PCIE_T2B_B2_RX_DP<10>")
	)
	(segment
		(start -180.3297 23.811151)
		(end -180.3297 38.877692)
		(width 0.127)
		(layer "In2.Cu")
		(net "PCIE_T2B_B2_RX_DP<10>")
	)
	(segment
		(start -159.007599 24.762399)
		(end -158.524999 25.244999)
		(width 0.127)
		(layer "F.Cu")
		(net "PCIE_T2B_B2_RX_DP<0>")
	)
	(segment
		(start -184.30112 43.04413)
		(end -184.30112 23.670773)
		(width 0.127)
		(layer "F.Cu")
		(net "PCIE_T2B_B2_RX_DP<0>")
	)
	(segment
		(start -160.509524 23.180563)
		(end -160.509524 23.981156)
		(width 0.127)
		(layer "F.Cu")
		(net "PCIE_T2B_B2_RX_DP<0>")
	)
	(segment
		(start -184.669392 43.412402)
		(end -184.30112 43.04413)
		(width 0.127)
		(layer "F.Cu")
		(net "PCIE_T2B_B2_RX_DP<0>")
	)
	(segment
		(start -159.728281 24.762399)
		(end -159.007599 24.762399)
		(width 0.127)
		(layer "F.Cu")
		(net "PCIE_T2B_B2_RX_DP<0>")
	)
	(segment
		(start -177.768997 17.13865)
		(end -166.551437 17.13865)
		(width 0.127)
		(layer "F.Cu")
		(net "PCIE_T2B_B2_RX_DP<0>")
	)
	(segment
		(start -185.46 43.960001)
		(end -184.912401 43.412402)
		(width 0.127)
		(layer "F.Cu")
		(net "PCIE_T2B_B2_RX_DP<0>")
	)
	(segment
		(start -160.509524 23.981156)
		(end -159.728281 24.762399)
		(width 0.127)
		(layer "F.Cu")
		(net "PCIE_T2B_B2_RX_DP<0>")
	)
	(segment
		(start -184.30112 23.670773)
		(end -177.768997 17.13865)
		(width 0.127)
		(layer "F.Cu")
		(net "PCIE_T2B_B2_RX_DP<0>")
	)
	(segment
		(start -166.551437 17.13865)
		(end -160.509524 23.180563)
		(width 0.127)
		(layer "F.Cu")
		(net "PCIE_T2B_B2_RX_DP<0>")
	)
	(segment
		(start -184.912401 43.412402)
		(end -184.669392 43.412402)
		(width 0.127)
		(layer "F.Cu")
		(net "PCIE_T2B_B2_RX_DP<0>")
	)
	(segment
		(start -154.714999 26.514999)
		(end -155.349999 25.879999)
		(width 0.127)
		(layer "F.Cu")
		(net "PCIE_T2B_B2_RX_DN<9>")
	)
	(via
		(at -155.349999 25.879999)
		(size 0.5588)
		(drill 0.254)
		(layers "F.Cu" "B.Cu")
		(net "PCIE_T2B_B2_RX_DN<9>")
	)
	(segment
		(start -182.757392 40.213953)
		(end -182.906048 40.213953)
		(width 0.127)
		(layer "In2.Cu")
		(net "PCIE_T2B_B2_RX_DN<9>")
	)
	(segment
		(start -177.623612 18.023957)
		(end -182.608263 23.008608)
		(width 0.127)
		(layer "In2.Cu")
		(net "PCIE_T2B_B2_RX_DN<9>")
	)
	(segment
		(start -158.691077 25.621234)
		(end -158.776627 25.535684)
		(width 0.127)
		(layer "In2.Cu")
		(net "PCIE_T2B_B2_RX_DN<9>")
	)
	(segment
		(start -160.180492 25.450127)
		(end -167.606663 18.023957)
		(width 0.127)
		(layer "In2.Cu")
		(net "PCIE_T2B_B2_RX_DN<9>")
	)
	(segment
		(start -158.691077 25.621239)
		(end -158.691077 25.621234)
		(width 0.127)
		(layer "In2.Cu")
		(net "PCIE_T2B_B2_RX_DN<9>")
	)
	(segment
		(start -157.943367 26.368949)
		(end -158.691077 25.621239)
		(width 0.127)
		(layer "In2.Cu")
		(net "PCIE_T2B_B2_RX_DN<9>")
	)
	(segment
		(start -158.776629 25.535682)
		(end -158.862182 25.450127)
		(width 0.127)
		(layer "In2.Cu")
		(net "PCIE_T2B_B2_RX_DN<9>")
	)
	(segment
		(start -182.608263 23.008608)
		(end -182.608263 40.064825)
		(width 0.127)
		(layer "In2.Cu")
		(net "PCIE_T2B_B2_RX_DN<9>")
	)
	(segment
		(start -182.906048 40.213953)
		(end -183.459999 39.660002)
		(width 0.127)
		(layer "In2.Cu")
		(net "PCIE_T2B_B2_RX_DN<9>")
	)
	(segment
		(start -155.349999 25.879999)
		(end -155.838949 26.368949)
		(width 0.127)
		(layer "In2.Cu")
		(net "PCIE_T2B_B2_RX_DN<9>")
	)
	(segment
		(start -167.606663 18.023957)
		(end -177.623612 18.023957)
		(width 0.127)
		(layer "In2.Cu")
		(net "PCIE_T2B_B2_RX_DN<9>")
	)
	(segment
		(start -182.608263 40.064825)
		(end -182.757392 40.213953)
		(width 0.127)
		(layer "In2.Cu")
		(net "PCIE_T2B_B2_RX_DN<9>")
	)
	(segment
		(start -158.862182 25.450127)
		(end -160.180492 25.450127)
		(width 0.127)
		(layer "In2.Cu")
		(net "PCIE_T2B_B2_RX_DN<9>")
	)
	(segment
		(start -158.776627 25.535679)
		(end -158.776629 25.535682)
		(width 0.127)
		(layer "In2.Cu")
		(net "PCIE_T2B_B2_RX_DN<9>")
	)
	(segment
		(start -155.838949 26.368949)
		(end -157.943367 26.368949)
		(width 0.127)
		(layer "In2.Cu")
		(net "PCIE_T2B_B2_RX_DN<9>")
	)
	(segment
		(start -158.776627 25.535684)
		(end -158.776627 25.535679)
		(width 0.127)
		(layer "In2.Cu")
		(net "PCIE_T2B_B2_RX_DN<9>")
	)
	(segment
		(start -155.984999 23.974999)
		(end -156.619999 23.339999)
		(width 0.127)
		(layer "F.Cu")
		(net "PCIE_T2B_B2_RX_DN<8>")
	)
	(via
		(at -156.619999 23.339999)
		(size 0.5588)
		(drill 0.254)
		(layers "F.Cu" "B.Cu")
		(net "PCIE_T2B_B2_RX_DN<8>")
	)
	(segment
		(start -184.6218 38.756699)
		(end -184.6218 22.973495)
		(width 0.127)
		(layer "In2.Cu")
		(net "PCIE_T2B_B2_RX_DN<8>")
	)
	(segment
		(start -184.779051 38.913951)
		(end -184.6218 38.756699)
		(width 0.127)
		(layer "In2.Cu")
		(net "PCIE_T2B_B2_RX_DN<8>")
	)
	(segment
		(start -184.906051 38.913951)
		(end -184.779051 38.913951)
		(width 0.127)
		(layer "In2.Cu")
		(net "PCIE_T2B_B2_RX_DN<8>")
	)
	(segment
		(start -184.6218 22.973495)
		(end -178.338256 16.689951)
		(width 0.127)
		(layer "In2.Cu")
		(net "PCIE_T2B_B2_RX_DN<8>")
	)
	(segment
		(start -166.820553 16.689951)
		(end -159.681555 23.828949)
		(width 0.127)
		(layer "In2.Cu")
		(net "PCIE_T2B_B2_RX_DN<8>")
	)
	(segment
		(start -157.108949 23.828949)
		(end -156.619999 23.339999)
		(width 0.127)
		(layer "In2.Cu")
		(net "PCIE_T2B_B2_RX_DN<8>")
	)
	(segment
		(start -185.46 38.360002)
		(end -184.906051 38.913951)
		(width 0.127)
		(layer "In2.Cu")
		(net "PCIE_T2B_B2_RX_DN<8>")
	)
	(segment
		(start -178.338256 16.689951)
		(end -166.820553 16.689951)
		(width 0.127)
		(layer "In2.Cu")
		(net "PCIE_T2B_B2_RX_DN<8>")
	)
	(segment
		(start -159.681555 23.828949)
		(end -157.108949 23.828949)
		(width 0.127)
		(layer "In2.Cu")
		(net "PCIE_T2B_B2_RX_DN<8>")
	)
	(segment
		(start -170.912399 44.407602)
		(end -162.16537 44.407602)
		(width 0.127)
		(layer "F.Cu")
		(net "PCIE_T2B_B2_RX_DN<7>")
	)
	(segment
		(start -171.46 43.860001)
		(end -170.912399 44.407602)
		(width 0.127)
		(layer "F.Cu")
		(net "PCIE_T2B_B2_RX_DN<7>")
	)
	(segment
		(start -162.16537 44.407602)
		(end -159.995367 42.237599)
		(width 0.127)
		(layer "F.Cu")
		(net "PCIE_T2B_B2_RX_DN<7>")
	)
	(segment
		(start -159.995367 42.237599)
		(end -157.737599 42.237599)
		(width 0.127)
		(layer "F.Cu")
		(net "PCIE_T2B_B2_RX_DN<7>")
	)
	(segment
		(start -157.737599 42.237599)
		(end -157.254999 41.754999)
		(width 0.127)
		(layer "F.Cu")
		(net "PCIE_T2B_B2_RX_DN<7>")
	)
	(segment
		(start -170.536936 24.48433)
		(end -171.959336 24.48433)
		(width 0.127)
		(layer "F.Cu")
		(net "PCIE_T2B_B2_RX_DN<6>")
	)
	(segment
		(start -172.9124 43.107602)
		(end -173.460001 42.560001)
		(width 0.127)
		(layer "F.Cu")
		(net "PCIE_T2B_B2_RX_DN<6>")
	)
	(segment
		(start -172.7854 43.107602)
		(end -172.9124 43.107602)
		(width 0.127)
		(layer "F.Cu")
		(net "PCIE_T2B_B2_RX_DN<6>")
	)
	(segment
		(start -171.959336 24.48433)
		(end -172.603226 25.12822)
		(width 0.127)
		(layer "F.Cu")
		(net "PCIE_T2B_B2_RX_DN<6>")
	)
	(segment
		(start -159.667748 39.697599)
		(end -160.5788 38.786547)
		(width 0.127)
		(layer "F.Cu")
		(net "PCIE_T2B_B2_RX_DN<6>")
	)
	(segment
		(start -160.5788 37.324843)
		(end -163.816843 34.0868)
		(width 0.127)
		(layer "F.Cu")
		(net "PCIE_T2B_B2_RX_DN<6>")
	)
	(segment
		(start -169.843008 25.178258)
		(end -170.536936 24.48433)
		(width 0.127)
		(layer "F.Cu")
		(net "PCIE_T2B_B2_RX_DN<6>")
	)
	(segment
		(start -169.843008 30.885638)
		(end -169.843008 25.178258)
		(width 0.127)
		(layer "F.Cu")
		(net "PCIE_T2B_B2_RX_DN<6>")
	)
	(segment
		(start -166.641846 34.0868)
		(end -169.843008 30.885638)
		(width 0.127)
		(layer "F.Cu")
		(net "PCIE_T2B_B2_RX_DN<6>")
	)
	(segment
		(start -158.524999 39.214999)
		(end -159.007599 39.697599)
		(width 0.127)
		(layer "F.Cu")
		(net "PCIE_T2B_B2_RX_DN<6>")
	)
	(segment
		(start -163.816843 34.0868)
		(end -166.641846 34.0868)
		(width 0.127)
		(layer "F.Cu")
		(net "PCIE_T2B_B2_RX_DN<6>")
	)
	(segment
		(start -159.007599 39.697599)
		(end -159.667748 39.697599)
		(width 0.127)
		(layer "F.Cu")
		(net "PCIE_T2B_B2_RX_DN<6>")
	)
	(segment
		(start -160.5788 38.786547)
		(end -160.5788 37.324843)
		(width 0.127)
		(layer "F.Cu")
		(net "PCIE_T2B_B2_RX_DN<6>")
	)
	(segment
		(start -172.603226 42.925429)
		(end -172.7854 43.107602)
		(width 0.127)
		(layer "F.Cu")
		(net "PCIE_T2B_B2_RX_DN<6>")
	)
	(segment
		(start -172.603226 25.12822)
		(end -172.603226 42.925429)
		(width 0.127)
		(layer "F.Cu")
		(net "PCIE_T2B_B2_RX_DN<6>")
	)
	(segment
		(start -169.561439 23.217886)
		(end -168.529 24.250325)
		(width 0.127)
		(layer "F.Cu")
		(net "PCIE_T2B_B2_RX_DN<5>")
	)
	(segment
		(start -175.46 43.860001)
		(end -174.912398 44.407602)
		(width 0.127)
		(layer "F.Cu")
		(net "PCIE_T2B_B2_RX_DN<5>")
	)
	(segment
		(start -160.02 36.017947)
		(end -158.880348 37.157599)
		(width 0.127)
		(layer "F.Cu")
		(net "PCIE_T2B_B2_RX_DN<5>")
	)
	(segment
		(start -174.785398 44.407602)
		(end -174.605 44.227204)
		(width 0.127)
		(layer "F.Cu")
		(net "PCIE_T2B_B2_RX_DN<5>")
	)
	(segment
		(start -174.605 44.227204)
		(end -174.605 23.955111)
		(width 0.127)
		(layer "F.Cu")
		(net "PCIE_T2B_B2_RX_DN<5>")
	)
	(segment
		(start -160.02 36.009885)
		(end -160.02 36.017947)
		(width 0.127)
		(layer "F.Cu")
		(net "PCIE_T2B_B2_RX_DN<5>")
	)
	(segment
		(start -172.985633 23.217886)
		(end -169.561439 23.217886)
		(width 0.127)
		(layer "F.Cu")
		(net "PCIE_T2B_B2_RX_DN<5>")
	)
	(segment
		(start -174.603001 23.953112)
		(end -174.603001 23.886518)
		(width 0.127)
		(layer "F.Cu")
		(net "PCIE_T2B_B2_RX_DN<5>")
	)
	(segment
		(start -157.737599 37.157599)
		(end -157.254999 36.674999)
		(width 0.127)
		(layer "F.Cu")
		(net "PCIE_T2B_B2_RX_DN<5>")
	)
	(segment
		(start -168.529064 30.352937)
		(end -166.0144 32.8676)
		(width 0.127)
		(layer "F.Cu")
		(net "PCIE_T2B_B2_RX_DN<5>")
	)
	(segment
		(start -166.0144 32.8676)
		(end -163.162285 32.8676)
		(width 0.127)
		(layer "F.Cu")
		(net "PCIE_T2B_B2_RX_DN<5>")
	)
	(segment
		(start -174.605 23.955111)
		(end -174.603001 23.953112)
		(width 0.127)
		(layer "F.Cu")
		(net "PCIE_T2B_B2_RX_DN<5>")
	)
	(segment
		(start -174.912398 44.407602)
		(end -174.785398 44.407602)
		(width 0.127)
		(layer "F.Cu")
		(net "PCIE_T2B_B2_RX_DN<5>")
	)
	(segment
		(start -168.529064 27.500948)
		(end -168.529064 30.352937)
		(width 0.127)
		(layer "F.Cu")
		(net "PCIE_T2B_B2_RX_DN<5>")
	)
	(segment
		(start -174.603001 23.886518)
		(end -173.933485 23.217002)
		(width 0.127)
		(layer "F.Cu")
		(net "PCIE_T2B_B2_RX_DN<5>")
	)
	(segment
		(start -168.529 24.250325)
		(end -168.529 27.500885)
		(width 0.127)
		(layer "F.Cu")
		(net "PCIE_T2B_B2_RX_DN<5>")
	)
	(segment
		(start -163.162285 32.8676)
		(end -160.02 36.009885)
		(width 0.127)
		(layer "F.Cu")
		(net "PCIE_T2B_B2_RX_DN<5>")
	)
	(segment
		(start -172.986517 23.217002)
		(end -172.985633 23.217886)
		(width 0.127)
		(layer "F.Cu")
		(net "PCIE_T2B_B2_RX_DN<5>")
	)
	(segment
		(start -168.529 27.500885)
		(end -168.529064 27.500948)
		(width 0.127)
		(layer "F.Cu")
		(net "PCIE_T2B_B2_RX_DN<5>")
	)
	(segment
		(start -173.933485 23.217002)
		(end -172.986517 23.217002)
		(width 0.127)
		(layer "F.Cu")
		(net "PCIE_T2B_B2_RX_DN<5>")
	)
	(segment
		(start -158.880348 37.157599)
		(end -157.737599 37.157599)
		(width 0.127)
		(layer "F.Cu")
		(net "PCIE_T2B_B2_RX_DN<5>")
	)
	(segment
		(start -176.9124 43.107602)
		(end -176.7854 43.107602)
		(width 0.127)
		(layer "F.Cu")
		(net "PCIE_T2B_B2_RX_DN<4>")
	)
	(segment
		(start -176.6116 42.933803)
		(end -176.6116 24.14016)
		(width 0.127)
		(layer "F.Cu")
		(net "PCIE_T2B_B2_RX_DN<4>")
	)
	(segment
		(start -174.388338 21.916898)
		(end -169.138216 21.916898)
		(width 0.127)
		(layer "F.Cu")
		(net "PCIE_T2B_B2_RX_DN<4>")
	)
	(segment
		(start -169.138216 21.916898)
		(end -167.0812 23.973914)
		(width 0.127)
		(layer "F.Cu")
		(net "PCIE_T2B_B2_RX_DN<4>")
	)
	(segment
		(start -162.1536 32.151881)
		(end -159.68788 34.617599)
		(width 0.127)
		(layer "F.Cu")
		(net "PCIE_T2B_B2_RX_DN<4>")
	)
	(segment
		(start -159.68788 34.617599)
		(end -159.007599 34.617599)
		(width 0.127)
		(layer "F.Cu")
		(net "PCIE_T2B_B2_RX_DN<4>")
	)
	(segment
		(start -159.007599 34.617599)
		(end -158.524999 34.134999)
		(width 0.127)
		(layer "F.Cu")
		(net "PCIE_T2B_B2_RX_DN<4>")
	)
	(segment
		(start -162.1536 30.4038)
		(end -162.1536 32.151881)
		(width 0.127)
		(layer "F.Cu")
		(net "PCIE_T2B_B2_RX_DN<4>")
	)
	(segment
		(start -176.6116 24.14016)
		(end -174.388338 21.916898)
		(width 0.127)
		(layer "F.Cu")
		(net "PCIE_T2B_B2_RX_DN<4>")
	)
	(segment
		(start -176.7854 43.107602)
		(end -176.6116 42.933803)
		(width 0.127)
		(layer "F.Cu")
		(net "PCIE_T2B_B2_RX_DN<4>")
	)
	(segment
		(start -177.460001 42.560001)
		(end -176.9124 43.107602)
		(width 0.127)
		(layer "F.Cu")
		(net "PCIE_T2B_B2_RX_DN<4>")
	)
	(segment
		(start -167.0812 23.973914)
		(end -167.0812 25.4762)
		(width 0.127)
		(layer "F.Cu")
		(net "PCIE_T2B_B2_RX_DN<4>")
	)
	(segment
		(start -167.0812 25.4762)
		(end -162.1536 30.4038)
		(width 0.127)
		(layer "F.Cu")
		(net "PCIE_T2B_B2_RX_DN<4>")
	)
	(segment
		(start -157.737599 32.077599)
		(end -160.219771 32.077599)
		(width 0.127)
		(layer "F.Cu")
		(net "PCIE_T2B_B2_RX_DN<3>")
	)
	(segment
		(start -175.56766 20.684998)
		(end -178.6182 23.735538)
		(width 0.127)
		(layer "F.Cu")
		(net "PCIE_T2B_B2_RX_DN<3>")
	)
	(segment
		(start -160.219771 32.077599)
		(end -160.7312 31.56617)
		(width 0.127)
		(layer "F.Cu")
		(net "PCIE_T2B_B2_RX_DN<3>")
	)
	(segment
		(start -160.7312 30.048947)
		(end -165.6842 25.095947)
		(width 0.127)
		(layer "F.Cu")
		(net "PCIE_T2B_B2_RX_DN<3>")
	)
	(segment
		(start -160.7312 31.56617)
		(end -160.7312 30.048947)
		(width 0.127)
		(layer "F.Cu")
		(net "PCIE_T2B_B2_RX_DN<3>")
	)
	(segment
		(start -165.6842 23.646704)
		(end -168.645906 20.684998)
		(width 0.127)
		(layer "F.Cu")
		(net "PCIE_T2B_B2_RX_DN<3>")
	)
	(segment
		(start -178.785398 44.407602)
		(end -178.912398 44.407602)
		(width 0.127)
		(layer "F.Cu")
		(net "PCIE_T2B_B2_RX_DN<3>")
	)
	(segment
		(start -178.912398 44.407602)
		(end -179.459999 43.860001)
		(width 0.127)
		(layer "F.Cu")
		(net "PCIE_T2B_B2_RX_DN<3>")
	)
	(segment
		(start -168.645906 20.684998)
		(end -175.56766 20.684998)
		(width 0.127)
		(layer "F.Cu")
		(net "PCIE_T2B_B2_RX_DN<3>")
	)
	(segment
		(start -178.6182 23.735538)
		(end -178.6182 44.240404)
		(width 0.127)
		(layer "F.Cu")
		(net "PCIE_T2B_B2_RX_DN<3>")
	)
	(segment
		(start -157.254999 31.594999)
		(end -157.737599 32.077599)
		(width 0.127)
		(layer "F.Cu")
		(net "PCIE_T2B_B2_RX_DN<3>")
	)
	(segment
		(start -178.6182 44.240404)
		(end -178.785398 44.407602)
		(width 0.127)
		(layer "F.Cu")
		(net "PCIE_T2B_B2_RX_DN<3>")
	)
	(segment
		(start -165.6842 25.095947)
		(end -165.6842 23.646704)
		(width 0.127)
		(layer "F.Cu")
		(net "PCIE_T2B_B2_RX_DN<3>")
	)
	(segment
		(start -162.92862 25.794127)
		(end -162.92862 24.37257)
		(width 0.127)
		(layer "F.Cu")
		(net "PCIE_T2B_B2_RX_DN<2>")
	)
	(segment
		(start -180.614213 42.936417)
		(end -180.785399 43.107602)
		(width 0.127)
		(layer "F.Cu")
		(net "PCIE_T2B_B2_RX_DN<2>")
	)
	(segment
		(start -167.847838 19.453352)
		(end -176.556482 19.453352)
		(width 0.127)
		(layer "F.Cu")
		(net "PCIE_T2B_B2_RX_DN<2>")
	)
	(segment
		(start -159.007599 29.537599)
		(end -159.185148 29.537599)
		(width 0.127)
		(layer "F.Cu")
		(net "PCIE_T2B_B2_RX_DN<2>")
	)
	(segment
		(start -180.614213 23.511083)
		(end -180.614213 42.936417)
		(width 0.127)
		(layer "F.Cu")
		(net "PCIE_T2B_B2_RX_DN<2>")
	)
	(segment
		(start -176.556482 19.453352)
		(end -180.614213 23.511083)
		(width 0.127)
		(layer "F.Cu")
		(net "PCIE_T2B_B2_RX_DN<2>")
	)
	(segment
		(start -159.185148 29.537599)
		(end -162.92862 25.794127)
		(width 0.127)
		(layer "F.Cu")
		(net "PCIE_T2B_B2_RX_DN<2>")
	)
	(segment
		(start -162.92862 24.37257)
		(end -167.847838 19.453352)
		(width 0.127)
		(layer "F.Cu")
		(net "PCIE_T2B_B2_RX_DN<2>")
	)
	(segment
		(start -180.912399 43.107602)
		(end -181.46 42.560001)
		(width 0.127)
		(layer "F.Cu")
		(net "PCIE_T2B_B2_RX_DN<2>")
	)
	(segment
		(start -180.785399 43.107602)
		(end -180.912399 43.107602)
		(width 0.127)
		(layer "F.Cu")
		(net "PCIE_T2B_B2_RX_DN<2>")
	)
	(segment
		(start -158.524999 29.054999)
		(end -159.007599 29.537599)
		(width 0.127)
		(layer "F.Cu")
		(net "PCIE_T2B_B2_RX_DN<2>")
	)
	(segment
		(start -177.372076 18.152364)
		(end -167.15391 18.152364)
		(width 0.127)
		(layer "F.Cu")
		(net "PCIE_T2B_B2_RX_DN<1>")
	)
	(segment
		(start -161.840723 23.465551)
		(end -161.840636 23.465551)
		(width 0.127)
		(layer "F.Cu")
		(net "PCIE_T2B_B2_RX_DN<1>")
	)
	(segment
		(start -161.840636 23.465551)
		(end -161.662176 23.644012)
		(width 0.127)
		(layer "F.Cu")
		(net "PCIE_T2B_B2_RX_DN<1>")
	)
	(segment
		(start -182.785398 44.407602)
		(end -182.606 44.228205)
		(width 0.127)
		(layer "F.Cu")
		(net "PCIE_T2B_B2_RX_DN<1>")
	)
	(segment
		(start -157.737599 26.997599)
		(end -157.254999 26.514999)
		(width 0.127)
		(layer "F.Cu")
		(net "PCIE_T2B_B2_RX_DN<1>")
	)
	(segment
		(start -161.662176 25.27636)
		(end -159.940937 26.997599)
		(width 0.127)
		(layer "F.Cu")
		(net "PCIE_T2B_B2_RX_DN<1>")
	)
	(segment
		(start -167.15391 18.152364)
		(end -161.840723 23.465551)
		(width 0.127)
		(layer "F.Cu")
		(net "PCIE_T2B_B2_RX_DN<1>")
	)
	(segment
		(start -182.912398 44.407602)
		(end -182.785398 44.407602)
		(width 0.127)
		(layer "F.Cu")
		(net "PCIE_T2B_B2_RX_DN<1>")
	)
	(segment
		(start -159.940937 26.997599)
		(end -157.737599 26.997599)
		(width 0.127)
		(layer "F.Cu")
		(net "PCIE_T2B_B2_RX_DN<1>")
	)
	(segment
		(start -161.662176 23.644012)
		(end -161.662176 25.27636)
		(width 0.127)
		(layer "F.Cu")
		(net "PCIE_T2B_B2_RX_DN<1>")
	)
	(segment
		(start -182.606 44.228205)
		(end -182.606 23.386288)
		(width 0.127)
		(layer "F.Cu")
		(net "PCIE_T2B_B2_RX_DN<1>")
	)
	(segment
		(start -183.459999 43.860001)
		(end -182.912398 44.407602)
		(width 0.127)
		(layer "F.Cu")
		(net "PCIE_T2B_B2_RX_DN<1>")
	)
	(segment
		(start -182.606 23.386288)
		(end -177.372076 18.152364)
		(width 0.127)
		(layer "F.Cu")
		(net "PCIE_T2B_B2_RX_DN<1>")
	)
	(segment
		(start -154.714999 41.754999)
		(end -155.349999 41.119999)
		(width 0.127)
		(layer "F.Cu")
		(net "PCIE_T2B_B2_RX_DN<15>")
	)
	(via
		(at -155.349999 41.119999)
		(size 0.5588)
		(drill 0.254)
		(layers "F.Cu" "B.Cu")
		(net "PCIE_T2B_B2_RX_DN<15>")
	)
	(segment
		(start -156.960435 41.608949)
		(end -155.838949 41.608949)
		(width 0.127)
		(layer "In2.Cu")
		(net "PCIE_T2B_B2_RX_DN<15>")
	)
	(segment
		(start -170.381625 40.213951)
		(end -169.866594 40.728981)
		(width 0.127)
		(layer "In2.Cu")
		(net "PCIE_T2B_B2_RX_DN<15>")
	)
	(segment
		(start -155.838949 41.608949)
		(end -155.349999 41.119999)
		(width 0.127)
		(layer "In2.Cu")
		(net "PCIE_T2B_B2_RX_DN<15>")
	)
	(segment
		(start -171.46 39.660002)
		(end -170.906051 40.213951)
		(width 0.127)
		(layer "In2.Cu")
		(net "PCIE_T2B_B2_RX_DN<15>")
	)
	(segment
		(start -167.366551 44.322637)
		(end -159.674123 44.322637)
		(width 0.127)
		(layer "In2.Cu")
		(net "PCIE_T2B_B2_RX_DN<15>")
	)
	(segment
		(start -169.866594 40.728981)
		(end -169.866594 41.822594)
		(width 0.127)
		(layer "In2.Cu")
		(net "PCIE_T2B_B2_RX_DN<15>")
	)
	(segment
		(start -159.674123 44.322637)
		(end -156.960435 41.608949)
		(width 0.127)
		(layer "In2.Cu")
		(net "PCIE_T2B_B2_RX_DN<15>")
	)
	(segment
		(start -169.866594 41.822594)
		(end -167.366551 44.322637)
		(width 0.127)
		(layer "In2.Cu")
		(net "PCIE_T2B_B2_RX_DN<15>")
	)
	(segment
		(start -170.906051 40.213951)
		(end -170.381625 40.213951)
		(width 0.127)
		(layer "In2.Cu")
		(net "PCIE_T2B_B2_RX_DN<15>")
	)
	(segment
		(start -155.984999 39.214999)
		(end -156.619999 38.579999)
		(width 0.127)
		(layer "F.Cu")
		(net "PCIE_T2B_B2_RX_DN<14>")
	)
	(via
		(at -156.619999 38.579999)
		(size 0.5588)
		(drill 0.254)
		(layers "F.Cu" "B.Cu")
		(net "PCIE_T2B_B2_RX_DN<14>")
	)
	(segment
		(start -172.5903 25.091982)
		(end -172.007685 24.509367)
		(width 0.127)
		(layer "In2.Cu")
		(net "PCIE_T2B_B2_RX_DN<14>")
	)
	(segment
		(start -172.5903 38.816961)
		(end -172.5903 25.091982)
		(width 0.127)
		(layer "In2.Cu")
		(net "PCIE_T2B_B2_RX_DN<14>")
	)
	(segment
		(start -169.464452 25.754325)
		(end -169.464452 29.188948)
		(width 0.127)
		(layer "In2.Cu")
		(net "PCIE_T2B_B2_RX_DN<14>")
	)
	(segment
		(start -172.007685 24.509367)
		(end -170.951395 24.509367)
		(width 0.127)
		(layer "In2.Cu")
		(net "PCIE_T2B_B2_RX_DN<14>")
	)
	(segment
		(start -172.68729 38.913951)
		(end -172.5903 38.816961)
		(width 0.127)
		(layer "In2.Cu")
		(net "PCIE_T2B_B2_RX_DN<14>")
	)
	(segment
		(start -170.951395 24.509367)
		(end -170.951335 24.509306)
		(width 0.127)
		(layer "In2.Cu")
		(net "PCIE_T2B_B2_RX_DN<14>")
	)
	(segment
		(start -172.906052 38.913951)
		(end -172.68729 38.913951)
		(width 0.127)
		(layer "In2.Cu")
		(net "PCIE_T2B_B2_RX_DN<14>")
	)
	(segment
		(start -169.464452 29.188948)
		(end -159.584451 39.068949)
		(width 0.127)
		(layer "In2.Cu")
		(net "PCIE_T2B_B2_RX_DN<14>")
	)
	(segment
		(start -173.460001 38.360002)
		(end -172.906052 38.913951)
		(width 0.127)
		(layer "In2.Cu")
		(net "PCIE_T2B_B2_RX_DN<14>")
	)
	(segment
		(start -159.584451 39.068949)
		(end -157.108949 39.068949)
		(width 0.127)
		(layer "In2.Cu")
		(net "PCIE_T2B_B2_RX_DN<14>")
	)
	(segment
		(start -170.951335 24.509306)
		(end -170.709471 24.509306)
		(width 0.127)
		(layer "In2.Cu")
		(net "PCIE_T2B_B2_RX_DN<14>")
	)
	(segment
		(start -170.709471 24.509306)
		(end -169.464452 25.754325)
		(width 0.127)
		(layer "In2.Cu")
		(net "PCIE_T2B_B2_RX_DN<14>")
	)
	(segment
		(start -157.108949 39.068949)
		(end -156.619999 38.579999)
		(width 0.127)
		(layer "In2.Cu")
		(net "PCIE_T2B_B2_RX_DN<14>")
	)
	(segment
		(start -154.714999 36.674999)
		(end -155.349999 36.039999)
		(width 0.127)
		(layer "F.Cu")
		(net "PCIE_T2B_B2_RX_DN<13>")
	)
	(via
		(at -155.349999 36.039999)
		(size 0.5588)
		(drill 0.254)
		(layers "F.Cu" "B.Cu")
		(net "PCIE_T2B_B2_RX_DN<13>")
	)
	(segment
		(start -173.901499 23.115811)
		(end -170.113871 23.115811)
		(width 0.127)
		(layer "In2.Cu")
		(net "PCIE_T2B_B2_RX_DN<13>")
	)
	(segment
		(start -161.072627 35.1028)
		(end -161.0614 35.1028)
		(width 0.127)
		(layer "In2.Cu")
		(net "PCIE_T2B_B2_RX_DN<13>")
	)
	(segment
		(start -174.672155 40.213951)
		(end -174.590301 40.132097)
		(width 0.127)
		(layer "In2.Cu")
		(net "PCIE_T2B_B2_RX_DN<13>")
	)
	(segment
		(start -174.590301 23.804613)
		(end -173.901499 23.115811)
		(width 0.127)
		(layer "In2.Cu")
		(net "PCIE_T2B_B2_RX_DN<13>")
	)
	(segment
		(start -167.552774 28.622653)
		(end -161.072627 35.1028)
		(width 0.127)
		(layer "In2.Cu")
		(net "PCIE_T2B_B2_RX_DN<13>")
	)
	(segment
		(start -175.46 39.660002)
		(end -174.906051 40.213951)
		(width 0.127)
		(layer "In2.Cu")
		(net "PCIE_T2B_B2_RX_DN<13>")
	)
	(segment
		(start -167.723881 25.505801)
		(end -167.723797 25.505801)
		(width 0.127)
		(layer "In2.Cu")
		(net "PCIE_T2B_B2_RX_DN<13>")
	)
	(segment
		(start -161.0614 35.1028)
		(end -159.635251 36.528949)
		(width 0.127)
		(layer "In2.Cu")
		(net "PCIE_T2B_B2_RX_DN<13>")
	)
	(segment
		(start -174.906051 40.213951)
		(end -174.672155 40.213951)
		(width 0.127)
		(layer "In2.Cu")
		(net "PCIE_T2B_B2_RX_DN<13>")
	)
	(segment
		(start -159.635251 36.528949)
		(end -155.838949 36.528949)
		(width 0.127)
		(layer "In2.Cu")
		(net "PCIE_T2B_B2_RX_DN<13>")
	)
	(segment
		(start -174.590301 40.132097)
		(end -174.590301 23.804613)
		(width 0.127)
		(layer "In2.Cu")
		(net "PCIE_T2B_B2_RX_DN<13>")
	)
	(segment
		(start -155.838949 36.528949)
		(end -155.349999 36.039999)
		(width 0.127)
		(layer "In2.Cu")
		(net "PCIE_T2B_B2_RX_DN<13>")
	)
	(segment
		(start -167.552774 25.676824)
		(end -167.552774 28.622653)
		(width 0.127)
		(layer "In2.Cu")
		(net "PCIE_T2B_B2_RX_DN<13>")
	)
	(segment
		(start -170.113871 23.115811)
		(end -167.723881 25.505801)
		(width 0.127)
		(layer "In2.Cu")
		(net "PCIE_T2B_B2_RX_DN<13>")
	)
	(segment
		(start -167.723797 25.505801)
		(end -167.552774 25.676824)
		(width 0.127)
		(layer "In2.Cu")
		(net "PCIE_T2B_B2_RX_DN<13>")
	)
	(segment
		(start -155.984999 34.134999)
		(end -156.619999 33.499999)
		(width 0.127)
		(layer "F.Cu")
		(net "PCIE_T2B_B2_RX_DN<12>")
	)
	(via
		(at -156.619999 33.499999)
		(size 0.5588)
		(drill 0.254)
		(layers "F.Cu" "B.Cu")
		(net "PCIE_T2B_B2_RX_DN<12>")
	)
	(segment
		(start -166.248832 27.222968)
		(end -159.482851 33.988949)
		(width 0.127)
		(layer "In2.Cu")
		(net "PCIE_T2B_B2_RX_DN<12>")
	)
	(segment
		(start -169.29799 22.073616)
		(end -166.419939 24.951667)
		(width 0.127)
		(layer "In2.Cu")
		(net "PCIE_T2B_B2_RX_DN<12>")
	)
	(segment
		(start -176.906052 38.913951)
		(end -176.779052 38.913951)
		(width 0.127)
		(layer "In2.Cu")
		(net "PCIE_T2B_B2_RX_DN<12>")
	)
	(segment
		(start -159.482851 33.988949)
		(end -157.108949 33.988949)
		(width 0.127)
		(layer "In2.Cu")
		(net "PCIE_T2B_B2_RX_DN<12>")
	)
	(segment
		(start -176.779052 38.913951)
		(end -176.5903 38.725198)
		(width 0.127)
		(layer "In2.Cu")
		(net "PCIE_T2B_B2_RX_DN<12>")
	)
	(segment
		(start -166.419855 24.951667)
		(end -166.248832 25.12269)
		(width 0.127)
		(layer "In2.Cu")
		(net "PCIE_T2B_B2_RX_DN<12>")
	)
	(segment
		(start -176.5903 23.946531)
		(end -174.717385 22.073616)
		(width 0.127)
		(layer "In2.Cu")
		(net "PCIE_T2B_B2_RX_DN<12>")
	)
	(segment
		(start -166.248832 25.12269)
		(end -166.248832 27.222968)
		(width 0.127)
		(layer "In2.Cu")
		(net "PCIE_T2B_B2_RX_DN<12>")
	)
	(segment
		(start -174.717385 22.073616)
		(end -169.29799 22.073616)
		(width 0.127)
		(layer "In2.Cu")
		(net "PCIE_T2B_B2_RX_DN<12>")
	)
	(segment
		(start -157.108949 33.988949)
		(end -156.619999 33.499999)
		(width 0.127)
		(layer "In2.Cu")
		(net "PCIE_T2B_B2_RX_DN<12>")
	)
	(segment
		(start -177.460001 38.360002)
		(end -176.906052 38.913951)
		(width 0.127)
		(layer "In2.Cu")
		(net "PCIE_T2B_B2_RX_DN<12>")
	)
	(segment
		(start -176.5903 38.725198)
		(end -176.5903 23.946531)
		(width 0.127)
		(layer "In2.Cu")
		(net "PCIE_T2B_B2_RX_DN<12>")
	)
	(segment
		(start -166.419939 24.951667)
		(end -166.419855 24.951667)
		(width 0.127)
		(layer "In2.Cu")
		(net "PCIE_T2B_B2_RX_DN<12>")
	)
	(segment
		(start -154.714999 31.594999)
		(end -155.349999 30.959999)
		(width 0.127)
		(layer "F.Cu")
		(net "PCIE_T2B_B2_RX_DN<11>")
	)
	(via
		(at -155.349999 30.959999)
		(size 0.5588)
		(drill 0.254)
		(layers "F.Cu" "B.Cu")
		(net "PCIE_T2B_B2_RX_DN<11>")
	)
	(segment
		(start -175.527317 20.57286)
		(end -168.869203 20.57286)
		(width 0.127)
		(layer "In2.Cu")
		(net "PCIE_T2B_B2_RX_DN<11>")
	)
	(segment
		(start -179.459999 39.660002)
		(end -178.906048 40.213953)
		(width 0.127)
		(layer "In2.Cu")
		(net "PCIE_T2B_B2_RX_DN<11>")
	)
	(segment
		(start -165.1 24.342062)
		(end -165.1 25.723507)
		(width 0.127)
		(layer "In2.Cu")
		(net "PCIE_T2B_B2_RX_DN<11>")
	)
	(segment
		(start -178.695825 40.213953)
		(end -178.590301 40.108429)
		(width 0.127)
		(layer "In2.Cu")
		(net "PCIE_T2B_B2_RX_DN<11>")
	)
	(segment
		(start -178.906048 40.213953)
		(end -178.695825 40.213953)
		(width 0.127)
		(layer "In2.Cu")
		(net "PCIE_T2B_B2_RX_DN<11>")
	)
	(segment
		(start -165.1 25.723507)
		(end -163.721707 27.1018)
		(width 0.127)
		(layer "In2.Cu")
		(net "PCIE_T2B_B2_RX_DN<11>")
	)
	(segment
		(start -168.869203 20.57286)
		(end -165.1 24.342062)
		(width 0.127)
		(layer "In2.Cu")
		(net "PCIE_T2B_B2_RX_DN<11>")
	)
	(segment
		(start -162.9664 27.1018)
		(end -158.619251 31.448949)
		(width 0.127)
		(layer "In2.Cu")
		(net "PCIE_T2B_B2_RX_DN<11>")
	)
	(segment
		(start -163.721707 27.1018)
		(end -162.9664 27.1018)
		(width 0.127)
		(layer "In2.Cu")
		(net "PCIE_T2B_B2_RX_DN<11>")
	)
	(segment
		(start -155.838949 31.448949)
		(end -155.349999 30.959999)
		(width 0.127)
		(layer "In2.Cu")
		(net "PCIE_T2B_B2_RX_DN<11>")
	)
	(segment
		(start -178.590301 23.635843)
		(end -175.527317 20.57286)
		(width 0.127)
		(layer "In2.Cu")
		(net "PCIE_T2B_B2_RX_DN<11>")
	)
	(segment
		(start -178.590301 40.108429)
		(end -178.590301 23.635843)
		(width 0.127)
		(layer "In2.Cu")
		(net "PCIE_T2B_B2_RX_DN<11>")
	)
	(segment
		(start -158.619251 31.448949)
		(end -155.838949 31.448949)
		(width 0.127)
		(layer "In2.Cu")
		(net "PCIE_T2B_B2_RX_DN<11>")
	)
	(segment
		(start -155.984999 29.054999)
		(end -156.619999 28.419999)
		(width 0.127)
		(layer "F.Cu")
		(net "PCIE_T2B_B2_RX_DN<10>")
	)
	(via
		(at -156.619999 28.419999)
		(size 0.5588)
		(drill 0.254)
		(layers "F.Cu" "B.Cu")
		(net "PCIE_T2B_B2_RX_DN<10>")
	)
	(segment
		(start -163.632822 23.712947)
		(end -167.952075 19.393695)
		(width 0.127)
		(layer "In2.Cu")
		(net "PCIE_T2B_B2_RX_DN<10>")
	)
	(segment
		(start -163.461715 24.781142)
		(end -163.461715 23.883971)
		(width 0.127)
		(layer "In2.Cu")
		(net "PCIE_T2B_B2_RX_DN<10>")
	)
	(segment
		(start -163.632739 23.712947)
		(end -163.632822 23.712947)
		(width 0.127)
		(layer "In2.Cu")
		(net "PCIE_T2B_B2_RX_DN<10>")
	)
	(segment
		(start -156.619999 28.419999)
		(end -157.108949 28.908949)
		(width 0.127)
		(layer "In2.Cu")
		(net "PCIE_T2B_B2_RX_DN<10>")
	)
	(segment
		(start -157.108949 28.908949)
		(end -159.333908 28.908949)
		(width 0.127)
		(layer "In2.Cu")
		(net "PCIE_T2B_B2_RX_DN<10>")
	)
	(segment
		(start -159.333908 28.908949)
		(end -163.461715 24.781142)
		(width 0.127)
		(layer "In2.Cu")
		(net "PCIE_T2B_B2_RX_DN<10>")
	)
	(segment
		(start -180.6218 23.690158)
		(end -180.6218 38.756699)
		(width 0.127)
		(layer "In2.Cu")
		(net "PCIE_T2B_B2_RX_DN<10>")
	)
	(segment
		(start -180.6218 38.756699)
		(end -180.779052 38.913951)
		(width 0.127)
		(layer "In2.Cu")
		(net "PCIE_T2B_B2_RX_DN<10>")
	)
	(segment
		(start -167.952075 19.393695)
		(end -176.325337 19.393695)
		(width 0.127)
		(layer "In2.Cu")
		(net "PCIE_T2B_B2_RX_DN<10>")
	)
	(segment
		(start -180.906052 38.913951)
		(end -181.46 38.360002)
		(width 0.127)
		(layer "In2.Cu")
		(net "PCIE_T2B_B2_RX_DN<10>")
	)
	(segment
		(start -176.325337 19.393695)
		(end -180.6218 23.690158)
		(width 0.127)
		(layer "In2.Cu")
		(net "PCIE_T2B_B2_RX_DN<10>")
	)
	(segment
		(start -163.461715 23.883971)
		(end -163.632739 23.712947)
		(width 0.127)
		(layer "In2.Cu")
		(net "PCIE_T2B_B2_RX_DN<10>")
	)
	(segment
		(start -180.779052 38.913951)
		(end -180.906052 38.913951)
		(width 0.127)
		(layer "In2.Cu")
		(net "PCIE_T2B_B2_RX_DN<10>")
	)
	(segment
		(start -159.602028 24.457599)
		(end -159.007599 24.457599)
		(width 0.127)
		(layer "F.Cu")
		(net "PCIE_T2B_B2_RX_DN<0>")
	)
	(segment
		(start -166.425184 16.83385)
		(end -160.204724 23.05431)
		(width 0.127)
		(layer "F.Cu")
		(net "PCIE_T2B_B2_RX_DN<0>")
	)
	(segment
		(start -159.007599 24.457599)
		(end -158.524999 23.974999)
		(width 0.127)
		(layer "F.Cu")
		(net "PCIE_T2B_B2_RX_DN<0>")
	)
	(segment
		(start -177.89525 16.83385)
		(end -166.425184 16.83385)
		(width 0.127)
		(layer "F.Cu")
		(net "PCIE_T2B_B2_RX_DN<0>")
	)
	(segment
		(start -160.204724 23.05431)
		(end -160.204724 23.854903)
		(width 0.127)
		(layer "F.Cu")
		(net "PCIE_T2B_B2_RX_DN<0>")
	)
	(segment
		(start -184.60592 42.917877)
		(end -184.60592 23.54452)
		(width 0.127)
		(layer "F.Cu")
		(net "PCIE_T2B_B2_RX_DN<0>")
	)
	(segment
		(start -184.912399 43.107602)
		(end -184.795645 43.107602)
		(width 0.127)
		(layer "F.Cu")
		(net "PCIE_T2B_B2_RX_DN<0>")
	)
	(segment
		(start -184.795645 43.107602)
		(end -184.60592 42.917877)
		(width 0.127)
		(layer "F.Cu")
		(net "PCIE_T2B_B2_RX_DN<0>")
	)
	(segment
		(start -184.60592 23.54452)
		(end -177.89525 16.83385)
		(width 0.127)
		(layer "F.Cu")
		(net "PCIE_T2B_B2_RX_DN<0>")
	)
	(segment
		(start -185.46 42.560001)
		(end -184.912399 43.107602)
		(width 0.127)
		(layer "F.Cu")
		(net "PCIE_T2B_B2_RX_DN<0>")
	)
	(segment
		(start -160.204724 23.854903)
		(end -159.602028 24.457599)
		(width 0.127)
		(layer "F.Cu")
		(net "PCIE_T2B_B2_RX_DN<0>")
	)
	(segment
		(start -375.714999 27.784999)
		(end -376.349999 27.149999)
		(width 0.127)
		(layer "F.Cu")
		(net "PCIE_T2B_B1_RX_DP<9>")
	)
	(via
		(at -376.349999 27.149999)
		(size 0.5588)
		(drill 0.254)
		(layers "F.Cu" "B.Cu")
		(net "PCIE_T2B_B1_RX_DP<9>")
	)
	(segment
		(start -403.636399 40.506053)
		(end -403.90605 40.506053)
		(width 0.127)
		(layer "In2.Cu")
		(net "PCIE_T2B_B1_RX_DP<9>")
	)
	(segment
		(start -376.838949 26.661049)
		(end -379.06436 26.661049)
		(width 0.127)
		(layer "In2.Cu")
		(net "PCIE_T2B_B1_RX_DP<9>")
	)
	(segment
		(start -381.301485 25.742227)
		(end -387.701612 19.3421)
		(width 0.127)
		(layer "In2.Cu")
		(net "PCIE_T2B_B1_RX_DP<9>")
	)
	(segment
		(start -403.90605 40.506053)
		(end -404.459999 41.060002)
		(width 0.127)
		(layer "In2.Cu")
		(net "PCIE_T2B_B1_RX_DP<9>")
	)
	(segment
		(start -403.316163 40.185818)
		(end -403.636399 40.506053)
		(width 0.127)
		(layer "In2.Cu")
		(net "PCIE_T2B_B1_RX_DP<9>")
	)
	(segment
		(start -403.316163 23.129601)
		(end -403.316163 40.185818)
		(width 0.127)
		(layer "In2.Cu")
		(net "PCIE_T2B_B1_RX_DP<9>")
	)
	(segment
		(start -379.983182 25.742227)
		(end -381.301485 25.742227)
		(width 0.127)
		(layer "In2.Cu")
		(net "PCIE_T2B_B1_RX_DP<9>")
	)
	(segment
		(start -376.349999 27.149999)
		(end -376.838949 26.661049)
		(width 0.127)
		(layer "In2.Cu")
		(net "PCIE_T2B_B1_RX_DP<9>")
	)
	(segment
		(start -379.06436 26.661049)
		(end -379.983182 25.742227)
		(width 0.127)
		(layer "In2.Cu")
		(net "PCIE_T2B_B1_RX_DP<9>")
	)
	(segment
		(start -399.528662 19.3421)
		(end -403.316163 23.129601)
		(width 0.127)
		(layer "In2.Cu")
		(net "PCIE_T2B_B1_RX_DP<9>")
	)
	(segment
		(start -387.701612 19.3421)
		(end -399.528662 19.3421)
		(width 0.127)
		(layer "In2.Cu")
		(net "PCIE_T2B_B1_RX_DP<9>")
	)
	(segment
		(start -376.984999 25.244999)
		(end -377.619999 24.609999)
		(width 0.127)
		(layer "F.Cu")
		(net "PCIE_T2B_B1_RX_DP<8>")
	)
	(via
		(at -377.619999 24.609999)
		(size 0.5588)
		(drill 0.254)
		(layers "F.Cu" "B.Cu")
		(net "PCIE_T2B_B1_RX_DP<8>")
	)
	(segment
		(start -380.802548 24.121049)
		(end -386.610197 18.3134)
		(width 0.127)
		(layer "In2.Cu")
		(net "PCIE_T2B_B1_RX_DP<8>")
	)
	(segment
		(start -378.108949 24.121049)
		(end -380.802548 24.121049)
		(width 0.127)
		(layer "In2.Cu")
		(net "PCIE_T2B_B1_RX_DP<8>")
	)
	(segment
		(start -377.619999 24.609999)
		(end -378.108949 24.121049)
		(width 0.127)
		(layer "In2.Cu")
		(net "PCIE_T2B_B1_RX_DP<8>")
	)
	(segment
		(start -405.359951 37.458475)
		(end -405.359951 38.907944)
		(width 0.127)
		(layer "In2.Cu")
		(net "PCIE_T2B_B1_RX_DP<8>")
	)
	(segment
		(start -386.610197 18.3134)
		(end -400.548612 18.3134)
		(width 0.127)
		(layer "In2.Cu")
		(net "PCIE_T2B_B1_RX_DP<8>")
	)
	(segment
		(start -405.906049 39.206051)
		(end -406.46 39.760002)
		(width 0.127)
		(layer "In2.Cu")
		(net "PCIE_T2B_B1_RX_DP<8>")
	)
	(segment
		(start -400.548612 18.3134)
		(end -405.3297 23.094488)
		(width 0.127)
		(layer "In2.Cu")
		(net "PCIE_T2B_B1_RX_DP<8>")
	)
	(segment
		(start -405.658058 39.206051)
		(end -405.906049 39.206051)
		(width 0.127)
		(layer "In2.Cu")
		(net "PCIE_T2B_B1_RX_DP<8>")
	)
	(segment
		(start -405.3297 37.428223)
		(end -405.359951 37.458475)
		(width 0.127)
		(layer "In2.Cu")
		(net "PCIE_T2B_B1_RX_DP<8>")
	)
	(segment
		(start -405.3297 23.094488)
		(end -405.3297 37.428223)
		(width 0.127)
		(layer "In2.Cu")
		(net "PCIE_T2B_B1_RX_DP<8>")
	)
	(segment
		(start -405.359951 38.907944)
		(end -405.658058 39.206051)
		(width 0.127)
		(layer "In2.Cu")
		(net "PCIE_T2B_B1_RX_DP<8>")
	)
	(segment
		(start -378.737599 42.542399)
		(end -378.254999 43.024999)
		(width 0.127)
		(layer "F.Cu")
		(net "PCIE_T2B_B1_RX_DP<7>")
	)
	(segment
		(start -380.869114 42.542399)
		(end -378.737599 42.542399)
		(width 0.127)
		(layer "F.Cu")
		(net "PCIE_T2B_B1_RX_DP<7>")
	)
	(segment
		(start -392.46 45.260001)
		(end -391.912401 44.712402)
		(width 0.127)
		(layer "F.Cu")
		(net "PCIE_T2B_B1_RX_DP<7>")
	)
	(segment
		(start -383.039117 44.712402)
		(end -380.869114 42.542399)
		(width 0.127)
		(layer "F.Cu")
		(net "PCIE_T2B_B1_RX_DP<7>")
	)
	(segment
		(start -391.912401 44.712402)
		(end -383.039117 44.712402)
		(width 0.127)
		(layer "F.Cu")
		(net "PCIE_T2B_B1_RX_DP<7>")
	)
	(segment
		(start -381.6858 38.280144)
		(end -382.524 37.441944)
		(width 0.127)
		(layer "F.Cu")
		(net "PCIE_T2B_B1_RX_DP<6>")
	)
	(segment
		(start -388.365253 34.544)
		(end -391.147808 31.761445)
		(width 0.127)
		(layer "F.Cu")
		(net "PCIE_T2B_B1_RX_DP<6>")
	)
	(segment
		(start -379.524999 40.484999)
		(end -380.007599 40.002399)
		(width 0.127)
		(layer "F.Cu")
		(net "PCIE_T2B_B1_RX_DP<6>")
	)
	(segment
		(start -393.659147 43.412402)
		(end -393.912402 43.412402)
		(width 0.127)
		(layer "F.Cu")
		(net "PCIE_T2B_B1_RX_DP<6>")
	)
	(segment
		(start -380.007599 40.002399)
		(end -381.129601 40.002399)
		(width 0.127)
		(layer "F.Cu")
		(net "PCIE_T2B_B1_RX_DP<6>")
	)
	(segment
		(start -391.147808 31.761445)
		(end -391.147808 25.304511)
		(width 0.127)
		(layer "F.Cu")
		(net "PCIE_T2B_B1_RX_DP<6>")
	)
	(segment
		(start -391.147808 25.304511)
		(end -391.663189 24.78913)
		(width 0.127)
		(layer "F.Cu")
		(net "PCIE_T2B_B1_RX_DP<6>")
	)
	(segment
		(start -393.912402 43.412402)
		(end -394.460001 43.960001)
		(width 0.127)
		(layer "F.Cu")
		(net "PCIE_T2B_B1_RX_DP<6>")
	)
	(segment
		(start -393.298426 43.051682)
		(end -393.659147 43.412402)
		(width 0.127)
		(layer "F.Cu")
		(net "PCIE_T2B_B1_RX_DP<6>")
	)
	(segment
		(start -392.833083 24.78913)
		(end -393.298426 25.254473)
		(width 0.127)
		(layer "F.Cu")
		(net "PCIE_T2B_B1_RX_DP<6>")
	)
	(segment
		(start -381.6858 39.4462)
		(end -381.6858 38.280144)
		(width 0.127)
		(layer "F.Cu")
		(net "PCIE_T2B_B1_RX_DP<6>")
	)
	(segment
		(start -384.790696 34.544)
		(end -388.365253 34.544)
		(width 0.127)
		(layer "F.Cu")
		(net "PCIE_T2B_B1_RX_DP<6>")
	)
	(segment
		(start -391.663189 24.78913)
		(end -392.833083 24.78913)
		(width 0.127)
		(layer "F.Cu")
		(net "PCIE_T2B_B1_RX_DP<6>")
	)
	(segment
		(start -393.298426 25.254473)
		(end -393.298426 43.051682)
		(width 0.127)
		(layer "F.Cu")
		(net "PCIE_T2B_B1_RX_DP<6>")
	)
	(segment
		(start -382.524 37.441944)
		(end -382.524 36.810696)
		(width 0.127)
		(layer "F.Cu")
		(net "PCIE_T2B_B1_RX_DP<6>")
	)
	(segment
		(start -381.129601 40.002399)
		(end -381.6858 39.4462)
		(width 0.127)
		(layer "F.Cu")
		(net "PCIE_T2B_B1_RX_DP<6>")
	)
	(segment
		(start -382.524 36.810696)
		(end -384.790696 34.544)
		(width 0.127)
		(layer "F.Cu")
		(net "PCIE_T2B_B1_RX_DP<6>")
	)
	(segment
		(start -395.3002 44.353457)
		(end -395.659145 44.712402)
		(width 0.127)
		(layer "F.Cu")
		(net "PCIE_T2B_B1_RX_DP<5>")
	)
	(segment
		(start -394.807232 23.521802)
		(end -395.298201 24.012771)
		(width 0.127)
		(layer "F.Cu")
		(net "PCIE_T2B_B1_RX_DP<5>")
	)
	(segment
		(start -395.659145 44.712402)
		(end -395.912401 44.712402)
		(width 0.127)
		(layer "F.Cu")
		(net "PCIE_T2B_B1_RX_DP<5>")
	)
	(segment
		(start -384.263138 33.1978)
		(end -387.9342 33.1978)
		(width 0.127)
		(layer "F.Cu")
		(net "PCIE_T2B_B1_RX_DP<5>")
	)
	(segment
		(start -389.8138 24.396578)
		(end -390.687692 23.522686)
		(width 0.127)
		(layer "F.Cu")
		(net "PCIE_T2B_B1_RX_DP<5>")
	)
	(segment
		(start -395.298201 24.079365)
		(end -395.3002 24.081364)
		(width 0.127)
		(layer "F.Cu")
		(net "PCIE_T2B_B1_RX_DP<5>")
	)
	(segment
		(start -387.9342 33.1978)
		(end -389.8138 31.3182)
		(width 0.127)
		(layer "F.Cu")
		(net "PCIE_T2B_B1_RX_DP<5>")
	)
	(segment
		(start -395.298201 24.012771)
		(end -395.298201 24.079365)
		(width 0.127)
		(layer "F.Cu")
		(net "PCIE_T2B_B1_RX_DP<5>")
	)
	(segment
		(start -381.596392 36.645342)
		(end -381.596392 35.864546)
		(width 0.127)
		(layer "F.Cu")
		(net "PCIE_T2B_B1_RX_DP<5>")
	)
	(segment
		(start -378.737599 37.462399)
		(end -380.779335 37.462399)
		(width 0.127)
		(layer "F.Cu")
		(net "PCIE_T2B_B1_RX_DP<5>")
	)
	(segment
		(start -380.779335 37.462399)
		(end -381.596392 36.645342)
		(width 0.127)
		(layer "F.Cu")
		(net "PCIE_T2B_B1_RX_DP<5>")
	)
	(segment
		(start -395.912401 44.712402)
		(end -396.46 45.260001)
		(width 0.127)
		(layer "F.Cu")
		(net "PCIE_T2B_B1_RX_DP<5>")
	)
	(segment
		(start -390.687692 23.522686)
		(end -394.111886 23.522686)
		(width 0.127)
		(layer "F.Cu")
		(net "PCIE_T2B_B1_RX_DP<5>")
	)
	(segment
		(start -381.596392 35.864546)
		(end -384.263138 33.1978)
		(width 0.127)
		(layer "F.Cu")
		(net "PCIE_T2B_B1_RX_DP<5>")
	)
	(segment
		(start -394.111886 23.522686)
		(end -394.11277 23.521802)
		(width 0.127)
		(layer "F.Cu")
		(net "PCIE_T2B_B1_RX_DP<5>")
	)
	(segment
		(start -389.8138 31.3182)
		(end -389.8138 24.396578)
		(width 0.127)
		(layer "F.Cu")
		(net "PCIE_T2B_B1_RX_DP<5>")
	)
	(segment
		(start -378.254999 37.944999)
		(end -378.737599 37.462399)
		(width 0.127)
		(layer "F.Cu")
		(net "PCIE_T2B_B1_RX_DP<5>")
	)
	(segment
		(start -394.11277 23.521802)
		(end -394.807232 23.521802)
		(width 0.127)
		(layer "F.Cu")
		(net "PCIE_T2B_B1_RX_DP<5>")
	)
	(segment
		(start -395.3002 24.081364)
		(end -395.3002 44.353457)
		(width 0.127)
		(layer "F.Cu")
		(net "PCIE_T2B_B1_RX_DP<5>")
	)
	(segment
		(start -380.4412 34.8996)
		(end -381.6604 33.6804)
		(width 0.127)
		(layer "F.Cu")
		(net "PCIE_T2B_B1_RX_DP<4>")
	)
	(segment
		(start -385.445 29.5148)
		(end -388.4168 26.543)
		(width 0.127)
		(layer "F.Cu")
		(net "PCIE_T2B_B1_RX_DP<4>")
	)
	(segment
		(start -388.4168 24.069368)
		(end -390.210368 22.2758)
		(width 0.127)
		(layer "F.Cu")
		(net "PCIE_T2B_B1_RX_DP<4>")
	)
	(segment
		(start -388.4168 26.543)
		(end -388.4168 24.069368)
		(width 0.127)
		(layer "F.Cu")
		(net "PCIE_T2B_B1_RX_DP<4>")
	)
	(segment
		(start -395.316187 22.2758)
		(end -397.3068 24.266413)
		(width 0.127)
		(layer "F.Cu")
		(net "PCIE_T2B_B1_RX_DP<4>")
	)
	(segment
		(start -379.524999 35.404999)
		(end -380.030398 34.8996)
		(width 0.127)
		(layer "F.Cu")
		(net "PCIE_T2B_B1_RX_DP<4>")
	)
	(segment
		(start -380.030398 34.8996)
		(end -380.4412 34.8996)
		(width 0.127)
		(layer "F.Cu")
		(net "PCIE_T2B_B1_RX_DP<4>")
	)
	(segment
		(start -397.3068 43.060056)
		(end -397.659146 43.412402)
		(width 0.127)
		(layer "F.Cu")
		(net "PCIE_T2B_B1_RX_DP<4>")
	)
	(segment
		(start -397.912402 43.412402)
		(end -398.460001 43.960001)
		(width 0.127)
		(layer "F.Cu")
		(net "PCIE_T2B_B1_RX_DP<4>")
	)
	(segment
		(start -397.3068 24.266413)
		(end -397.3068 43.060056)
		(width 0.127)
		(layer "F.Cu")
		(net "PCIE_T2B_B1_RX_DP<4>")
	)
	(segment
		(start -381.6604 33.6804)
		(end -381.6604 33.298653)
		(width 0.127)
		(layer "F.Cu")
		(net "PCIE_T2B_B1_RX_DP<4>")
	)
	(segment
		(start -381.6604 33.298653)
		(end -385.444253 29.5148)
		(width 0.127)
		(layer "F.Cu")
		(net "PCIE_T2B_B1_RX_DP<4>")
	)
	(segment
		(start -385.444253 29.5148)
		(end -385.445 29.5148)
		(width 0.127)
		(layer "F.Cu")
		(net "PCIE_T2B_B1_RX_DP<4>")
	)
	(segment
		(start -390.210368 22.2758)
		(end -395.316187 22.2758)
		(width 0.127)
		(layer "F.Cu")
		(net "PCIE_T2B_B1_RX_DP<4>")
	)
	(segment
		(start -397.659146 43.412402)
		(end -397.912402 43.412402)
		(width 0.127)
		(layer "F.Cu")
		(net "PCIE_T2B_B1_RX_DP<4>")
	)
	(segment
		(start -378.254999 32.864999)
		(end -378.737599 32.382399)
		(width 0.127)
		(layer "F.Cu")
		(net "PCIE_T2B_B1_RX_DP<3>")
	)
	(segment
		(start -385.266453 27.9146)
		(end -385.2672 27.9146)
		(width 0.127)
		(layer "F.Cu")
		(net "PCIE_T2B_B1_RX_DP<3>")
	)
	(segment
		(start -385.2672 27.9146)
		(end -386.969 26.2128)
		(width 0.127)
		(layer "F.Cu")
		(net "PCIE_T2B_B1_RX_DP<3>")
	)
	(segment
		(start -399.659145 44.712402)
		(end -399.912401 44.712402)
		(width 0.127)
		(layer "F.Cu")
		(net "PCIE_T2B_B1_RX_DP<3>")
	)
	(segment
		(start -399.3134 23.861791)
		(end -399.3134 44.366658)
		(width 0.127)
		(layer "F.Cu")
		(net "PCIE_T2B_B1_RX_DP<3>")
	)
	(segment
		(start -396.508209 21.0566)
		(end -399.3134 23.861791)
		(width 0.127)
		(layer "F.Cu")
		(net "PCIE_T2B_B1_RX_DP<3>")
	)
	(segment
		(start -399.912401 44.712402)
		(end -400.459999 45.260001)
		(width 0.127)
		(layer "F.Cu")
		(net "PCIE_T2B_B1_RX_DP<3>")
	)
	(segment
		(start -389.705357 21.0566)
		(end -396.508209 21.0566)
		(width 0.127)
		(layer "F.Cu")
		(net "PCIE_T2B_B1_RX_DP<3>")
	)
	(segment
		(start -380.798654 32.382399)
		(end -385.266453 27.9146)
		(width 0.127)
		(layer "F.Cu")
		(net "PCIE_T2B_B1_RX_DP<3>")
	)
	(segment
		(start -386.969 23.792957)
		(end -389.705357 21.0566)
		(width 0.127)
		(layer "F.Cu")
		(net "PCIE_T2B_B1_RX_DP<3>")
	)
	(segment
		(start -386.969 26.2128)
		(end -386.969 23.792957)
		(width 0.127)
		(layer "F.Cu")
		(net "PCIE_T2B_B1_RX_DP<3>")
	)
	(segment
		(start -399.3134 44.366658)
		(end -399.659145 44.712402)
		(width 0.127)
		(layer "F.Cu")
		(net "PCIE_T2B_B1_RX_DP<3>")
	)
	(segment
		(start -378.737599 32.382399)
		(end -380.798654 32.382399)
		(width 0.127)
		(layer "F.Cu")
		(net "PCIE_T2B_B1_RX_DP<3>")
	)
	(segment
		(start -401.309413 23.637337)
		(end -401.309413 43.06267)
		(width 0.127)
		(layer "F.Cu")
		(net "PCIE_T2B_B1_RX_DP<2>")
	)
	(segment
		(start -384.23342 26.204433)
		(end -384.23342 24.498823)
		(width 0.127)
		(layer "F.Cu")
		(net "PCIE_T2B_B1_RX_DP<2>")
	)
	(segment
		(start -384.23342 24.498823)
		(end -388.894843 19.8374)
		(width 0.127)
		(layer "F.Cu")
		(net "PCIE_T2B_B1_RX_DP<2>")
	)
	(segment
		(start -397.509477 19.8374)
		(end -401.309413 23.637337)
		(width 0.127)
		(layer "F.Cu")
		(net "PCIE_T2B_B1_RX_DP<2>")
	)
	(segment
		(start -380.595454 29.842399)
		(end -384.23342 26.204433)
		(width 0.127)
		(layer "F.Cu")
		(net "PCIE_T2B_B1_RX_DP<2>")
	)
	(segment
		(start -380.007599 29.842399)
		(end -380.595454 29.842399)
		(width 0.127)
		(layer "F.Cu")
		(net "PCIE_T2B_B1_RX_DP<2>")
	)
	(segment
		(start -379.524999 30.324999)
		(end -380.007599 29.842399)
		(width 0.127)
		(layer "F.Cu")
		(net "PCIE_T2B_B1_RX_DP<2>")
	)
	(segment
		(start -401.912402 43.412402)
		(end -402.46 43.960001)
		(width 0.127)
		(layer "F.Cu")
		(net "PCIE_T2B_B1_RX_DP<2>")
	)
	(segment
		(start -401.659146 43.412402)
		(end -401.912402 43.412402)
		(width 0.127)
		(layer "F.Cu")
		(net "PCIE_T2B_B1_RX_DP<2>")
	)
	(segment
		(start -401.309413 43.06267)
		(end -401.659146 43.412402)
		(width 0.127)
		(layer "F.Cu")
		(net "PCIE_T2B_B1_RX_DP<2>")
	)
	(segment
		(start -388.894843 19.8374)
		(end -397.509477 19.8374)
		(width 0.127)
		(layer "F.Cu")
		(net "PCIE_T2B_B1_RX_DP<2>")
	)
	(segment
		(start -388.119127 18.6182)
		(end -398.406859 18.6182)
		(width 0.127)
		(layer "F.Cu")
		(net "PCIE_T2B_B1_RX_DP<1>")
	)
	(segment
		(start -403.3012 44.354458)
		(end -403.659144 44.712402)
		(width 0.127)
		(layer "F.Cu")
		(net "PCIE_T2B_B1_RX_DP<1>")
	)
	(segment
		(start -403.9124 44.712402)
		(end -404.459999 45.260001)
		(width 0.127)
		(layer "F.Cu")
		(net "PCIE_T2B_B1_RX_DP<1>")
	)
	(segment
		(start -378.254999 27.784999)
		(end -378.737599 27.302399)
		(width 0.127)
		(layer "F.Cu")
		(net "PCIE_T2B_B1_RX_DP<1>")
	)
	(segment
		(start -403.3012 23.512541)
		(end -403.3012 44.354458)
		(width 0.127)
		(layer "F.Cu")
		(net "PCIE_T2B_B1_RX_DP<1>")
	)
	(segment
		(start -382.966976 25.402614)
		(end -382.966976 23.770351)
		(width 0.127)
		(layer "F.Cu")
		(net "PCIE_T2B_B1_RX_DP<1>")
	)
	(segment
		(start -378.737599 27.302399)
		(end -381.067191 27.302399)
		(width 0.127)
		(layer "F.Cu")
		(net "PCIE_T2B_B1_RX_DP<1>")
	)
	(segment
		(start -398.406859 18.6182)
		(end -403.3012 23.512541)
		(width 0.127)
		(layer "F.Cu")
		(net "PCIE_T2B_B1_RX_DP<1>")
	)
	(segment
		(start -403.659144 44.712402)
		(end -403.9124 44.712402)
		(width 0.127)
		(layer "F.Cu")
		(net "PCIE_T2B_B1_RX_DP<1>")
	)
	(segment
		(start -382.966976 23.770351)
		(end -388.119127 18.6182)
		(width 0.127)
		(layer "F.Cu")
		(net "PCIE_T2B_B1_RX_DP<1>")
	)
	(segment
		(start -381.067191 27.302399)
		(end -382.966976 25.402614)
		(width 0.127)
		(layer "F.Cu")
		(net "PCIE_T2B_B1_RX_DP<1>")
	)
	(segment
		(start -375.714999 43.024999)
		(end -376.349999 42.389999)
		(width 0.127)
		(layer "F.Cu")
		(net "PCIE_T2B_B1_RX_DP<15>")
	)
	(via
		(at -376.349999 42.389999)
		(size 0.5588)
		(drill 0.254)
		(layers "F.Cu" "B.Cu")
		(net "PCIE_T2B_B1_RX_DP<15>")
	)
	(segment
		(start -377.827207 41.901049)
		(end -380.540895 44.614737)
		(width 0.127)
		(layer "In2.Cu")
		(net "PCIE_T2B_B1_RX_DP<15>")
	)
	(segment
		(start -376.838949 41.901049)
		(end -377.827207 41.901049)
		(width 0.127)
		(layer "In2.Cu")
		(net "PCIE_T2B_B1_RX_DP<15>")
	)
	(segment
		(start -387.558303 44.614737)
		(end -391.666989 40.506051)
		(width 0.127)
		(layer "In2.Cu")
		(net "PCIE_T2B_B1_RX_DP<15>")
	)
	(segment
		(start -376.349999 42.389999)
		(end -376.838949 41.901049)
		(width 0.127)
		(layer "In2.Cu")
		(net "PCIE_T2B_B1_RX_DP<15>")
	)
	(segment
		(start -391.666989 40.506051)
		(end -391.906049 40.506051)
		(width 0.127)
		(layer "In2.Cu")
		(net "PCIE_T2B_B1_RX_DP<15>")
	)
	(segment
		(start -380.540895 44.614737)
		(end -387.558303 44.614737)
		(width 0.127)
		(layer "In2.Cu")
		(net "PCIE_T2B_B1_RX_DP<15>")
	)
	(segment
		(start -391.906049 40.506051)
		(end -392.46 41.060002)
		(width 0.127)
		(layer "In2.Cu")
		(net "PCIE_T2B_B1_RX_DP<15>")
	)
	(segment
		(start -376.984999 40.484999)
		(end -377.619999 39.849999)
		(width 0.127)
		(layer "F.Cu")
		(net "PCIE_T2B_B1_RX_DP<14>")
	)
	(via
		(at -377.619999 39.849999)
		(size 0.5588)
		(drill 0.254)
		(layers "F.Cu" "B.Cu")
		(net "PCIE_T2B_B1_RX_DP<14>")
	)
	(segment
		(start -381.086197 39.361049)
		(end -378.108949 39.361049)
		(width 0.127)
		(layer "In2.Cu")
		(net "PCIE_T2B_B1_RX_DP<14>")
	)
	(segment
		(start -391.830403 24.801467)
		(end -390.756551 25.875318)
		(width 0.127)
		(layer "In2.Cu")
		(net "PCIE_T2B_B1_RX_DP<14>")
	)
	(segment
		(start -393.2982 38.937954)
		(end -393.2982 25.212975)
		(width 0.127)
		(layer "In2.Cu")
		(net "PCIE_T2B_B1_RX_DP<14>")
	)
	(segment
		(start -378.108949 39.361049)
		(end -377.619999 39.849999)
		(width 0.127)
		(layer "In2.Cu")
		(net "PCIE_T2B_B1_RX_DP<14>")
	)
	(segment
		(start -390.756551 29.690695)
		(end -381.086197 39.361049)
		(width 0.127)
		(layer "In2.Cu")
		(net "PCIE_T2B_B1_RX_DP<14>")
	)
	(segment
		(start -393.90605 39.206051)
		(end -393.566297 39.206051)
		(width 0.127)
		(layer "In2.Cu")
		(net "PCIE_T2B_B1_RX_DP<14>")
	)
	(segment
		(start -390.756551 25.875318)
		(end -390.756551 29.690695)
		(width 0.127)
		(layer "In2.Cu")
		(net "PCIE_T2B_B1_RX_DP<14>")
	)
	(segment
		(start -392.886692 24.801467)
		(end -391.830403 24.801467)
		(width 0.127)
		(layer "In2.Cu")
		(net "PCIE_T2B_B1_RX_DP<14>")
	)
	(segment
		(start -393.566297 39.206051)
		(end -393.2982 38.937954)
		(width 0.127)
		(layer "In2.Cu")
		(net "PCIE_T2B_B1_RX_DP<14>")
	)
	(segment
		(start -393.2982 25.212975)
		(end -392.886692 24.801467)
		(width 0.127)
		(layer "In2.Cu")
		(net "PCIE_T2B_B1_RX_DP<14>")
	)
	(segment
		(start -394.460001 39.760002)
		(end -393.90605 39.206051)
		(width 0.127)
		(layer "In2.Cu")
		(net "PCIE_T2B_B1_RX_DP<14>")
	)
	(segment
		(start -375.714999 37.944999)
		(end -376.349999 37.309999)
		(width 0.127)
		(layer "F.Cu")
		(net "PCIE_T2B_B1_RX_DP<13>")
	)
	(via
		(at -376.349999 37.309999)
		(size 0.5588)
		(drill 0.254)
		(layers "F.Cu" "B.Cu")
		(net "PCIE_T2B_B1_RX_DP<13>")
	)
	(segment
		(start -376.838949 36.821049)
		(end -376.349999 37.309999)
		(width 0.127)
		(layer "In2.Cu")
		(net "PCIE_T2B_B1_RX_DP<13>")
	)
	(segment
		(start -395.906048 40.506051)
		(end -395.551162 40.506051)
		(width 0.127)
		(layer "In2.Cu")
		(net "PCIE_T2B_B1_RX_DP<13>")
	)
	(segment
		(start -394.880295 23.5077)
		(end -391.135075 23.5077)
		(width 0.127)
		(layer "In2.Cu")
		(net "PCIE_T2B_B1_RX_DP<13>")
	)
	(segment
		(start -396.46 41.060002)
		(end -395.906048 40.506051)
		(width 0.127)
		(layer "In2.Cu")
		(net "PCIE_T2B_B1_RX_DP<13>")
	)
	(segment
		(start -389.3185 25.324275)
		(end -389.3185 28.27002)
		(width 0.127)
		(layer "In2.Cu")
		(net "PCIE_T2B_B1_RX_DP<13>")
	)
	(segment
		(start -389.3185 28.27002)
		(end -381.579311 36.009209)
		(width 0.127)
		(layer "In2.Cu")
		(net "PCIE_T2B_B1_RX_DP<13>")
	)
	(segment
		(start -378.861747 36.821049)
		(end -376.838949 36.821049)
		(width 0.127)
		(layer "In2.Cu")
		(net "PCIE_T2B_B1_RX_DP<13>")
	)
	(segment
		(start -381.579311 36.009209)
		(end -379.673587 36.009209)
		(width 0.127)
		(layer "In2.Cu")
		(net "PCIE_T2B_B1_RX_DP<13>")
	)
	(segment
		(start -395.298201 23.925606)
		(end -394.880295 23.5077)
		(width 0.127)
		(layer "In2.Cu")
		(net "PCIE_T2B_B1_RX_DP<13>")
	)
	(segment
		(start -395.551162 40.506051)
		(end -395.298201 40.253089)
		(width 0.127)
		(layer "In2.Cu")
		(net "PCIE_T2B_B1_RX_DP<13>")
	)
	(segment
		(start -391.135075 23.5077)
		(end -389.3185 25.324275)
		(width 0.127)
		(layer "In2.Cu")
		(net "PCIE_T2B_B1_RX_DP<13>")
	)
	(segment
		(start -379.673587 36.009209)
		(end -378.861747 36.821049)
		(width 0.127)
		(layer "In2.Cu")
		(net "PCIE_T2B_B1_RX_DP<13>")
	)
	(segment
		(start -395.298201 40.253089)
		(end -395.298201 23.925606)
		(width 0.127)
		(layer "In2.Cu")
		(net "PCIE_T2B_B1_RX_DP<13>")
	)
	(segment
		(start -376.984999 35.404999)
		(end -377.619999 34.769999)
		(width 0.127)
		(layer "F.Cu")
		(net "PCIE_T2B_B1_RX_DP<12>")
	)
	(via
		(at -377.619999 34.769999)
		(size 0.5588)
		(drill 0.254)
		(layers "F.Cu" "B.Cu")
		(net "PCIE_T2B_B1_RX_DP<12>")
	)
	(segment
		(start -381.100198 34.281049)
		(end -378.108949 34.281049)
		(width 0.127)
		(layer "In2.Cu")
		(net "PCIE_T2B_B1_RX_DP<12>")
	)
	(segment
		(start -397.90605 39.206051)
		(end -397.658059 39.206051)
		(width 0.127)
		(layer "In2.Cu")
		(net "PCIE_T2B_B1_RX_DP<12>")
	)
	(segment
		(start -397.2982 38.846191)
		(end -397.2982 24.067524)
		(width 0.127)
		(layer "In2.Cu")
		(net "PCIE_T2B_B1_RX_DP<12>")
	)
	(segment
		(start -398.460001 39.760002)
		(end -397.90605 39.206051)
		(width 0.127)
		(layer "In2.Cu")
		(net "PCIE_T2B_B1_RX_DP<12>")
	)
	(segment
		(start -397.2982 24.067524)
		(end -395.684276 22.4536)
		(width 0.127)
		(layer "In2.Cu")
		(net "PCIE_T2B_B1_RX_DP<12>")
	)
	(segment
		(start -395.684276 22.4536)
		(end -390.331099 22.4536)
		(width 0.127)
		(layer "In2.Cu")
		(net "PCIE_T2B_B1_RX_DP<12>")
	)
	(segment
		(start -397.658059 39.206051)
		(end -397.2982 38.846191)
		(width 0.127)
		(layer "In2.Cu")
		(net "PCIE_T2B_B1_RX_DP<12>")
	)
	(segment
		(start -390.331099 22.4536)
		(end -388.1501 24.634599)
		(width 0.127)
		(layer "In2.Cu")
		(net "PCIE_T2B_B1_RX_DP<12>")
	)
	(segment
		(start -388.1501 24.634599)
		(end -388.1501 27.231147)
		(width 0.127)
		(layer "In2.Cu")
		(net "PCIE_T2B_B1_RX_DP<12>")
	)
	(segment
		(start -378.108949 34.281049)
		(end -377.619999 34.769999)
		(width 0.127)
		(layer "In2.Cu")
		(net "PCIE_T2B_B1_RX_DP<12>")
	)
	(segment
		(start -388.1501 27.231147)
		(end -381.100198 34.281049)
		(width 0.127)
		(layer "In2.Cu")
		(net "PCIE_T2B_B1_RX_DP<12>")
	)
	(segment
		(start -375.714999 32.864999)
		(end -376.349999 32.229999)
		(width 0.127)
		(layer "F.Cu")
		(net "PCIE_T2B_B1_RX_DP<11>")
	)
	(via
		(at -376.349999 32.229999)
		(size 0.5588)
		(drill 0.254)
		(layers "F.Cu" "B.Cu")
		(net "PCIE_T2B_B1_RX_DP<11>")
	)
	(segment
		(start -376.838949 31.741049)
		(end -376.349999 32.229999)
		(width 0.127)
		(layer "In2.Cu")
		(net "PCIE_T2B_B1_RX_DP<11>")
	)
	(segment
		(start -379.225089 31.741049)
		(end -376.838949 31.741049)
		(width 0.127)
		(layer "In2.Cu")
		(net "PCIE_T2B_B1_RX_DP<11>")
	)
	(segment
		(start -389.442955 21.4122)
		(end -386.6007 24.254455)
		(width 0.127)
		(layer "In2.Cu")
		(net "PCIE_T2B_B1_RX_DP<11>")
	)
	(segment
		(start -380.030911 30.935226)
		(end -379.225089 31.741049)
		(width 0.127)
		(layer "In2.Cu")
		(net "PCIE_T2B_B1_RX_DP<11>")
	)
	(segment
		(start -396.953565 21.4122)
		(end -389.442955 21.4122)
		(width 0.127)
		(layer "In2.Cu")
		(net "PCIE_T2B_B1_RX_DP<11>")
	)
	(segment
		(start -399.574832 40.506053)
		(end -399.298201 40.229422)
		(width 0.127)
		(layer "In2.Cu")
		(net "PCIE_T2B_B1_RX_DP<11>")
	)
	(segment
		(start -386.6007 25.24683)
		(end -380.912304 30.935226)
		(width 0.127)
		(layer "In2.Cu")
		(net "PCIE_T2B_B1_RX_DP<11>")
	)
	(segment
		(start -399.906051 40.506053)
		(end -399.574832 40.506053)
		(width 0.127)
		(layer "In2.Cu")
		(net "PCIE_T2B_B1_RX_DP<11>")
	)
	(segment
		(start -399.298201 23.756836)
		(end -396.953565 21.4122)
		(width 0.127)
		(layer "In2.Cu")
		(net "PCIE_T2B_B1_RX_DP<11>")
	)
	(segment
		(start -380.912304 30.935226)
		(end -380.030911 30.935226)
		(width 0.127)
		(layer "In2.Cu")
		(net "PCIE_T2B_B1_RX_DP<11>")
	)
	(segment
		(start -400.459999 41.060002)
		(end -399.906051 40.506053)
		(width 0.127)
		(layer "In2.Cu")
		(net "PCIE_T2B_B1_RX_DP<11>")
	)
	(segment
		(start -386.6007 24.254455)
		(end -386.6007 25.24683)
		(width 0.127)
		(layer "In2.Cu")
		(net "PCIE_T2B_B1_RX_DP<11>")
	)
	(segment
		(start -399.298201 40.229422)
		(end -399.298201 23.756836)
		(width 0.127)
		(layer "In2.Cu")
		(net "PCIE_T2B_B1_RX_DP<11>")
	)
	(segment
		(start -376.984999 30.324999)
		(end -377.619999 29.689999)
		(width 0.127)
		(layer "F.Cu")
		(net "PCIE_T2B_B1_RX_DP<10>")
	)
	(via
		(at -377.619999 29.689999)
		(size 0.5588)
		(drill 0.254)
		(layers "F.Cu" "B.Cu")
		(net "PCIE_T2B_B1_RX_DP<10>")
	)
	(segment
		(start -384.753815 24.005047)
		(end -388.388062 20.3708)
		(width 0.127)
		(layer "In2.Cu")
		(net "PCIE_T2B_B1_RX_DP<10>")
	)
	(segment
		(start -378.108949 29.201049)
		(end -380.454901 29.201049)
		(width 0.127)
		(layer "In2.Cu")
		(net "PCIE_T2B_B1_RX_DP<10>")
	)
	(segment
		(start -388.388062 20.3708)
		(end -397.889349 20.3708)
		(width 0.127)
		(layer "In2.Cu")
		(net "PCIE_T2B_B1_RX_DP<10>")
	)
	(segment
		(start -380.454901 29.201049)
		(end -384.753815 24.902135)
		(width 0.127)
		(layer "In2.Cu")
		(net "PCIE_T2B_B1_RX_DP<10>")
	)
	(segment
		(start -401.3297 38.877692)
		(end -401.658059 39.206051)
		(width 0.127)
		(layer "In2.Cu")
		(net "PCIE_T2B_B1_RX_DP<10>")
	)
	(segment
		(start -377.619999 29.689999)
		(end -378.108949 29.201049)
		(width 0.127)
		(layer "In2.Cu")
		(net "PCIE_T2B_B1_RX_DP<10>")
	)
	(segment
		(start -401.658059 39.206051)
		(end -401.906049 39.206051)
		(width 0.127)
		(layer "In2.Cu")
		(net "PCIE_T2B_B1_RX_DP<10>")
	)
	(segment
		(start -401.906049 39.206051)
		(end -402.46 39.760002)
		(width 0.127)
		(layer "In2.Cu")
		(net "PCIE_T2B_B1_RX_DP<10>")
	)
	(segment
		(start -397.889349 20.3708)
		(end -401.3297 23.811151)
		(width 0.127)
		(layer "In2.Cu")
		(net "PCIE_T2B_B1_RX_DP<10>")
	)
	(segment
		(start -401.3297 23.811151)
		(end -401.3297 38.877692)
		(width 0.127)
		(layer "In2.Cu")
		(net "PCIE_T2B_B1_RX_DP<10>")
	)
	(segment
		(start -384.753815 24.902135)
		(end -384.753815 24.005047)
		(width 0.127)
		(layer "In2.Cu")
		(net "PCIE_T2B_B1_RX_DP<10>")
	)
	(segment
		(start -405.912401 43.412402)
		(end -405.669392 43.412402)
		(width 0.127)
		(layer "F.Cu")
		(net "PCIE_T2B_B1_RX_DP<0>")
	)
	(segment
		(start -399.581863 17.399)
		(end -387.291087 17.399)
		(width 0.127)
		(layer "F.Cu")
		(net "PCIE_T2B_B1_RX_DP<0>")
	)
	(segment
		(start -380.007599 24.762399)
		(end -379.524999 25.244999)
		(width 0.127)
		(layer "F.Cu")
		(net "PCIE_T2B_B1_RX_DP<0>")
	)
	(segment
		(start -405.30112 23.118257)
		(end -399.581863 17.399)
		(width 0.127)
		(layer "F.Cu")
		(net "PCIE_T2B_B1_RX_DP<0>")
	)
	(segment
		(start -380.728281 24.762399)
		(end -380.007599 24.762399)
		(width 0.127)
		(layer "F.Cu")
		(net "PCIE_T2B_B1_RX_DP<0>")
	)
	(segment
		(start -406.46 43.960001)
		(end -405.912401 43.412402)
		(width 0.127)
		(layer "F.Cu")
		(net "PCIE_T2B_B1_RX_DP<0>")
	)
	(segment
		(start -381.509524 23.180563)
		(end -381.509524 23.981156)
		(width 0.127)
		(layer "F.Cu")
		(net "PCIE_T2B_B1_RX_DP<0>")
	)
	(segment
		(start -387.291087 17.399)
		(end -381.509524 23.180563)
		(width 0.127)
		(layer "F.Cu")
		(net "PCIE_T2B_B1_RX_DP<0>")
	)
	(segment
		(start -405.30112 43.04413)
		(end -405.30112 23.118257)
		(width 0.127)
		(layer "F.Cu")
		(net "PCIE_T2B_B1_RX_DP<0>")
	)
	(segment
		(start -381.509524 23.981156)
		(end -380.728281 24.762399)
		(width 0.127)
		(layer "F.Cu")
		(net "PCIE_T2B_B1_RX_DP<0>")
	)
	(segment
		(start -405.669392 43.412402)
		(end -405.30112 43.04413)
		(width 0.127)
		(layer "F.Cu")
		(net "PCIE_T2B_B1_RX_DP<0>")
	)
	(segment
		(start -375.714999 26.514999)
		(end -376.349999 25.879999)
		(width 0.127)
		(layer "F.Cu")
		(net "PCIE_T2B_B1_RX_DN<9>")
	)
	(via
		(at -376.349999 25.879999)
		(size 0.5588)
		(drill 0.254)
		(layers "F.Cu" "B.Cu")
		(net "PCIE_T2B_B1_RX_DN<9>")
	)
	(segment
		(start -376.349999 25.879999)
		(end -376.838949 26.368949)
		(width 0.127)
		(layer "In2.Cu")
		(net "PCIE_T2B_B1_RX_DN<9>")
	)
	(segment
		(start -387.580619 19.05)
		(end -399.649655 19.05)
		(width 0.127)
		(layer "In2.Cu")
		(net "PCIE_T2B_B1_RX_DN<9>")
	)
	(segment
		(start -379.776629 25.535687)
		(end -379.776629 25.535682)
		(width 0.127)
		(layer "In2.Cu")
		(net "PCIE_T2B_B1_RX_DN<9>")
	)
	(segment
		(start -381.180492 25.450127)
		(end -387.580619 19.05)
		(width 0.127)
		(layer "In2.Cu")
		(net "PCIE_T2B_B1_RX_DN<9>")
	)
	(segment
		(start -403.906048 40.213953)
		(end -404.459999 39.660002)
		(width 0.127)
		(layer "In2.Cu")
		(net "PCIE_T2B_B1_RX_DN<9>")
	)
	(segment
		(start -403.608263 23.008608)
		(end -403.608263 40.064825)
		(width 0.127)
		(layer "In2.Cu")
		(net "PCIE_T2B_B1_RX_DN<9>")
	)
	(segment
		(start -403.608263 40.064825)
		(end -403.757392 40.213953)
		(width 0.127)
		(layer "In2.Cu")
		(net "PCIE_T2B_B1_RX_DN<9>")
	)
	(segment
		(start -378.943367 26.368949)
		(end -379.776629 25.535687)
		(width 0.127)
		(layer "In2.Cu")
		(net "PCIE_T2B_B1_RX_DN<9>")
	)
	(segment
		(start -379.776629 25.535682)
		(end -379.862184 25.450127)
		(width 0.127)
		(layer "In2.Cu")
		(net "PCIE_T2B_B1_RX_DN<9>")
	)
	(segment
		(start -403.757392 40.213953)
		(end -403.906048 40.213953)
		(width 0.127)
		(layer "In2.Cu")
		(net "PCIE_T2B_B1_RX_DN<9>")
	)
	(segment
		(start -399.649655 19.05)
		(end -403.608263 23.008608)
		(width 0.127)
		(layer "In2.Cu")
		(net "PCIE_T2B_B1_RX_DN<9>")
	)
	(segment
		(start -376.838949 26.368949)
		(end -378.943367 26.368949)
		(width 0.127)
		(layer "In2.Cu")
		(net "PCIE_T2B_B1_RX_DN<9>")
	)
	(segment
		(start -379.862184 25.450127)
		(end -381.180492 25.450127)
		(width 0.127)
		(layer "In2.Cu")
		(net "PCIE_T2B_B1_RX_DN<9>")
	)
	(segment
		(start -376.984999 23.974999)
		(end -377.619999 23.339999)
		(width 0.127)
		(layer "F.Cu")
		(net "PCIE_T2B_B1_RX_DN<8>")
	)
	(via
		(at -377.619999 23.339999)
		(size 0.5588)
		(drill 0.254)
		(layers "F.Cu" "B.Cu")
		(net "PCIE_T2B_B1_RX_DN<8>")
	)
	(segment
		(start -405.6218 37.30723)
		(end -405.652051 37.337482)
		(width 0.127)
		(layer "In2.Cu")
		(net "PCIE_T2B_B1_RX_DN<8>")
	)
	(segment
		(start -386.489204 18.0213)
		(end -400.669605 18.0213)
		(width 0.127)
		(layer "In2.Cu")
		(net "PCIE_T2B_B1_RX_DN<8>")
	)
	(segment
		(start -405.6218 22.973495)
		(end -405.6218 37.30723)
		(width 0.127)
		(layer "In2.Cu")
		(net "PCIE_T2B_B1_RX_DN<8>")
	)
	(segment
		(start -400.669605 18.0213)
		(end -405.6218 22.973495)
		(width 0.127)
		(layer "In2.Cu")
		(net "PCIE_T2B_B1_RX_DN<8>")
	)
	(segment
		(start -405.652051 37.337482)
		(end -405.652051 38.786951)
		(width 0.127)
		(layer "In2.Cu")
		(net "PCIE_T2B_B1_RX_DN<8>")
	)
	(segment
		(start -378.108949 23.828949)
		(end -380.681555 23.828949)
		(width 0.127)
		(layer "In2.Cu")
		(net "PCIE_T2B_B1_RX_DN<8>")
	)
	(segment
		(start -405.652051 38.786951)
		(end -405.779051 38.913951)
		(width 0.127)
		(layer "In2.Cu")
		(net "PCIE_T2B_B1_RX_DN<8>")
	)
	(segment
		(start -405.906051 38.913951)
		(end -406.46 38.360002)
		(width 0.127)
		(layer "In2.Cu")
		(net "PCIE_T2B_B1_RX_DN<8>")
	)
	(segment
		(start -377.619999 23.339999)
		(end -378.108949 23.828949)
		(width 0.127)
		(layer "In2.Cu")
		(net "PCIE_T2B_B1_RX_DN<8>")
	)
	(segment
		(start -405.779051 38.913951)
		(end -405.906051 38.913951)
		(width 0.127)
		(layer "In2.Cu")
		(net "PCIE_T2B_B1_RX_DN<8>")
	)
	(segment
		(start -380.681555 23.828949)
		(end -386.489204 18.0213)
		(width 0.127)
		(layer "In2.Cu")
		(net "PCIE_T2B_B1_RX_DN<8>")
	)
	(segment
		(start -383.16537 44.407602)
		(end -380.995367 42.237599)
		(width 0.127)
		(layer "F.Cu")
		(net "PCIE_T2B_B1_RX_DN<7>")
	)
	(segment
		(start -378.737599 42.237599)
		(end -378.254999 41.754999)
		(width 0.127)
		(layer "F.Cu")
		(net "PCIE_T2B_B1_RX_DN<7>")
	)
	(segment
		(start -392.46 43.860001)
		(end -391.912399 44.407602)
		(width 0.127)
		(layer "F.Cu")
		(net "PCIE_T2B_B1_RX_DN<7>")
	)
	(segment
		(start -391.912399 44.407602)
		(end -383.16537 44.407602)
		(width 0.127)
		(layer "F.Cu")
		(net "PCIE_T2B_B1_RX_DN<7>")
	)
	(segment
		(start -380.995367 42.237599)
		(end -378.737599 42.237599)
		(width 0.127)
		(layer "F.Cu")
		(net "PCIE_T2B_B1_RX_DN<7>")
	)
	(segment
		(start -393.9124 43.107602)
		(end -394.460001 42.560001)
		(width 0.127)
		(layer "F.Cu")
		(net "PCIE_T2B_B1_RX_DN<6>")
	)
	(segment
		(start -381.003348 39.697599)
		(end -381.381 39.319947)
		(width 0.127)
		(layer "F.Cu")
		(net "PCIE_T2B_B1_RX_DN<6>")
	)
	(segment
		(start -379.524999 39.214999)
		(end -380.007599 39.697599)
		(width 0.127)
		(layer "F.Cu")
		(net "PCIE_T2B_B1_RX_DN<6>")
	)
	(segment
		(start -392.959336 24.48433)
		(end -393.603226 25.12822)
		(width 0.127)
		(layer "F.Cu")
		(net "PCIE_T2B_B1_RX_DN<6>")
	)
	(segment
		(start -380.007599 39.697599)
		(end -381.003348 39.697599)
		(width 0.127)
		(layer "F.Cu")
		(net "PCIE_T2B_B1_RX_DN<6>")
	)
	(segment
		(start -393.603226 25.12822)
		(end -393.603226 42.925429)
		(width 0.127)
		(layer "F.Cu")
		(net "PCIE_T2B_B1_RX_DN<6>")
	)
	(segment
		(start -393.603226 42.925429)
		(end -393.7854 43.107602)
		(width 0.127)
		(layer "F.Cu")
		(net "PCIE_T2B_B1_RX_DN<6>")
	)
	(segment
		(start -388.239 34.2392)
		(end -390.843008 31.635192)
		(width 0.127)
		(layer "F.Cu")
		(net "PCIE_T2B_B1_RX_DN<6>")
	)
	(segment
		(start -390.843008 25.178258)
		(end -391.536936 24.48433)
		(width 0.127)
		(layer "F.Cu")
		(net "PCIE_T2B_B1_RX_DN<6>")
	)
	(segment
		(start -390.843008 31.635192)
		(end -390.843008 25.178258)
		(width 0.127)
		(layer "F.Cu")
		(net "PCIE_T2B_B1_RX_DN<6>")
	)
	(segment
		(start -384.664443 34.2392)
		(end -388.239 34.2392)
		(width 0.127)
		(layer "F.Cu")
		(net "PCIE_T2B_B1_RX_DN<6>")
	)
	(segment
		(start -382.2192 36.684443)
		(end -384.664443 34.2392)
		(width 0.127)
		(layer "F.Cu")
		(net "PCIE_T2B_B1_RX_DN<6>")
	)
	(segment
		(start -393.7854 43.107602)
		(end -393.9124 43.107602)
		(width 0.127)
		(layer "F.Cu")
		(net "PCIE_T2B_B1_RX_DN<6>")
	)
	(segment
		(start -381.381 39.319947)
		(end -381.381 38.153891)
		(width 0.127)
		(layer "F.Cu")
		(net "PCIE_T2B_B1_RX_DN<6>")
	)
	(segment
		(start -391.536936 24.48433)
		(end -392.959336 24.48433)
		(width 0.127)
		(layer "F.Cu")
		(net "PCIE_T2B_B1_RX_DN<6>")
	)
	(segment
		(start -381.381 38.153891)
		(end -382.2192 37.315691)
		(width 0.127)
		(layer "F.Cu")
		(net "PCIE_T2B_B1_RX_DN<6>")
	)
	(segment
		(start -382.2192 37.315691)
		(end -382.2192 36.684443)
		(width 0.127)
		(layer "F.Cu")
		(net "PCIE_T2B_B1_RX_DN<6>")
	)
	(segment
		(start -387.807947 32.893)
		(end -389.509 31.191947)
		(width 0.127)
		(layer "F.Cu")
		(net "PCIE_T2B_B1_RX_DN<5>")
	)
	(segment
		(start -389.509 24.270325)
		(end -390.561439 23.217886)
		(width 0.127)
		(layer "F.Cu")
		(net "PCIE_T2B_B1_RX_DN<5>")
	)
	(segment
		(start -395.603001 23.886518)
		(end -395.603001 23.953112)
		(width 0.127)
		(layer "F.Cu")
		(net "PCIE_T2B_B1_RX_DN<5>")
	)
	(segment
		(start -395.605 44.227204)
		(end -395.785398 44.407602)
		(width 0.127)
		(layer "F.Cu")
		(net "PCIE_T2B_B1_RX_DN<5>")
	)
	(segment
		(start -395.912398 44.407602)
		(end -396.46 43.860001)
		(width 0.127)
		(layer "F.Cu")
		(net "PCIE_T2B_B1_RX_DN<5>")
	)
	(segment
		(start -393.986517 23.217002)
		(end -394.933485 23.217002)
		(width 0.127)
		(layer "F.Cu")
		(net "PCIE_T2B_B1_RX_DN<5>")
	)
	(segment
		(start -395.785398 44.407602)
		(end -395.912398 44.407602)
		(width 0.127)
		(layer "F.Cu")
		(net "PCIE_T2B_B1_RX_DN<5>")
	)
	(segment
		(start -381.291592 35.738293)
		(end -384.136885 32.893)
		(width 0.127)
		(layer "F.Cu")
		(net "PCIE_T2B_B1_RX_DN<5>")
	)
	(segment
		(start -395.605 23.955111)
		(end -395.605 44.227204)
		(width 0.127)
		(layer "F.Cu")
		(net "PCIE_T2B_B1_RX_DN<5>")
	)
	(segment
		(start -390.561439 23.217886)
		(end -393.985633 23.217886)
		(width 0.127)
		(layer "F.Cu")
		(net "PCIE_T2B_B1_RX_DN<5>")
	)
	(segment
		(start -384.136885 32.893)
		(end -387.807947 32.893)
		(width 0.127)
		(layer "F.Cu")
		(net "PCIE_T2B_B1_RX_DN<5>")
	)
	(segment
		(start -389.509 31.191947)
		(end -389.509 24.270325)
		(width 0.127)
		(layer "F.Cu")
		(net "PCIE_T2B_B1_RX_DN<5>")
	)
	(segment
		(start -380.653082 37.157599)
		(end -381.291592 36.519089)
		(width 0.127)
		(layer "F.Cu")
		(net "PCIE_T2B_B1_RX_DN<5>")
	)
	(segment
		(start -394.933485 23.217002)
		(end -395.603001 23.886518)
		(width 0.127)
		(layer "F.Cu")
		(net "PCIE_T2B_B1_RX_DN<5>")
	)
	(segment
		(start -393.985633 23.217886)
		(end -393.986517 23.217002)
		(width 0.127)
		(layer "F.Cu")
		(net "PCIE_T2B_B1_RX_DN<5>")
	)
	(segment
		(start -378.254999 36.674999)
		(end -378.737599 37.157599)
		(width 0.127)
		(layer "F.Cu")
		(net "PCIE_T2B_B1_RX_DN<5>")
	)
	(segment
		(start -381.291592 36.519089)
		(end -381.291592 35.738293)
		(width 0.127)
		(layer "F.Cu")
		(net "PCIE_T2B_B1_RX_DN<5>")
	)
	(segment
		(start -395.603001 23.953112)
		(end -395.605 23.955111)
		(width 0.127)
		(layer "F.Cu")
		(net "PCIE_T2B_B1_RX_DN<5>")
	)
	(segment
		(start -378.737599 37.157599)
		(end -380.653082 37.157599)
		(width 0.127)
		(layer "F.Cu")
		(net "PCIE_T2B_B1_RX_DN<5>")
	)
	(segment
		(start -395.44244 21.971)
		(end -397.6116 24.14016)
		(width 0.127)
		(layer "F.Cu")
		(net "PCIE_T2B_B1_RX_DN<4>")
	)
	(segment
		(start -397.6116 42.933803)
		(end -397.7854 43.107602)
		(width 0.127)
		(layer "F.Cu")
		(net "PCIE_T2B_B1_RX_DN<4>")
	)
	(segment
		(start -397.6116 24.14016)
		(end -397.6116 42.933803)
		(width 0.127)
		(layer "F.Cu")
		(net "PCIE_T2B_B1_RX_DN<4>")
	)
	(segment
		(start -397.7854 43.107602)
		(end -397.9124 43.107602)
		(width 0.127)
		(layer "F.Cu")
		(net "PCIE_T2B_B1_RX_DN<4>")
	)
	(segment
		(start -380.314947 34.5948)
		(end -381.3556 33.554147)
		(width 0.127)
		(layer "F.Cu")
		(net "PCIE_T2B_B1_RX_DN<4>")
	)
	(segment
		(start -388.112 26.416747)
		(end -388.112 23.943114)
		(width 0.127)
		(layer "F.Cu")
		(net "PCIE_T2B_B1_RX_DN<4>")
	)
	(segment
		(start -390.084114 21.971)
		(end -395.44244 21.971)
		(width 0.127)
		(layer "F.Cu")
		(net "PCIE_T2B_B1_RX_DN<4>")
	)
	(segment
		(start -397.9124 43.107602)
		(end -398.460001 42.560001)
		(width 0.127)
		(layer "F.Cu")
		(net "PCIE_T2B_B1_RX_DN<4>")
	)
	(segment
		(start -385.318 29.21)
		(end -385.318747 29.21)
		(width 0.127)
		(layer "F.Cu")
		(net "PCIE_T2B_B1_RX_DN<4>")
	)
	(segment
		(start -388.112 23.943114)
		(end -390.084114 21.971)
		(width 0.127)
		(layer "F.Cu")
		(net "PCIE_T2B_B1_RX_DN<4>")
	)
	(segment
		(start -381.3556 33.1724)
		(end -385.318 29.21)
		(width 0.127)
		(layer "F.Cu")
		(net "PCIE_T2B_B1_RX_DN<4>")
	)
	(segment
		(start -379.524999 34.134999)
		(end -379.9848 34.5948)
		(width 0.127)
		(layer "F.Cu")
		(net "PCIE_T2B_B1_RX_DN<4>")
	)
	(segment
		(start -385.318747 29.21)
		(end -388.112 26.416747)
		(width 0.127)
		(layer "F.Cu")
		(net "PCIE_T2B_B1_RX_DN<4>")
	)
	(segment
		(start -381.3556 33.554147)
		(end -381.3556 33.1724)
		(width 0.127)
		(layer "F.Cu")
		(net "PCIE_T2B_B1_RX_DN<4>")
	)
	(segment
		(start -379.9848 34.5948)
		(end -380.314947 34.5948)
		(width 0.127)
		(layer "F.Cu")
		(net "PCIE_T2B_B1_RX_DN<4>")
	)
	(segment
		(start -399.785398 44.407602)
		(end -399.912398 44.407602)
		(width 0.127)
		(layer "F.Cu")
		(net "PCIE_T2B_B1_RX_DN<3>")
	)
	(segment
		(start -380.672401 32.077599)
		(end -385.1402 27.6098)
		(width 0.127)
		(layer "F.Cu")
		(net "PCIE_T2B_B1_RX_DN<3>")
	)
	(segment
		(start -399.6182 44.240404)
		(end -399.785398 44.407602)
		(width 0.127)
		(layer "F.Cu")
		(net "PCIE_T2B_B1_RX_DN<3>")
	)
	(segment
		(start -378.737599 32.077599)
		(end -380.672401 32.077599)
		(width 0.127)
		(layer "F.Cu")
		(net "PCIE_T2B_B1_RX_DN<3>")
	)
	(segment
		(start -386.6642 23.666704)
		(end -389.579104 20.7518)
		(width 0.127)
		(layer "F.Cu")
		(net "PCIE_T2B_B1_RX_DN<3>")
	)
	(segment
		(start -389.579104 20.7518)
		(end -396.634462 20.7518)
		(width 0.127)
		(layer "F.Cu")
		(net "PCIE_T2B_B1_RX_DN<3>")
	)
	(segment
		(start -399.6182 23.735538)
		(end -399.6182 44.240404)
		(width 0.127)
		(layer "F.Cu")
		(net "PCIE_T2B_B1_RX_DN<3>")
	)
	(segment
		(start -378.254999 31.594999)
		(end -378.737599 32.077599)
		(width 0.127)
		(layer "F.Cu")
		(net "PCIE_T2B_B1_RX_DN<3>")
	)
	(segment
		(start -385.140947 27.6098)
		(end -386.6642 26.086547)
		(width 0.127)
		(layer "F.Cu")
		(net "PCIE_T2B_B1_RX_DN<3>")
	)
	(segment
		(start -399.912398 44.407602)
		(end -400.459999 43.860001)
		(width 0.127)
		(layer "F.Cu")
		(net "PCIE_T2B_B1_RX_DN<3>")
	)
	(segment
		(start -396.634462 20.7518)
		(end -399.6182 23.735538)
		(width 0.127)
		(layer "F.Cu")
		(net "PCIE_T2B_B1_RX_DN<3>")
	)
	(segment
		(start -386.6642 26.086547)
		(end -386.6642 23.666704)
		(width 0.127)
		(layer "F.Cu")
		(net "PCIE_T2B_B1_RX_DN<3>")
	)
	(segment
		(start -385.1402 27.6098)
		(end -385.140947 27.6098)
		(width 0.127)
		(layer "F.Cu")
		(net "PCIE_T2B_B1_RX_DN<3>")
	)
	(segment
		(start -380.469201 29.537599)
		(end -383.92862 26.07818)
		(width 0.127)
		(layer "F.Cu")
		(net "PCIE_T2B_B1_RX_DN<2>")
	)
	(segment
		(start -397.63573 19.5326)
		(end -401.614213 23.511083)
		(width 0.127)
		(layer "F.Cu")
		(net "PCIE_T2B_B1_RX_DN<2>")
	)
	(segment
		(start -401.912399 43.107602)
		(end -402.46 42.560001)
		(width 0.127)
		(layer "F.Cu")
		(net "PCIE_T2B_B1_RX_DN<2>")
	)
	(segment
		(start -383.92862 26.07818)
		(end -383.92862 24.37257)
		(width 0.127)
		(layer "F.Cu")
		(net "PCIE_T2B_B1_RX_DN<2>")
	)
	(segment
		(start -401.614213 42.936417)
		(end -401.785399 43.107602)
		(width 0.127)
		(layer "F.Cu")
		(net "PCIE_T2B_B1_RX_DN<2>")
	)
	(segment
		(start -380.007599 29.537599)
		(end -380.469201 29.537599)
		(width 0.127)
		(layer "F.Cu")
		(net "PCIE_T2B_B1_RX_DN<2>")
	)
	(segment
		(start -401.614213 23.511083)
		(end -401.614213 42.936417)
		(width 0.127)
		(layer "F.Cu")
		(net "PCIE_T2B_B1_RX_DN<2>")
	)
	(segment
		(start -388.76859 19.5326)
		(end -397.63573 19.5326)
		(width 0.127)
		(layer "F.Cu")
		(net "PCIE_T2B_B1_RX_DN<2>")
	)
	(segment
		(start -401.785399 43.107602)
		(end -401.912399 43.107602)
		(width 0.127)
		(layer "F.Cu")
		(net "PCIE_T2B_B1_RX_DN<2>")
	)
	(segment
		(start -383.92862 24.37257)
		(end -388.76859 19.5326)
		(width 0.127)
		(layer "F.Cu")
		(net "PCIE_T2B_B1_RX_DN<2>")
	)
	(segment
		(start -379.524999 29.054999)
		(end -380.007599 29.537599)
		(width 0.127)
		(layer "F.Cu")
		(net "PCIE_T2B_B1_RX_DN<2>")
	)
	(segment
		(start -403.912398 44.407602)
		(end -404.459999 43.860001)
		(width 0.127)
		(layer "F.Cu")
		(net "PCIE_T2B_B1_RX_DN<1>")
	)
	(segment
		(start -382.662176 23.644012)
		(end -382.840636 23.465551)
		(width 0.127)
		(layer "F.Cu")
		(net "PCIE_T2B_B1_RX_DN<1>")
	)
	(segment
		(start -378.254999 26.514999)
		(end -378.737599 26.997599)
		(width 0.127)
		(layer "F.Cu")
		(net "PCIE_T2B_B1_RX_DN<1>")
	)
	(segment
		(start -403.785398 44.407602)
		(end -403.912398 44.407602)
		(width 0.127)
		(layer "F.Cu")
		(net "PCIE_T2B_B1_RX_DN<1>")
	)
	(segment
		(start -378.737599 26.997599)
		(end -380.940937 26.997599)
		(width 0.127)
		(layer "F.Cu")
		(net "PCIE_T2B_B1_RX_DN<1>")
	)
	(segment
		(start -403.606 44.228205)
		(end -403.785398 44.407602)
		(width 0.127)
		(layer "F.Cu")
		(net "PCIE_T2B_B1_RX_DN<1>")
	)
	(segment
		(start -387.992874 18.3134)
		(end -398.533112 18.3134)
		(width 0.127)
		(layer "F.Cu")
		(net "PCIE_T2B_B1_RX_DN<1>")
	)
	(segment
		(start -380.940937 26.997599)
		(end -382.662176 25.27636)
		(width 0.127)
		(layer "F.Cu")
		(net "PCIE_T2B_B1_RX_DN<1>")
	)
	(segment
		(start -403.606 23.386288)
		(end -403.606 44.228205)
		(width 0.127)
		(layer "F.Cu")
		(net "PCIE_T2B_B1_RX_DN<1>")
	)
	(segment
		(start -398.533112 18.3134)
		(end -403.606 23.386288)
		(width 0.127)
		(layer "F.Cu")
		(net "PCIE_T2B_B1_RX_DN<1>")
	)
	(segment
		(start -382.840723 23.465551)
		(end -387.992874 18.3134)
		(width 0.127)
		(layer "F.Cu")
		(net "PCIE_T2B_B1_RX_DN<1>")
	)
	(segment
		(start -382.840636 23.465551)
		(end -382.840723 23.465551)
		(width 0.127)
		(layer "F.Cu")
		(net "PCIE_T2B_B1_RX_DN<1>")
	)
	(segment
		(start -382.662176 25.27636)
		(end -382.662176 23.644012)
		(width 0.127)
		(layer "F.Cu")
		(net "PCIE_T2B_B1_RX_DN<1>")
	)
	(segment
		(start -375.714999 41.754999)
		(end -376.349999 41.119999)
		(width 0.127)
		(layer "F.Cu")
		(net "PCIE_T2B_B1_RX_DN<15>")
	)
	(via
		(at -376.349999 41.119999)
		(size 0.5588)
		(drill 0.254)
		(layers "F.Cu" "B.Cu")
		(net "PCIE_T2B_B1_RX_DN<15>")
	)
	(segment
		(start -376.838949 41.608949)
		(end -377.9482 41.608949)
		(width 0.127)
		(layer "In2.Cu")
		(net "PCIE_T2B_B1_RX_DN<15>")
	)
	(segment
		(start -391.906051 40.213951)
		(end -392.46 39.660002)
		(width 0.127)
		(layer "In2.Cu")
		(net "PCIE_T2B_B1_RX_DN<15>")
	)
	(segment
		(start -376.349999 41.119999)
		(end -376.838949 41.608949)
		(width 0.127)
		(layer "In2.Cu")
		(net "PCIE_T2B_B1_RX_DN<15>")
	)
	(segment
		(start -377.9482 41.608949)
		(end -380.661888 44.322637)
		(width 0.127)
		(layer "In2.Cu")
		(net "PCIE_T2B_B1_RX_DN<15>")
	)
	(segment
		(start -387.43731 44.322637)
		(end -391.545996 40.213951)
		(width 0.127)
		(layer "In2.Cu")
		(net "PCIE_T2B_B1_RX_DN<15>")
	)
	(segment
		(start -380.661888 44.322637)
		(end -387.43731 44.322637)
		(width 0.127)
		(layer "In2.Cu")
		(net "PCIE_T2B_B1_RX_DN<15>")
	)
	(segment
		(start -391.545996 40.213951)
		(end -391.906051 40.213951)
		(width 0.127)
		(layer "In2.Cu")
		(net "PCIE_T2B_B1_RX_DN<15>")
	)
	(segment
		(start -376.984999 39.214999)
		(end -377.619999 38.579999)
		(width 0.127)
		(layer "F.Cu")
		(net "PCIE_T2B_B1_RX_DN<14>")
	)
	(via
		(at -377.619999 38.579999)
		(size 0.5588)
		(drill 0.254)
		(layers "F.Cu" "B.Cu")
		(net "PCIE_T2B_B1_RX_DN<14>")
	)
	(segment
		(start -393.906052 38.913951)
		(end -393.68729 38.913951)
		(width 0.127)
		(layer "In2.Cu")
		(net "PCIE_T2B_B1_RX_DN<14>")
	)
	(segment
		(start -380.965205 39.068949)
		(end -378.108949 39.068949)
		(width 0.127)
		(layer "In2.Cu")
		(net "PCIE_T2B_B1_RX_DN<14>")
	)
	(segment
		(start -393.007685 24.509367)
		(end -391.951395 24.509367)
		(width 0.127)
		(layer "In2.Cu")
		(net "PCIE_T2B_B1_RX_DN<14>")
	)
	(segment
		(start -391.951334 24.509306)
		(end -391.709471 24.509306)
		(width 0.127)
		(layer "In2.Cu")
		(net "PCIE_T2B_B1_RX_DN<14>")
	)
	(segment
		(start -391.951395 24.509367)
		(end -391.951334 24.509306)
		(width 0.127)
		(layer "In2.Cu")
		(net "PCIE_T2B_B1_RX_DN<14>")
	)
	(segment
		(start -390.464451 29.569702)
		(end -380.965205 39.068949)
		(width 0.127)
		(layer "In2.Cu")
		(net "PCIE_T2B_B1_RX_DN<14>")
	)
	(segment
		(start -390.464451 25.754325)
		(end -390.464451 29.569702)
		(width 0.127)
		(layer "In2.Cu")
		(net "PCIE_T2B_B1_RX_DN<14>")
	)
	(segment
		(start -394.460001 38.360002)
		(end -393.906052 38.913951)
		(width 0.127)
		(layer "In2.Cu")
		(net "PCIE_T2B_B1_RX_DN<14>")
	)
	(segment
		(start -393.5903 38.816961)
		(end -393.5903 25.091982)
		(width 0.127)
		(layer "In2.Cu")
		(net "PCIE_T2B_B1_RX_DN<14>")
	)
	(segment
		(start -393.5903 25.091982)
		(end -393.007685 24.509367)
		(width 0.127)
		(layer "In2.Cu")
		(net "PCIE_T2B_B1_RX_DN<14>")
	)
	(segment
		(start -391.709471 24.509306)
		(end -390.464451 25.754325)
		(width 0.127)
		(layer "In2.Cu")
		(net "PCIE_T2B_B1_RX_DN<14>")
	)
	(segment
		(start -393.68729 38.913951)
		(end -393.5903 38.816961)
		(width 0.127)
		(layer "In2.Cu")
		(net "PCIE_T2B_B1_RX_DN<14>")
	)
	(segment
		(start -378.108949 39.068949)
		(end -377.619999 38.579999)
		(width 0.127)
		(layer "In2.Cu")
		(net "PCIE_T2B_B1_RX_DN<14>")
	)
	(segment
		(start -375.714999 36.674999)
		(end -376.349999 36.039999)
		(width 0.127)
		(layer "F.Cu")
		(net "PCIE_T2B_B1_RX_DN<13>")
	)
	(via
		(at -376.349999 36.039999)
		(size 0.5588)
		(drill 0.254)
		(layers "F.Cu" "B.Cu")
		(net "PCIE_T2B_B1_RX_DN<13>")
	)
	(segment
		(start -396.46 39.660002)
		(end -395.906051 40.213951)
		(width 0.127)
		(layer "In2.Cu")
		(net "PCIE_T2B_B1_RX_DN<13>")
	)
	(segment
		(start -395.001288 23.2156)
		(end -391.014082 23.2156)
		(width 0.127)
		(layer "In2.Cu")
		(net "PCIE_T2B_B1_RX_DN<13>")
	)
	(segment
		(start -381.458318 35.717109)
		(end -379.55251 35.717109)
		(width 0.127)
		(layer "In2.Cu")
		(net "PCIE_T2B_B1_RX_DN<13>")
	)
	(segment
		(start -395.906051 40.213951)
		(end -395.672155 40.213951)
		(width 0.127)
		(layer "In2.Cu")
		(net "PCIE_T2B_B1_RX_DN<13>")
	)
	(segment
		(start -389.0264 28.149027)
		(end -381.458318 35.717109)
		(width 0.127)
		(layer "In2.Cu")
		(net "PCIE_T2B_B1_RX_DN<13>")
	)
	(segment
		(start -379.55251 35.717109)
		(end -379.381487 35.888132)
		(width 0.127)
		(layer "In2.Cu")
		(net "PCIE_T2B_B1_RX_DN<13>")
	)
	(segment
		(start -376.838949 36.528949)
		(end -376.349999 36.039999)
		(width 0.127)
		(layer "In2.Cu")
		(net "PCIE_T2B_B1_RX_DN<13>")
	)
	(segment
		(start -378.740754 36.528949)
		(end -376.838949 36.528949)
		(width 0.127)
		(layer "In2.Cu")
		(net "PCIE_T2B_B1_RX_DN<13>")
	)
	(segment
		(start -395.590301 40.132097)
		(end -395.590301 23.804613)
		(width 0.127)
		(layer "In2.Cu")
		(net "PCIE_T2B_B1_RX_DN<13>")
	)
	(segment
		(start -395.672155 40.213951)
		(end -395.590301 40.132097)
		(width 0.127)
		(layer "In2.Cu")
		(net "PCIE_T2B_B1_RX_DN<13>")
	)
	(segment
		(start -389.0264 25.203282)
		(end -389.0264 28.149027)
		(width 0.127)
		(layer "In2.Cu")
		(net "PCIE_T2B_B1_RX_DN<13>")
	)
	(segment
		(start -395.590301 23.804613)
		(end -395.001288 23.2156)
		(width 0.127)
		(layer "In2.Cu")
		(net "PCIE_T2B_B1_RX_DN<13>")
	)
	(segment
		(start -379.381487 35.888132)
		(end -379.381487 35.888216)
		(width 0.127)
		(layer "In2.Cu")
		(net "PCIE_T2B_B1_RX_DN<13>")
	)
	(segment
		(start -391.014082 23.2156)
		(end -389.0264 25.203282)
		(width 0.127)
		(layer "In2.Cu")
		(net "PCIE_T2B_B1_RX_DN<13>")
	)
	(segment
		(start -379.381487 35.888216)
		(end -378.740754 36.528949)
		(width 0.127)
		(layer "In2.Cu")
		(net "PCIE_T2B_B1_RX_DN<13>")
	)
	(segment
		(start -376.984999 34.134999)
		(end -377.619999 33.499999)
		(width 0.127)
		(layer "F.Cu")
		(net "PCIE_T2B_B1_RX_DN<12>")
	)
	(via
		(at -377.619999 33.499999)
		(size 0.5588)
		(drill 0.254)
		(layers "F.Cu" "B.Cu")
		(net "PCIE_T2B_B1_RX_DN<12>")
	)
	(segment
		(start -397.5903 38.725198)
		(end -397.5903 23.946531)
		(width 0.127)
		(layer "In2.Cu")
		(net "PCIE_T2B_B1_RX_DN<12>")
	)
	(segment
		(start -397.5903 23.946531)
		(end -395.805269 22.1615)
		(width 0.127)
		(layer "In2.Cu")
		(net "PCIE_T2B_B1_RX_DN<12>")
	)
	(segment
		(start -387.858 27.110154)
		(end -380.979205 33.988949)
		(width 0.127)
		(layer "In2.Cu")
		(net "PCIE_T2B_B1_RX_DN<12>")
	)
	(segment
		(start -390.210106 22.1615)
		(end -387.858 24.513606)
		(width 0.127)
		(layer "In2.Cu")
		(net "PCIE_T2B_B1_RX_DN<12>")
	)
	(segment
		(start -398.460001 38.360002)
		(end -397.906052 38.913951)
		(width 0.127)
		(layer "In2.Cu")
		(net "PCIE_T2B_B1_RX_DN<12>")
	)
	(segment
		(start -380.979205 33.988949)
		(end -378.108949 33.988949)
		(width 0.127)
		(layer "In2.Cu")
		(net "PCIE_T2B_B1_RX_DN<12>")
	)
	(segment
		(start -378.108949 33.988949)
		(end -377.619999 33.499999)
		(width 0.127)
		(layer "In2.Cu")
		(net "PCIE_T2B_B1_RX_DN<12>")
	)
	(segment
		(start -395.805269 22.1615)
		(end -390.210106 22.1615)
		(width 0.127)
		(layer "In2.Cu")
		(net "PCIE_T2B_B1_RX_DN<12>")
	)
	(segment
		(start -387.858 24.513606)
		(end -387.858 27.110154)
		(width 0.127)
		(layer "In2.Cu")
		(net "PCIE_T2B_B1_RX_DN<12>")
	)
	(segment
		(start -397.779052 38.913951)
		(end -397.5903 38.725198)
		(width 0.127)
		(layer "In2.Cu")
		(net "PCIE_T2B_B1_RX_DN<12>")
	)
	(segment
		(start -397.906052 38.913951)
		(end -397.779052 38.913951)
		(width 0.127)
		(layer "In2.Cu")
		(net "PCIE_T2B_B1_RX_DN<12>")
	)
	(segment
		(start -375.714999 31.594999)
		(end -376.349999 30.959999)
		(width 0.127)
		(layer "F.Cu")
		(net "PCIE_T2B_B1_RX_DN<11>")
	)
	(via
		(at -376.349999 30.959999)
		(size 0.5588)
		(drill 0.254)
		(layers "F.Cu" "B.Cu")
		(net "PCIE_T2B_B1_RX_DN<11>")
	)
	(segment
		(start -386.3086 25.125837)
		(end -380.791311 30.643126)
		(width 0.127)
		(layer "In2.Cu")
		(net "PCIE_T2B_B1_RX_DN<11>")
	)
	(segment
		(start -379.909835 30.643126)
		(end -379.738811 30.81415)
		(width 0.127)
		(layer "In2.Cu")
		(net "PCIE_T2B_B1_RX_DN<11>")
	)
	(segment
		(start -379.104096 31.448949)
		(end -376.838949 31.448949)
		(width 0.127)
		(layer "In2.Cu")
		(net "PCIE_T2B_B1_RX_DN<11>")
	)
	(segment
		(start -400.459999 39.660002)
		(end -399.906048 40.213953)
		(width 0.127)
		(layer "In2.Cu")
		(net "PCIE_T2B_B1_RX_DN<11>")
	)
	(segment
		(start -379.738811 30.814234)
		(end -379.104096 31.448949)
		(width 0.127)
		(layer "In2.Cu")
		(net "PCIE_T2B_B1_RX_DN<11>")
	)
	(segment
		(start -399.906048 40.213953)
		(end -399.695825 40.213953)
		(width 0.127)
		(layer "In2.Cu")
		(net "PCIE_T2B_B1_RX_DN<11>")
	)
	(segment
		(start -397.074558 21.1201)
		(end -389.321962 21.1201)
		(width 0.127)
		(layer "In2.Cu")
		(net "PCIE_T2B_B1_RX_DN<11>")
	)
	(segment
		(start -399.590301 40.108429)
		(end -399.590301 23.635843)
		(width 0.127)
		(layer "In2.Cu")
		(net "PCIE_T2B_B1_RX_DN<11>")
	)
	(segment
		(start -399.590301 23.635843)
		(end -397.074558 21.1201)
		(width 0.127)
		(layer "In2.Cu")
		(net "PCIE_T2B_B1_RX_DN<11>")
	)
	(segment
		(start -380.791311 30.643126)
		(end -379.909835 30.643126)
		(width 0.127)
		(layer "In2.Cu")
		(net "PCIE_T2B_B1_RX_DN<11>")
	)
	(segment
		(start -376.838949 31.448949)
		(end -376.349999 30.959999)
		(width 0.127)
		(layer "In2.Cu")
		(net "PCIE_T2B_B1_RX_DN<11>")
	)
	(segment
		(start -389.321962 21.1201)
		(end -386.3086 24.133462)
		(width 0.127)
		(layer "In2.Cu")
		(net "PCIE_T2B_B1_RX_DN<11>")
	)
	(segment
		(start -399.695825 40.213953)
		(end -399.590301 40.108429)
		(width 0.127)
		(layer "In2.Cu")
		(net "PCIE_T2B_B1_RX_DN<11>")
	)
	(segment
		(start -379.738811 30.81415)
		(end -379.738811 30.814234)
		(width 0.127)
		(layer "In2.Cu")
		(net "PCIE_T2B_B1_RX_DN<11>")
	)
	(segment
		(start -386.3086 24.133462)
		(end -386.3086 25.125837)
		(width 0.127)
		(layer "In2.Cu")
		(net "PCIE_T2B_B1_RX_DN<11>")
	)
	(segment
		(start -376.984999 29.054999)
		(end -377.619999 28.419999)
		(width 0.127)
		(layer "F.Cu")
		(net "PCIE_T2B_B1_RX_DN<10>")
	)
	(via
		(at -377.619999 28.419999)
		(size 0.5588)
		(drill 0.254)
		(layers "F.Cu" "B.Cu")
		(net "PCIE_T2B_B1_RX_DN<10>")
	)
	(segment
		(start -384.461715 24.781142)
		(end -384.461715 23.884054)
		(width 0.127)
		(layer "In2.Cu")
		(net "PCIE_T2B_B1_RX_DN<10>")
	)
	(segment
		(start -401.906052 38.913951)
		(end -402.46 38.360002)
		(width 0.127)
		(layer "In2.Cu")
		(net "PCIE_T2B_B1_RX_DN<10>")
	)
	(segment
		(start -401.779052 38.913951)
		(end -401.906052 38.913951)
		(width 0.127)
		(layer "In2.Cu")
		(net "PCIE_T2B_B1_RX_DN<10>")
	)
	(segment
		(start -377.619999 28.419999)
		(end -378.108949 28.908949)
		(width 0.127)
		(layer "In2.Cu")
		(net "PCIE_T2B_B1_RX_DN<10>")
	)
	(segment
		(start -401.6218 23.690158)
		(end -401.6218 38.756699)
		(width 0.127)
		(layer "In2.Cu")
		(net "PCIE_T2B_B1_RX_DN<10>")
	)
	(segment
		(start -384.461715 23.884054)
		(end -388.26707 20.0787)
		(width 0.127)
		(layer "In2.Cu")
		(net "PCIE_T2B_B1_RX_DN<10>")
	)
	(segment
		(start -398.010342 20.0787)
		(end -401.6218 23.690158)
		(width 0.127)
		(layer "In2.Cu")
		(net "PCIE_T2B_B1_RX_DN<10>")
	)
	(segment
		(start -388.26707 20.0787)
		(end -398.010342 20.0787)
		(width 0.127)
		(layer "In2.Cu")
		(net "PCIE_T2B_B1_RX_DN<10>")
	)
	(segment
		(start -401.6218 38.756699)
		(end -401.779052 38.913951)
		(width 0.127)
		(layer "In2.Cu")
		(net "PCIE_T2B_B1_RX_DN<10>")
	)
	(segment
		(start -380.333908 28.908949)
		(end -384.461715 24.781142)
		(width 0.127)
		(layer "In2.Cu")
		(net "PCIE_T2B_B1_RX_DN<10>")
	)
	(segment
		(start -378.108949 28.908949)
		(end -380.333908 28.908949)
		(width 0.127)
		(layer "In2.Cu")
		(net "PCIE_T2B_B1_RX_DN<10>")
	)
	(segment
		(start -381.204724 23.05431)
		(end -381.204724 23.854903)
		(width 0.127)
		(layer "F.Cu")
		(net "PCIE_T2B_B1_RX_DN<0>")
	)
	(segment
		(start -405.795645 43.107602)
		(end -405.60592 42.917877)
		(width 0.127)
		(layer "F.Cu")
		(net "PCIE_T2B_B1_RX_DN<0>")
	)
	(segment
		(start -405.60592 42.917877)
		(end -405.60592 22.992004)
		(width 0.127)
		(layer "F.Cu")
		(net "PCIE_T2B_B1_RX_DN<0>")
	)
	(segment
		(start -406.46 42.560001)
		(end -405.912399 43.107602)
		(width 0.127)
		(layer "F.Cu")
		(net "PCIE_T2B_B1_RX_DN<0>")
	)
	(segment
		(start -387.164834 17.0942)
		(end -381.204724 23.05431)
		(width 0.127)
		(layer "F.Cu")
		(net "PCIE_T2B_B1_RX_DN<0>")
	)
	(segment
		(start -405.912399 43.107602)
		(end -405.795645 43.107602)
		(width 0.127)
		(layer "F.Cu")
		(net "PCIE_T2B_B1_RX_DN<0>")
	)
	(segment
		(start -380.007599 24.457599)
		(end -379.524999 23.974999)
		(width 0.127)
		(layer "F.Cu")
		(net "PCIE_T2B_B1_RX_DN<0>")
	)
	(segment
		(start -380.602028 24.457599)
		(end -380.007599 24.457599)
		(width 0.127)
		(layer "F.Cu")
		(net "PCIE_T2B_B1_RX_DN<0>")
	)
	(segment
		(start -381.204724 23.854903)
		(end -380.602028 24.457599)
		(width 0.127)
		(layer "F.Cu")
		(net "PCIE_T2B_B1_RX_DN<0>")
	)
	(segment
		(start -399.708116 17.0942)
		(end -387.164834 17.0942)
		(width 0.127)
		(layer "F.Cu")
		(net "PCIE_T2B_B1_RX_DN<0>")
	)
	(segment
		(start -405.60592 22.992004)
		(end -399.708116 17.0942)
		(width 0.127)
		(layer "F.Cu")
		(net "PCIE_T2B_B1_RX_DN<0>")
	)
	(segment
		(start -149.634999 20.164999)
		(end -150.269999 19.529999)
		(width 0.127)
		(layer "F.Cu")
		(net "PCIE_RESET_B2_N<3>")
	)
	(via
		(at -150.269999 19.529999)
		(size 0.5588)
		(drill 0.254)
		(layers "F.Cu" "B.Cu")
		(net "PCIE_RESET_B2_N<3>")
	)
	(segment
		(start -170.033 35.433)
		(end -171.46 36.86)
		(width 0.12954)
		(layer "In3.Cu")
		(net "PCIE_RESET_B2_N<3>")
	)
	(segment
		(start -170.033 31.8516)
		(end -170.033 35.433)
		(width 0.12954)
		(layer "In3.Cu")
		(net "PCIE_RESET_B2_N<3>")
	)
	(segment
		(start -149.5352 32.5882)
		(end -149.7892 32.8422)
		(width 0.12954)
		(layer "In3.Cu")
		(net "PCIE_RESET_B2_N<3>")
	)
	(segment
		(start -149.7892 32.8422)
		(end -158.84906 32.8422)
		(width 0.12954)
		(layer "In3.Cu")
		(net "PCIE_RESET_B2_N<3>")
	)
	(segment
		(start -149.5352 20.264798)
		(end -149.5352 32.5882)
		(width 0.12954)
		(layer "In3.Cu")
		(net "PCIE_RESET_B2_N<3>")
	)
	(segment
		(start -150.269999 19.529999)
		(end -149.5352 20.264798)
		(width 0.12954)
		(layer "In3.Cu")
		(net "PCIE_RESET_B2_N<3>")
	)
	(segment
		(start -167.347847 29.166447)
		(end -170.033 31.8516)
		(width 0.12954)
		(layer "In3.Cu")
		(net "PCIE_RESET_B2_N<3>")
	)
	(segment
		(start -158.84906 32.8422)
		(end -162.524813 29.166447)
		(width 0.12954)
		(layer "In3.Cu")
		(net "PCIE_RESET_B2_N<3>")
	)
	(segment
		(start -162.524813 29.166447)
		(end -167.347847 29.166447)
		(width 0.12954)
		(layer "In3.Cu")
		(net "PCIE_RESET_B2_N<3>")
	)
	(segment
		(start -150.904999 21.434999)
		(end -151.539999 20.799999)
		(width 0.1016)
		(layer "F.Cu")
		(net "PCIE_RESET_B2_N<2>")
	)
	(via
		(at -151.539999 20.799999)
		(size 0.5588)
		(drill 0.254)
		(layers "F.Cu" "B.Cu")
		(net "PCIE_RESET_B2_N<2>")
	)
	(segment
		(start -151.3894 30.3784)
		(end -150.856 29.845)
		(width 0.12954)
		(layer "In3.Cu")
		(net "PCIE_RESET_B2_N<2>")
	)
	(segment
		(start -170.541 34.541)
		(end -170.541 31.6992)
		(width 0.12954)
		(layer "In3.Cu")
		(net "PCIE_RESET_B2_N<2>")
	)
	(segment
		(start -161.14268 28.72486)
		(end -159.48914 30.3784)
		(width 0.12954)
		(layer "In3.Cu")
		(net "PCIE_RESET_B2_N<2>")
	)
	(segment
		(start -159.48914 30.3784)
		(end -151.3894 30.3784)
		(width 0.12954)
		(layer "In3.Cu")
		(net "PCIE_RESET_B2_N<2>")
	)
	(segment
		(start -170.541 31.6992)
		(end -167.56666 28.72486)
		(width 0.12954)
		(layer "In3.Cu")
		(net "PCIE_RESET_B2_N<2>")
	)
	(segment
		(start -150.856 21.483998)
		(end -151.539999 20.799999)
		(width 0.12954)
		(layer "In3.Cu")
		(net "PCIE_RESET_B2_N<2>")
	)
	(segment
		(start -150.856 29.845)
		(end -150.856 21.483998)
		(width 0.12954)
		(layer "In3.Cu")
		(net "PCIE_RESET_B2_N<2>")
	)
	(segment
		(start -171.46 35.46)
		(end -170.541 34.541)
		(width 0.12954)
		(layer "In3.Cu")
		(net "PCIE_RESET_B2_N<2>")
	)
	(segment
		(start -167.56666 28.72486)
		(end -161.14268 28.72486)
		(width 0.12954)
		(layer "In3.Cu")
		(net "PCIE_RESET_B2_N<2>")
	)
	(segment
		(start -150.904999 20.164999)
		(end -151.539999 19.529999)
		(width 0.127)
		(layer "F.Cu")
		(net "PCIE_RESET_B2_N<1>")
	)
	(via
		(at -151.539999 19.529999)
		(size 0.5588)
		(drill 0.254)
		(layers "F.Cu" "B.Cu")
		(net "PCIE_RESET_B2_N<1>")
	)
	(segment
		(start -172.319 25.273)
		(end -172.319 34.417)
		(width 0.12954)
		(layer "In3.Cu")
		(net "PCIE_RESET_B2_N<1>")
	)
	(segment
		(start -172.319 34.417)
		(end -173.460001 35.558001)
		(width 0.12954)
		(layer "In3.Cu")
		(net "PCIE_RESET_B2_N<1>")
	)
	(segment
		(start -162.88798 27.09926)
		(end -165.22224 24.765)
		(width 0.12954)
		(layer "In3.Cu")
		(net "PCIE_RESET_B2_N<1>")
	)
	(segment
		(start -171.811 24.765)
		(end -172.319 25.273)
		(width 0.12954)
		(layer "In3.Cu")
		(net "PCIE_RESET_B2_N<1>")
	)
	(segment
		(start -151.539999 19.529999)
		(end -152.17934 20.16934)
		(width 0.12954)
		(layer "In3.Cu")
		(net "PCIE_RESET_B2_N<1>")
	)
	(segment
		(start -173.460001 35.558001)
		(end -173.460001 35.56)
		(width 0.12954)
		(layer "In3.Cu")
		(net "PCIE_RESET_B2_N<1>")
	)
	(segment
		(start -152.52478 27.79776)
		(end -157.67336 27.79776)
		(width 0.12954)
		(layer "In3.Cu")
		(net "PCIE_RESET_B2_N<1>")
	)
	(segment
		(start -158.37186 27.09926)
		(end -162.88798 27.09926)
		(width 0.12954)
		(layer "In3.Cu")
		(net "PCIE_RESET_B2_N<1>")
	)
	(segment
		(start -157.67336 27.79776)
		(end -158.37186 27.09926)
		(width 0.12954)
		(layer "In3.Cu")
		(net "PCIE_RESET_B2_N<1>")
	)
	(segment
		(start -152.17934 27.45232)
		(end -152.52478 27.79776)
		(width 0.12954)
		(layer "In3.Cu")
		(net "PCIE_RESET_B2_N<1>")
	)
	(segment
		(start -152.17934 20.16934)
		(end -152.17934 27.45232)
		(width 0.12954)
		(layer "In3.Cu")
		(net "PCIE_RESET_B2_N<1>")
	)
	(segment
		(start -165.22224 24.765)
		(end -171.811 24.765)
		(width 0.12954)
		(layer "In3.Cu")
		(net "PCIE_RESET_B2_N<1>")
	)
	(segment
		(start -152.174999 20.164999)
		(end -152.809999 19.529999)
		(width 0.127)
		(layer "F.Cu")
		(net "PCIE_RESET_B2_N<0>")
	)
	(via
		(at -152.809999 19.529999)
		(size 0.5588)
		(drill 0.254)
		(layers "F.Cu" "B.Cu")
		(net "PCIE_RESET_B2_N<0>")
	)
	(segment
		(start -153.396 20.116)
		(end -152.809999 19.529999)
		(width 0.12954)
		(layer "In3.Cu")
		(net "PCIE_RESET_B2_N<0>")
	)
	(segment
		(start -163.76682 25.21204)
		(end -153.72112 25.21204)
		(width 0.12954)
		(layer "In3.Cu")
		(net "PCIE_RESET_B2_N<0>")
	)
	(segment
		(start -164.67106 24.3078)
		(end -163.76682 25.21204)
		(width 0.12954)
		(layer "In3.Cu")
		(net "PCIE_RESET_B2_N<0>")
	)
	(segment
		(start -173.460001 34.16)
		(end -172.60856 33.308559)
		(width 0.12954)
		(layer "In3.Cu")
		(net "PCIE_RESET_B2_N<0>")
	)
	(segment
		(start -153.72112 25.21204)
		(end -153.396 24.88692)
		(width 0.12954)
		(layer "In3.Cu")
		(net "PCIE_RESET_B2_N<0>")
	)
	(segment
		(start -153.396 24.88692)
		(end -153.396 20.116)
		(width 0.12954)
		(layer "In3.Cu")
		(net "PCIE_RESET_B2_N<0>")
	)
	(segment
		(start -172.0269 24.3078)
		(end -164.67106 24.3078)
		(width 0.12954)
		(layer "In3.Cu")
		(net "PCIE_RESET_B2_N<0>")
	)
	(segment
		(start -172.60856 24.88946)
		(end -172.0269 24.3078)
		(width 0.12954)
		(layer "In3.Cu")
		(net "PCIE_RESET_B2_N<0>")
	)
	(segment
		(start -172.60856 33.308559)
		(end -172.60856 24.88946)
		(width 0.12954)
		(layer "In3.Cu")
		(net "PCIE_RESET_B2_N<0>")
	)
	(segment
		(start -370.634999 20.164999)
		(end -371.269999 19.529999)
		(width 0.127)
		(layer "F.Cu")
		(net "PCIE_RESET_B1_N<3>")
	)
	(via
		(at -371.269999 19.529999)
		(size 0.5588)
		(drill 0.254)
		(layers "F.Cu" "B.Cu")
		(net "PCIE_RESET_B1_N<3>")
	)
	(segment
		(start -388.962824 29.781424)
		(end -388.366 29.781424)
		(width 0.12954)
		(layer "In3.Cu")
		(net "PCIE_RESET_B1_N<3>")
	)
	(segment
		(start -391.033 35.433)
		(end -391.033 31.8516)
		(width 0.12954)
		(layer "In3.Cu")
		(net "PCIE_RESET_B1_N<3>")
	)
	(segment
		(start -370.5352 32.5882)
		(end -370.5352 20.264798)
		(width 0.12954)
		(layer "In3.Cu")
		(net "PCIE_RESET_B1_N<3>")
	)
	(segment
		(start -392.46 36.86)
		(end -391.033 35.433)
		(width 0.12954)
		(layer "In3.Cu")
		(net "PCIE_RESET_B1_N<3>")
	)
	(segment
		(start -378.785178 32.039502)
		(end -377.98248 32.8422)
		(width 0.12954)
		(layer "In3.Cu")
		(net "PCIE_RESET_B1_N<3>")
	)
	(segment
		(start -391.033 31.8516)
		(end -388.962824 29.781424)
		(width 0.12954)
		(layer "In3.Cu")
		(net "PCIE_RESET_B1_N<3>")
	)
	(segment
		(start -370.5352 20.264798)
		(end -371.269999 19.529999)
		(width 0.12954)
		(layer "In3.Cu")
		(net "PCIE_RESET_B1_N<3>")
	)
	(segment
		(start -379.234807 30.873593)
		(end -378.785178 31.323222)
		(width 0.12954)
		(layer "In3.Cu")
		(net "PCIE_RESET_B1_N<3>")
	)
	(segment
		(start -370.7892 32.8422)
		(end -370.5352 32.5882)
		(width 0.12954)
		(layer "In3.Cu")
		(net "PCIE_RESET_B1_N<3>")
	)
	(segment
		(start -388.366 29.781424)
		(end -387.27383 30.873593)
		(width 0.12954)
		(layer "In3.Cu")
		(net "PCIE_RESET_B1_N<3>")
	)
	(segment
		(start -377.98248 32.8422)
		(end -370.7892 32.8422)
		(width 0.12954)
		(layer "In3.Cu")
		(net "PCIE_RESET_B1_N<3>")
	)
	(segment
		(start -387.27383 30.873593)
		(end -379.234807 30.873593)
		(width 0.12954)
		(layer "In3.Cu")
		(net "PCIE_RESET_B1_N<3>")
	)
	(segment
		(start -378.785178 31.323222)
		(end -378.785178 32.039502)
		(width 0.12954)
		(layer "In3.Cu")
		(net "PCIE_RESET_B1_N<3>")
	)
	(segment
		(start -371.904999 21.434999)
		(end -372.539999 20.799999)
		(width 0.127)
		(layer "F.Cu")
		(net "PCIE_RESET_B1_N<2>")
	)
	(via
		(at -372.539999 20.799999)
		(size 0.5588)
		(drill 0.254)
		(layers "F.Cu" "B.Cu")
		(net "PCIE_RESET_B1_N<2>")
	)
	(segment
		(start -391.541 34.541)
		(end -392.46 35.46)
		(width 0.12954)
		(layer "In3.Cu")
		(net "PCIE_RESET_B1_N<2>")
	)
	(segment
		(start -388.2136 29.464015)
		(end -389.305815 29.464015)
		(width 0.12954)
		(layer "In3.Cu")
		(net "PCIE_RESET_B1_N<2>")
	)
	(segment
		(start -372.539999 20.799999)
		(end -371.856 21.483998)
		(width 0.12954)
		(layer "In3.Cu")
		(net "PCIE_RESET_B1_N<2>")
	)
	(segment
		(start -389.305815 29.464015)
		(end -391.541 31.6992)
		(width 0.12954)
		(layer "In3.Cu")
		(net "PCIE_RESET_B1_N<2>")
	)
	(segment
		(start -371.856 21.483998)
		(end -371.856 29.845)
		(width 0.12954)
		(layer "In3.Cu")
		(net "PCIE_RESET_B1_N<2>")
	)
	(segment
		(start -371.856 29.845)
		(end -372.3894 30.3784)
		(width 0.12954)
		(layer "In3.Cu")
		(net "PCIE_RESET_B1_N<2>")
	)
	(segment
		(start -387.299215 30.3784)
		(end -388.2136 29.464015)
		(width 0.12954)
		(layer "In3.Cu")
		(net "PCIE_RESET_B1_N<2>")
	)
	(segment
		(start -372.3894 30.3784)
		(end -387.299215 30.3784)
		(width 0.12954)
		(layer "In3.Cu")
		(net "PCIE_RESET_B1_N<2>")
	)
	(segment
		(start -391.541 31.6992)
		(end -391.541 34.541)
		(width 0.12954)
		(layer "In3.Cu")
		(net "PCIE_RESET_B1_N<2>")
	)
	(segment
		(start -371.904999 20.164999)
		(end -372.539999 19.529999)
		(width 0.127)
		(layer "F.Cu")
		(net "PCIE_RESET_B1_N<1>")
	)
	(via
		(at -372.539999 19.529999)
		(size 0.5588)
		(drill 0.254)
		(layers "F.Cu" "B.Cu")
		(net "PCIE_RESET_B1_N<1>")
	)
	(segment
		(start -392.811 24.765)
		(end -393.319 25.273)
		(width 0.12954)
		(layer "In3.Cu")
		(net "PCIE_RESET_B1_N<1>")
	)
	(segment
		(start -379.37186 27.09926)
		(end -383.88798 27.09926)
		(width 0.12954)
		(layer "In3.Cu")
		(net "PCIE_RESET_B1_N<1>")
	)
	(segment
		(start -386.22224 24.765)
		(end -392.811 24.765)
		(width 0.12954)
		(layer "In3.Cu")
		(net "PCIE_RESET_B1_N<1>")
	)
	(segment
		(start -378.67336 27.79776)
		(end -379.37186 27.09926)
		(width 0.12954)
		(layer "In3.Cu")
		(net "PCIE_RESET_B1_N<1>")
	)
	(segment
		(start -373.17934 20.16934)
		(end -373.17934 27.45232)
		(width 0.12954)
		(layer "In3.Cu")
		(net "PCIE_RESET_B1_N<1>")
	)
	(segment
		(start -373.52478 27.79776)
		(end -378.67336 27.79776)
		(width 0.12954)
		(layer "In3.Cu")
		(net "PCIE_RESET_B1_N<1>")
	)
	(segment
		(start -393.319 25.273)
		(end -393.319 34.417)
		(width 0.12954)
		(layer "In3.Cu")
		(net "PCIE_RESET_B1_N<1>")
	)
	(segment
		(start -383.88798 27.09926)
		(end -386.22224 24.765)
		(width 0.12954)
		(layer "In3.Cu")
		(net "PCIE_RESET_B1_N<1>")
	)
	(segment
		(start -393.319 34.417)
		(end -394.460001 35.558001)
		(width 0.12954)
		(layer "In3.Cu")
		(net "PCIE_RESET_B1_N<1>")
	)
	(segment
		(start -372.539999 19.529999)
		(end -373.17934 20.16934)
		(width 0.12954)
		(layer "In3.Cu")
		(net "PCIE_RESET_B1_N<1>")
	)
	(segment
		(start -373.17934 27.45232)
		(end -373.52478 27.79776)
		(width 0.12954)
		(layer "In3.Cu")
		(net "PCIE_RESET_B1_N<1>")
	)
	(segment
		(start -394.460001 35.558001)
		(end -394.460001 35.56)
		(width 0.12954)
		(layer "In3.Cu")
		(net "PCIE_RESET_B1_N<1>")
	)
	(segment
		(start -373.174999 20.164999)
		(end -373.809999 19.529999)
		(width 0.127)
		(layer "F.Cu")
		(net "PCIE_RESET_B1_N<0>")
	)
	(via
		(at -373.809999 19.529999)
		(size 0.5588)
		(drill 0.254)
		(layers "F.Cu" "B.Cu")
		(net "PCIE_RESET_B1_N<0>")
	)
	(segment
		(start -385.67106 24.3078)
		(end -384.76682 25.21204)
		(width 0.12954)
		(layer "In3.Cu")
		(net "PCIE_RESET_B1_N<0>")
	)
	(segment
		(start -393.0269 24.3078)
		(end -385.67106 24.3078)
		(width 0.12954)
		(layer "In3.Cu")
		(net "PCIE_RESET_B1_N<0>")
	)
	(segment
		(start -384.76682 25.21204)
		(end -374.72112 25.21204)
		(width 0.12954)
		(layer "In3.Cu")
		(net "PCIE_RESET_B1_N<0>")
	)
	(segment
		(start -374.396 24.88692)
		(end -374.396 20.116)
		(width 0.12954)
		(layer "In3.Cu")
		(net "PCIE_RESET_B1_N<0>")
	)
	(segment
		(start -393.60856 24.88946)
		(end -393.0269 24.3078)
		(width 0.12954)
		(layer "In3.Cu")
		(net "PCIE_RESET_B1_N<0>")
	)
	(segment
		(start -374.72112 25.21204)
		(end -374.396 24.88692)
		(width 0.12954)
		(layer "In3.Cu")
		(net "PCIE_RESET_B1_N<0>")
	)
	(segment
		(start -374.396 20.116)
		(end -373.809999 19.529999)
		(width 0.12954)
		(layer "In3.Cu")
		(net "PCIE_RESET_B1_N<0>")
	)
	(segment
		(start -394.460001 34.16)
		(end -393.60856 33.308559)
		(width 0.12954)
		(layer "In3.Cu")
		(net "PCIE_RESET_B1_N<0>")
	)
	(segment
		(start -393.60856 33.308559)
		(end -393.60856 24.88946)
		(width 0.12954)
		(layer "In3.Cu")
		(net "PCIE_RESET_B1_N<0>")
	)
	(segment
		(start -154.714999 20.164999)
		(end -155.349999 19.529999)
		(width 0.127)
		(layer "F.Cu")
		(net "PCIE_CFG_B2_ID1")
	)
	(via
		(at -155.349999 19.529999)
		(size 0.5588)
		(drill 0.254)
		(layers "F.Cu" "B.Cu")
		(net "PCIE_CFG_B2_ID1")
	)
	(segment
		(start -174.084082 23.101082)
		(end -160.828258 23.101082)
		(width 0.12954)
		(layer "In3.Cu")
		(net "PCIE_CFG_B2_ID1")
	)
	(segment
		(start -159.632137 21.90496)
		(end -157.72496 21.90496)
		(width 0.12954)
		(layer "In3.Cu")
		(net "PCIE_CFG_B2_ID1")
	)
	(segment
		(start -174.5796 34.579601)
		(end -174.5796 23.5966)
		(width 0.12954)
		(layer "In3.Cu")
		(net "PCIE_CFG_B2_ID1")
	)
	(segment
		(start -157.72496 21.90496)
		(end -157.266041 21.44604)
		(width 0.12954)
		(layer "In3.Cu")
		(net "PCIE_CFG_B2_ID1")
	)
	(segment
		(start -156.05284 21.0185)
		(end -156.05284 20.23284)
		(width 0.12954)
		(layer "In3.Cu")
		(net "PCIE_CFG_B2_ID1")
	)
	(segment
		(start -174.5796 23.5966)
		(end -174.084082 23.101082)
		(width 0.12954)
		(layer "In3.Cu")
		(net "PCIE_CFG_B2_ID1")
	)
	(segment
		(start -157.266041 21.44604)
		(end -156.48038 21.44604)
		(width 0.12954)
		(layer "In3.Cu")
		(net "PCIE_CFG_B2_ID1")
	)
	(segment
		(start -160.828258 23.101082)
		(end -159.632137 21.90496)
		(width 0.12954)
		(layer "In3.Cu")
		(net "PCIE_CFG_B2_ID1")
	)
	(segment
		(start -156.48038 21.44604)
		(end -156.05284 21.0185)
		(width 0.12954)
		(layer "In3.Cu")
		(net "PCIE_CFG_B2_ID1")
	)
	(segment
		(start -175.46 35.46)
		(end -174.5796 34.579601)
		(width 0.12954)
		(layer "In3.Cu")
		(net "PCIE_CFG_B2_ID1")
	)
	(segment
		(start -156.05284 20.23284)
		(end -155.349999 19.529999)
		(width 0.12954)
		(layer "In3.Cu")
		(net "PCIE_CFG_B2_ID1")
	)
	(segment
		(start -153.444999 20.164999)
		(end -154.079999 19.529999)
		(width 0.127)
		(layer "F.Cu")
		(net "PCIE_CFG_B2_ID0")
	)
	(via
		(at -154.079999 19.529999)
		(size 0.5588)
		(drill 0.254)
		(layers "F.Cu" "B.Cu")
		(net "PCIE_CFG_B2_ID0")
	)
	(segment
		(start -157.95022 22.5933)
		(end -158.87224 23.51532)
		(width 0.12954)
		(layer "In3.Cu")
		(net "PCIE_CFG_B2_ID0")
	)
	(segment
		(start -174.3256 24.003)
		(end -174.3256 35.7256)
		(width 0.12954)
		(layer "In3.Cu")
		(net "PCIE_CFG_B2_ID0")
	)
	(segment
		(start -158.87224 23.51532)
		(end -173.83792 23.51532)
		(width 0.12954)
		(layer "In3.Cu")
		(net "PCIE_CFG_B2_ID0")
	)
	(segment
		(start -154.93016 22.5933)
		(end -157.95022 22.5933)
		(width 0.12954)
		(layer "In3.Cu")
		(net "PCIE_CFG_B2_ID0")
	)
	(segment
		(start -154.6533 22.31644)
		(end -154.93016 22.5933)
		(width 0.12954)
		(layer "In3.Cu")
		(net "PCIE_CFG_B2_ID0")
	)
	(segment
		(start -154.679068 20.129068)
		(end -154.6533 20.154837)
		(width 0.12954)
		(layer "In3.Cu")
		(net "PCIE_CFG_B2_ID0")
	)
	(segment
		(start -173.83792 23.51532)
		(end -174.3256 24.003)
		(width 0.12954)
		(layer "In3.Cu")
		(net "PCIE_CFG_B2_ID0")
	)
	(segment
		(start -154.079999 19.529999)
		(end -154.679068 20.129068)
		(width 0.12954)
		(layer "In3.Cu")
		(net "PCIE_CFG_B2_ID0")
	)
	(segment
		(start -154.6533 20.154837)
		(end -154.6533 22.31644)
		(width 0.12954)
		(layer "In3.Cu")
		(net "PCIE_CFG_B2_ID0")
	)
	(segment
		(start -174.3256 35.7256)
		(end -175.46 36.86)
		(width 0.12954)
		(layer "In3.Cu")
		(net "PCIE_CFG_B2_ID0")
	)
	(segment
		(start -375.714999 20.164999)
		(end -376.349999 19.529999)
		(width 0.127)
		(layer "F.Cu")
		(net "PCIE_CFG_B1_ID1")
	)
	(via
		(at -376.349999 19.529999)
		(size 0.5588)
		(drill 0.254)
		(layers "F.Cu" "B.Cu")
		(net "PCIE_CFG_B1_ID1")
	)
	(segment
		(start -378.266041 21.44604)
		(end -377.48038 21.44604)
		(width 0.12954)
		(layer "In3.Cu")
		(net "PCIE_CFG_B1_ID1")
	)
	(segment
		(start -381.828258 23.101082)
		(end -380.632137 21.90496)
		(width 0.12954)
		(layer "In3.Cu")
		(net "PCIE_CFG_B1_ID1")
	)
	(segment
		(start -377.48038 21.44604)
		(end -377.05284 21.0185)
		(width 0.12954)
		(layer "In3.Cu")
		(net "PCIE_CFG_B1_ID1")
	)
	(segment
		(start -395.5796 23.5966)
		(end -395.084082 23.101082)
		(width 0.12954)
		(layer "In3.Cu")
		(net "PCIE_CFG_B1_ID1")
	)
	(segment
		(start -378.72496 21.90496)
		(end -378.266041 21.44604)
		(width 0.12954)
		(layer "In3.Cu")
		(net "PCIE_CFG_B1_ID1")
	)
	(segment
		(start -395.084082 23.101082)
		(end -381.828258 23.101082)
		(width 0.12954)
		(layer "In3.Cu")
		(net "PCIE_CFG_B1_ID1")
	)
	(segment
		(start -380.632137 21.90496)
		(end -378.72496 21.90496)
		(width 0.12954)
		(layer "In3.Cu")
		(net "PCIE_CFG_B1_ID1")
	)
	(segment
		(start -377.05284 20.23284)
		(end -376.349999 19.529999)
		(width 0.12954)
		(layer "In3.Cu")
		(net "PCIE_CFG_B1_ID1")
	)
	(segment
		(start -377.05284 21.0185)
		(end -377.05284 20.23284)
		(width 0.12954)
		(layer "In3.Cu")
		(net "PCIE_CFG_B1_ID1")
	)
	(segment
		(start -395.5796 34.579601)
		(end -395.5796 23.5966)
		(width 0.12954)
		(layer "In3.Cu")
		(net "PCIE_CFG_B1_ID1")
	)
	(segment
		(start -396.46 35.46)
		(end -395.5796 34.579601)
		(width 0.12954)
		(layer "In3.Cu")
		(net "PCIE_CFG_B1_ID1")
	)
	(segment
		(start -374.444999 20.164999)
		(end -375.079999 19.529999)
		(width 0.127)
		(layer "F.Cu")
		(net "PCIE_CFG_B1_ID0")
	)
	(via
		(at -375.079999 19.529999)
		(size 0.5588)
		(drill 0.254)
		(layers "F.Cu" "B.Cu")
		(net "PCIE_CFG_B1_ID0")
	)
	(segment
		(start -379.87224 23.51532)
		(end -394.83792 23.51532)
		(width 0.12954)
		(layer "In3.Cu")
		(net "PCIE_CFG_B1_ID0")
	)
	(segment
		(start -395.3256 24.003)
		(end -395.3256 35.7256)
		(width 0.12954)
		(layer "In3.Cu")
		(net "PCIE_CFG_B1_ID0")
	)
	(segment
		(start -375.93016 22.5933)
		(end -378.95022 22.5933)
		(width 0.12954)
		(layer "In3.Cu")
		(net "PCIE_CFG_B1_ID0")
	)
	(segment
		(start -395.3256 35.7256)
		(end -396.46 36.86)
		(width 0.12954)
		(layer "In3.Cu")
		(net "PCIE_CFG_B1_ID0")
	)
	(segment
		(start -378.95022 22.5933)
		(end -379.87224 23.51532)
		(width 0.12954)
		(layer "In3.Cu")
		(net "PCIE_CFG_B1_ID0")
	)
	(segment
		(start -375.679068 20.129068)
		(end -375.6533 20.154837)
		(width 0.12954)
		(layer "In3.Cu")
		(net "PCIE_CFG_B1_ID0")
	)
	(segment
		(start -375.6533 22.31644)
		(end -375.93016 22.5933)
		(width 0.12954)
		(layer "In3.Cu")
		(net "PCIE_CFG_B1_ID0")
	)
	(segment
		(start -394.83792 23.51532)
		(end -395.3256 24.003)
		(width 0.12954)
		(layer "In3.Cu")
		(net "PCIE_CFG_B1_ID0")
	)
	(segment
		(start -375.079999 19.529999)
		(end -375.679068 20.129068)
		(width 0.12954)
		(layer "In3.Cu")
		(net "PCIE_CFG_B1_ID0")
	)
	(segment
		(start -375.6533 20.154837)
		(end -375.6533 22.31644)
		(width 0.12954)
		(layer "In3.Cu")
		(net "PCIE_CFG_B1_ID0")
	)
	(segment
		(start -149.634999 27.784999)
		(end -150.269999 27.149999)
		(width 0.127)
		(layer "F.Cu")
		(net "PCIE_B2T_B2_TX_DP<9>")
	)
	(via
		(at -150.269999 27.149999)
		(size 0.5588)
		(drill 0.254)
		(layers "F.Cu" "B.Cu")
		(net "PCIE_B2T_B2_TX_DP<9>")
	)
	(segment
		(start -152.30856 26.3833)
		(end -152.30856 25.59082)
		(width 0.127)
		(layer "In5.Cu")
		(net "PCIE_B2T_B2_TX_DP<9>")
	)
	(segment
		(start -178.5166 19.3294)
		(end -182.3266 23.1394)
		(width 0.127)
		(layer "In5.Cu")
		(net "PCIE_B2T_B2_TX_DP<9>")
	)
	(segment
		(start -150.758949 26.661049)
		(end -152.030811 26.661049)
		(width 0.127)
		(layer "In5.Cu")
		(net "PCIE_B2T_B2_TX_DP<9>")
	)
	(segment
		(start -152.50954 25.38984)
		(end -161.185253 25.38984)
		(width 0.127)
		(layer "In5.Cu")
		(net "PCIE_B2T_B2_TX_DP<9>")
	)
	(segment
		(start -152.30856 25.59082)
		(end -152.50954 25.38984)
		(width 0.127)
		(layer "In5.Cu")
		(net "PCIE_B2T_B2_TX_DP<9>")
	)
	(segment
		(start -152.030811 26.661049)
		(end -152.30856 26.3833)
		(width 0.127)
		(layer "In5.Cu")
		(net "PCIE_B2T_B2_TX_DP<9>")
	)
	(segment
		(start -182.3266 27.657184)
		(end -182.575469 27.906053)
		(width 0.127)
		(layer "In5.Cu")
		(net "PCIE_B2T_B2_TX_DP<9>")
	)
	(segment
		(start -150.269999 27.149999)
		(end -150.758949 26.661049)
		(width 0.127)
		(layer "In5.Cu")
		(net "PCIE_B2T_B2_TX_DP<9>")
	)
	(segment
		(start -182.575469 27.906053)
		(end -182.90605 27.906053)
		(width 0.127)
		(layer "In5.Cu")
		(net "PCIE_B2T_B2_TX_DP<9>")
	)
	(segment
		(start -167.245693 19.3294)
		(end -178.5166 19.3294)
		(width 0.127)
		(layer "In5.Cu")
		(net "PCIE_B2T_B2_TX_DP<9>")
	)
	(segment
		(start -182.90605 27.906053)
		(end -183.459999 28.460002)
		(width 0.127)
		(layer "In5.Cu")
		(net "PCIE_B2T_B2_TX_DP<9>")
	)
	(segment
		(start -182.3266 23.1394)
		(end -182.3266 27.657184)
		(width 0.127)
		(layer "In5.Cu")
		(net "PCIE_B2T_B2_TX_DP<9>")
	)
	(segment
		(start -161.185253 25.38984)
		(end -167.245693 19.3294)
		(width 0.127)
		(layer "In5.Cu")
		(net "PCIE_B2T_B2_TX_DP<9>")
	)
	(segment
		(start -150.904999 25.244999)
		(end -151.539999 24.609999)
		(width 0.127)
		(layer "F.Cu")
		(net "PCIE_B2T_B2_TX_DP<8>")
	)
	(via
		(at -151.539999 24.609999)
		(size 0.5588)
		(drill 0.254)
		(layers "F.Cu" "B.Cu")
		(net "PCIE_B2T_B2_TX_DP<8>")
	)
	(segment
		(start -158.98908 23.72106)
		(end -161.380833 23.72106)
		(width 0.127)
		(layer "In5.Cu")
		(net "PCIE_B2T_B2_TX_DP<8>")
	)
	(segment
		(start -153.78208 22.8473)
		(end -158.11532 22.8473)
		(width 0.127)
		(layer "In5.Cu")
		(net "PCIE_B2T_B2_TX_DP<8>")
	)
	(segment
		(start -151.539999 24.609999)
		(end -152.028949 24.121049)
		(width 0.127)
		(layer "In5.Cu")
		(net "PCIE_B2T_B2_TX_DP<8>")
	)
	(segment
		(start -180.066 18.288)
		(end -184.298793 22.520793)
		(width 0.127)
		(layer "In5.Cu")
		(net "PCIE_B2T_B2_TX_DP<8>")
	)
	(segment
		(start -152.028949 24.121049)
		(end -153.300811 24.121049)
		(width 0.127)
		(layer "In5.Cu")
		(net "PCIE_B2T_B2_TX_DP<8>")
	)
	(segment
		(start -166.813893 18.288)
		(end -180.066 18.288)
		(width 0.127)
		(layer "In5.Cu")
		(net "PCIE_B2T_B2_TX_DP<8>")
	)
	(segment
		(start -184.906051 26.606053)
		(end -185.46 27.160002)
		(width 0.127)
		(layer "In5.Cu")
		(net "PCIE_B2T_B2_TX_DP<8>")
	)
	(segment
		(start -153.57348 23.84838)
		(end -153.57348 23.0559)
		(width 0.127)
		(layer "In5.Cu")
		(net "PCIE_B2T_B2_TX_DP<8>")
	)
	(segment
		(start -158.11532 22.8473)
		(end -158.98908 23.72106)
		(width 0.127)
		(layer "In5.Cu")
		(net "PCIE_B2T_B2_TX_DP<8>")
	)
	(segment
		(start -153.300811 24.121049)
		(end -153.57348 23.84838)
		(width 0.127)
		(layer "In5.Cu")
		(net "PCIE_B2T_B2_TX_DP<8>")
	)
	(segment
		(start -161.380833 23.72106)
		(end -166.813893 18.288)
		(width 0.127)
		(layer "In5.Cu")
		(net "PCIE_B2T_B2_TX_DP<8>")
	)
	(segment
		(start -184.298793 22.520793)
		(end -184.298793 26.235645)
		(width 0.127)
		(layer "In5.Cu")
		(net "PCIE_B2T_B2_TX_DP<8>")
	)
	(segment
		(start -184.669201 26.606053)
		(end -184.906051 26.606053)
		(width 0.127)
		(layer "In5.Cu")
		(net "PCIE_B2T_B2_TX_DP<8>")
	)
	(segment
		(start -153.57348 23.0559)
		(end -153.78208 22.8473)
		(width 0.127)
		(layer "In5.Cu")
		(net "PCIE_B2T_B2_TX_DP<8>")
	)
	(segment
		(start -184.298793 26.235645)
		(end -184.669201 26.606053)
		(width 0.127)
		(layer "In5.Cu")
		(net "PCIE_B2T_B2_TX_DP<8>")
	)
	(segment
		(start -152.174999 43.024999)
		(end -152.809999 42.389999)
		(width 0.127)
		(layer "F.Cu")
		(net "PCIE_B2T_B2_TX_DP<7>")
	)
	(via
		(at -152.809999 42.389999)
		(size 0.5588)
		(drill 0.254)
		(layers "F.Cu" "B.Cu")
		(net "PCIE_B2T_B2_TX_DP<7>")
	)
	(segment
		(start -167.930378 32.112402)
		(end -165.62578 34.417)
		(width 0.127)
		(layer "B.Cu")
		(net "PCIE_B2T_B2_TX_DP<7>")
	)
	(segment
		(start -160.49752 37.675073)
		(end -160.49752 38.932693)
		(width 0.127)
		(layer "B.Cu")
		(net "PCIE_B2T_B2_TX_DP<7>")
	)
	(segment
		(start -170.912401 32.112402)
		(end -167.930378 32.112402)
		(width 0.127)
		(layer "B.Cu")
		(net "PCIE_B2T_B2_TX_DP<7>")
	)
	(segment
		(start -154.8565 41.581532)
		(end -154.530633 41.907399)
		(width 0.127)
		(layer "B.Cu")
		(net "PCIE_B2T_B2_TX_DP<7>")
	)
	(segment
		(start -158.787673 40.64254)
		(end -155.081813 40.64254)
		(width 0.127)
		(layer "B.Cu")
		(net "PCIE_B2T_B2_TX_DP<7>")
	)
	(segment
		(start -171.46 32.660001)
		(end -170.912401 32.112402)
		(width 0.127)
		(layer "B.Cu")
		(net "PCIE_B2T_B2_TX_DP<7>")
	)
	(segment
		(start -163.755593 34.417)
		(end -160.49752 37.675073)
		(width 0.127)
		(layer "B.Cu")
		(net "PCIE_B2T_B2_TX_DP<7>")
	)
	(segment
		(start -165.62578 34.417)
		(end -163.755593 34.417)
		(width 0.127)
		(layer "B.Cu")
		(net "PCIE_B2T_B2_TX_DP<7>")
	)
	(segment
		(start -154.8565 40.867853)
		(end -154.8565 41.581532)
		(width 0.127)
		(layer "B.Cu")
		(net "PCIE_B2T_B2_TX_DP<7>")
	)
	(segment
		(start -154.530633 41.907399)
		(end -153.292599 41.907399)
		(width 0.127)
		(layer "B.Cu")
		(net "PCIE_B2T_B2_TX_DP<7>")
	)
	(segment
		(start -160.49752 38.932693)
		(end -158.787673 40.64254)
		(width 0.127)
		(layer "B.Cu")
		(net "PCIE_B2T_B2_TX_DP<7>")
	)
	(segment
		(start -155.081813 40.64254)
		(end -154.8565 40.867853)
		(width 0.127)
		(layer "B.Cu")
		(net "PCIE_B2T_B2_TX_DP<7>")
	)
	(segment
		(start -153.292599 41.907399)
		(end -152.809999 42.389999)
		(width 0.127)
		(layer "B.Cu")
		(net "PCIE_B2T_B2_TX_DP<7>")
	)
	(segment
		(start -153.444999 40.484999)
		(end -154.079999 39.849999)
		(width 0.127)
		(layer "F.Cu")
		(net "PCIE_B2T_B2_TX_DP<6>")
	)
	(via
		(at -154.079999 39.849999)
		(size 0.5588)
		(drill 0.254)
		(layers "F.Cu" "B.Cu")
		(net "PCIE_B2T_B2_TX_DP<6>")
	)
	(segment
		(start -173.460001 31.360001)
		(end -172.912402 30.812402)
		(width 0.127)
		(layer "B.Cu")
		(net "PCIE_B2T_B2_TX_DP<6>")
	)
	(segment
		(start -158.482873 36.8046)
		(end -157.184933 38.10254)
		(width 0.127)
		(layer "B.Cu")
		(net "PCIE_B2T_B2_TX_DP<6>")
	)
	(segment
		(start -172.595393 30.812402)
		(end -172.2982 30.515209)
		(width 0.127)
		(layer "B.Cu")
		(net "PCIE_B2T_B2_TX_DP<6>")
	)
	(segment
		(start -163.47694 32.74568)
		(end -159.41802 36.8046)
		(width 0.127)
		(layer "B.Cu")
		(net "PCIE_B2T_B2_TX_DP<6>")
	)
	(segment
		(start -171.112769 24.821802)
		(end -170.6218 25.312771)
		(width 0.127)
		(layer "B.Cu")
		(net "PCIE_B2T_B2_TX_DP<6>")
	)
	(segment
		(start -156.1265 38.327853)
		(end -156.1265 39.041532)
		(width 0.127)
		(layer "B.Cu")
		(net "PCIE_B2T_B2_TX_DP<6>")
	)
	(segment
		(start -171.575651 24.821802)
		(end -171.112769 24.821802)
		(width 0.127)
		(layer "B.Cu")
		(net "PCIE_B2T_B2_TX_DP<6>")
	)
	(segment
		(start -155.800633 39.367399)
		(end -154.562599 39.367399)
		(width 0.127)
		(layer "B.Cu")
		(net "PCIE_B2T_B2_TX_DP<6>")
	)
	(segment
		(start -156.1265 39.041532)
		(end -155.800633 39.367399)
		(width 0.127)
		(layer "B.Cu")
		(net "PCIE_B2T_B2_TX_DP<6>")
	)
	(segment
		(start -172.2982 25.251453)
		(end -171.862547 24.8158)
		(width 0.127)
		(layer "B.Cu")
		(net "PCIE_B2T_B2_TX_DP<6>")
	)
	(segment
		(start -170.6218 25.922653)
		(end -163.798773 32.74568)
		(width 0.127)
		(layer "B.Cu")
		(net "PCIE_B2T_B2_TX_DP<6>")
	)
	(segment
		(start -159.41802 36.8046)
		(end -158.482873 36.8046)
		(width 0.127)
		(layer "B.Cu")
		(net "PCIE_B2T_B2_TX_DP<6>")
	)
	(segment
		(start -172.912402 30.812402)
		(end -172.595393 30.812402)
		(width 0.127)
		(layer "B.Cu")
		(net "PCIE_B2T_B2_TX_DP<6>")
	)
	(segment
		(start -172.2982 30.515209)
		(end -172.2982 25.251453)
		(width 0.127)
		(layer "B.Cu")
		(net "PCIE_B2T_B2_TX_DP<6>")
	)
	(segment
		(start -171.581653 24.8158)
		(end -171.575651 24.821802)
		(width 0.127)
		(layer "B.Cu")
		(net "PCIE_B2T_B2_TX_DP<6>")
	)
	(segment
		(start -154.562599 39.367399)
		(end -154.079999 39.849999)
		(width 0.127)
		(layer "B.Cu")
		(net "PCIE_B2T_B2_TX_DP<6>")
	)
	(segment
		(start -157.184933 38.10254)
		(end -156.351813 38.10254)
		(width 0.127)
		(layer "B.Cu")
		(net "PCIE_B2T_B2_TX_DP<6>")
	)
	(segment
		(start -170.6218 25.312771)
		(end -170.6218 25.922653)
		(width 0.127)
		(layer "B.Cu")
		(net "PCIE_B2T_B2_TX_DP<6>")
	)
	(segment
		(start -171.862547 24.8158)
		(end -171.581653 24.8158)
		(width 0.127)
		(layer "B.Cu")
		(net "PCIE_B2T_B2_TX_DP<6>")
	)
	(segment
		(start -163.798773 32.74568)
		(end -163.47694 32.74568)
		(width 0.127)
		(layer "B.Cu")
		(net "PCIE_B2T_B2_TX_DP<6>")
	)
	(segment
		(start -156.351813 38.10254)
		(end -156.1265 38.327853)
		(width 0.127)
		(layer "B.Cu")
		(net "PCIE_B2T_B2_TX_DP<6>")
	)
	(segment
		(start -152.174999 37.944999)
		(end -152.809999 37.309999)
		(width 0.127)
		(layer "F.Cu")
		(net "PCIE_B2T_B2_TX_DP<5>")
	)
	(via
		(at -152.809999 37.309999)
		(size 0.5588)
		(drill 0.254)
		(layers "F.Cu" "B.Cu")
		(net "PCIE_B2T_B2_TX_DP<5>")
	)
	(segment
		(start -174.298201 24.012771)
		(end -173.807232 23.521802)
		(width 0.127)
		(layer "B.Cu")
		(net "PCIE_B2T_B2_TX_DP<5>")
	)
	(segment
		(start -174.3002 24.027567)
		(end -174.298201 24.025568)
		(width 0.127)
		(layer "B.Cu")
		(net "PCIE_B2T_B2_TX_DP<5>")
	)
	(segment
		(start -158.419053 35.56254)
		(end -155.081813 35.56254)
		(width 0.127)
		(layer "B.Cu")
		(net "PCIE_B2T_B2_TX_DP<5>")
	)
	(segment
		(start -175.46 32.660001)
		(end -174.912401 32.112402)
		(width 0.127)
		(layer "B.Cu")
		(net "PCIE_B2T_B2_TX_DP<5>")
	)
	(segment
		(start -174.912401 32.112402)
		(end -174.640065 32.112402)
		(width 0.127)
		(layer "B.Cu")
		(net "PCIE_B2T_B2_TX_DP<5>")
	)
	(segment
		(start -153.292599 36.827399)
		(end -152.809999 37.309999)
		(width 0.127)
		(layer "B.Cu")
		(net "PCIE_B2T_B2_TX_DP<5>")
	)
	(segment
		(start -173.807232 23.521802)
		(end -170.459791 23.521802)
		(width 0.127)
		(layer "B.Cu")
		(net "PCIE_B2T_B2_TX_DP<5>")
	)
	(segment
		(start -154.8565 36.501532)
		(end -154.530633 36.827399)
		(width 0.127)
		(layer "B.Cu")
		(net "PCIE_B2T_B2_TX_DP<5>")
	)
	(segment
		(start -154.530633 36.827399)
		(end -153.292599 36.827399)
		(width 0.127)
		(layer "B.Cu")
		(net "PCIE_B2T_B2_TX_DP<5>")
	)
	(segment
		(start -170.459791 23.521802)
		(end -158.419053 35.56254)
		(width 0.127)
		(layer "B.Cu")
		(net "PCIE_B2T_B2_TX_DP<5>")
	)
	(segment
		(start -154.8565 35.787853)
		(end -154.8565 36.501532)
		(width 0.127)
		(layer "B.Cu")
		(net "PCIE_B2T_B2_TX_DP<5>")
	)
	(segment
		(start -174.640065 32.112402)
		(end -174.3002 31.772537)
		(width 0.127)
		(layer "B.Cu")
		(net "PCIE_B2T_B2_TX_DP<5>")
	)
	(segment
		(start -155.081813 35.56254)
		(end -154.8565 35.787853)
		(width 0.127)
		(layer "B.Cu")
		(net "PCIE_B2T_B2_TX_DP<5>")
	)
	(segment
		(start -174.298201 24.025568)
		(end -174.298201 24.012771)
		(width 0.127)
		(layer "B.Cu")
		(net "PCIE_B2T_B2_TX_DP<5>")
	)
	(segment
		(start -174.3002 31.772537)
		(end -174.3002 24.027567)
		(width 0.127)
		(layer "B.Cu")
		(net "PCIE_B2T_B2_TX_DP<5>")
	)
	(segment
		(start -153.444999 35.404999)
		(end -154.079999 34.769999)
		(width 0.127)
		(layer "F.Cu")
		(net "PCIE_B2T_B2_TX_DP<4>")
	)
	(via
		(at -154.079999 34.769999)
		(size 0.5588)
		(drill 0.254)
		(layers "F.Cu" "B.Cu")
		(net "PCIE_B2T_B2_TX_DP<4>")
	)
	(segment
		(start -169.956053 22.3012)
		(end -159.872253 32.385)
		(width 0.127)
		(layer "B.Cu")
		(net "PCIE_B2T_B2_TX_DP<4>")
	)
	(segment
		(start -156.1265 33.247853)
		(end -156.1265 33.961532)
		(width 0.127)
		(layer "B.Cu")
		(net "PCIE_B2T_B2_TX_DP<4>")
	)
	(segment
		(start -156.351813 33.02254)
		(end -156.1265 33.247853)
		(width 0.127)
		(layer "B.Cu")
		(net "PCIE_B2T_B2_TX_DP<4>")
	)
	(segment
		(start -154.562599 34.287399)
		(end -154.079999 34.769999)
		(width 0.127)
		(layer "B.Cu")
		(net "PCIE_B2T_B2_TX_DP<4>")
	)
	(segment
		(start -156.1265 33.961532)
		(end -155.800633 34.287399)
		(width 0.127)
		(layer "B.Cu")
		(net "PCIE_B2T_B2_TX_DP<4>")
	)
	(segment
		(start -155.800633 34.287399)
		(end -154.562599 34.287399)
		(width 0.127)
		(layer "B.Cu")
		(net "PCIE_B2T_B2_TX_DP<4>")
	)
	(segment
		(start -177.460001 31.360001)
		(end -176.912402 30.812402)
		(width 0.127)
		(layer "B.Cu")
		(net "PCIE_B2T_B2_TX_DP<4>")
	)
	(segment
		(start -174.427947 22.3012)
		(end -169.956053 22.3012)
		(width 0.127)
		(layer "B.Cu")
		(net "PCIE_B2T_B2_TX_DP<4>")
	)
	(segment
		(start -176.3068 24.180053)
		(end -174.427947 22.3012)
		(width 0.127)
		(layer "B.Cu")
		(net "PCIE_B2T_B2_TX_DP<4>")
	)
	(segment
		(start -157.995193 33.02254)
		(end -156.351813 33.02254)
		(width 0.127)
		(layer "B.Cu")
		(net "PCIE_B2T_B2_TX_DP<4>")
	)
	(segment
		(start -159.872253 32.385)
		(end -158.632733 32.385)
		(width 0.127)
		(layer "B.Cu")
		(net "PCIE_B2T_B2_TX_DP<4>")
	)
	(segment
		(start -176.3068 30.443251)
		(end -176.3068 24.180053)
		(width 0.127)
		(layer "B.Cu")
		(net "PCIE_B2T_B2_TX_DP<4>")
	)
	(segment
		(start -176.675951 30.812402)
		(end -176.3068 30.443251)
		(width 0.127)
		(layer "B.Cu")
		(net "PCIE_B2T_B2_TX_DP<4>")
	)
	(segment
		(start -158.632733 32.385)
		(end -157.995193 33.02254)
		(width 0.127)
		(layer "B.Cu")
		(net "PCIE_B2T_B2_TX_DP<4>")
	)
	(segment
		(start -176.912402 30.812402)
		(end -176.675951 30.812402)
		(width 0.127)
		(layer "B.Cu")
		(net "PCIE_B2T_B2_TX_DP<4>")
	)
	(segment
		(start -152.174999 32.864999)
		(end -152.809999 32.229999)
		(width 0.127)
		(layer "F.Cu")
		(net "PCIE_B2T_B2_TX_DP<3>")
	)
	(via
		(at -152.809999 32.229999)
		(size 0.5588)
		(drill 0.254)
		(layers "F.Cu" "B.Cu")
		(net "PCIE_B2T_B2_TX_DP<3>")
	)
	(segment
		(start -154.8565 31.421532)
		(end -154.530633 31.747399)
		(width 0.127)
		(layer "B.Cu")
		(net "PCIE_B2T_B2_TX_DP<3>")
	)
	(segment
		(start -175.494749 21.082)
		(end -169.802904 21.082)
		(width 0.127)
		(layer "B.Cu")
		(net "PCIE_B2T_B2_TX_DP<3>")
	)
	(segment
		(start -159.64186 30.48254)
		(end -155.081813 30.48254)
		(width 0.127)
		(layer "B.Cu")
		(net "PCIE_B2T_B2_TX_DP<3>")
	)
	(segment
		(start -154.8565 30.707853)
		(end -154.8565 31.421532)
		(width 0.127)
		(layer "B.Cu")
		(net "PCIE_B2T_B2_TX_DP<3>")
	)
	(segment
		(start -179.459999 32.660001)
		(end -178.912401 32.112402)
		(width 0.127)
		(layer "B.Cu")
		(net "PCIE_B2T_B2_TX_DP<3>")
	)
	(segment
		(start -178.3134 31.766657)
		(end -178.3134 23.900651)
		(width 0.127)
		(layer "B.Cu")
		(net "PCIE_B2T_B2_TX_DP<3>")
	)
	(segment
		(start -155.081813 30.48254)
		(end -154.8565 30.707853)
		(width 0.127)
		(layer "B.Cu")
		(net "PCIE_B2T_B2_TX_DP<3>")
	)
	(segment
		(start -169.045575 21.081815)
		(end -169.04539 21.082)
		(width 0.127)
		(layer "B.Cu")
		(net "PCIE_B2T_B2_TX_DP<3>")
	)
	(segment
		(start -169.0424 21.082)
		(end -159.64186 30.48254)
		(width 0.127)
		(layer "B.Cu")
		(net "PCIE_B2T_B2_TX_DP<3>")
	)
	(segment
		(start -169.802719 21.081815)
		(end -169.045575 21.081815)
		(width 0.127)
		(layer "B.Cu")
		(net "PCIE_B2T_B2_TX_DP<3>")
	)
	(segment
		(start -178.912401 32.112402)
		(end -178.659145 32.112402)
		(width 0.127)
		(layer "B.Cu")
		(net "PCIE_B2T_B2_TX_DP<3>")
	)
	(segment
		(start -178.3134 23.900651)
		(end -175.494749 21.082)
		(width 0.127)
		(layer "B.Cu")
		(net "PCIE_B2T_B2_TX_DP<3>")
	)
	(segment
		(start -178.659145 32.112402)
		(end -178.3134 31.766657)
		(width 0.127)
		(layer "B.Cu")
		(net "PCIE_B2T_B2_TX_DP<3>")
	)
	(segment
		(start -169.04539 21.082)
		(end -169.0424 21.082)
		(width 0.127)
		(layer "B.Cu")
		(net "PCIE_B2T_B2_TX_DP<3>")
	)
	(segment
		(start -154.530633 31.747399)
		(end -153.292599 31.747399)
		(width 0.127)
		(layer "B.Cu")
		(net "PCIE_B2T_B2_TX_DP<3>")
	)
	(segment
		(start -153.292599 31.747399)
		(end -152.809999 32.229999)
		(width 0.127)
		(layer "B.Cu")
		(net "PCIE_B2T_B2_TX_DP<3>")
	)
	(segment
		(start -169.802904 21.082)
		(end -169.802719 21.081815)
		(width 0.127)
		(layer "B.Cu")
		(net "PCIE_B2T_B2_TX_DP<3>")
	)
	(segment
		(start -153.444999 30.324999)
		(end -154.079999 29.689999)
		(width 0.127)
		(layer "F.Cu")
		(net "PCIE_B2T_B2_TX_DP<2>")
	)
	(via
		(at -154.079999 29.689999)
		(size 0.5588)
		(drill 0.254)
		(layers "F.Cu" "B.Cu")
		(net "PCIE_B2T_B2_TX_DP<2>")
	)
	(segment
		(start -180.912402 30.812402)
		(end -180.659146 30.812402)
		(width 0.127)
		(layer "B.Cu")
		(net "PCIE_B2T_B2_TX_DP<2>")
	)
	(segment
		(start -154.562599 29.207399)
		(end -154.079999 29.689999)
		(width 0.127)
		(layer "B.Cu")
		(net "PCIE_B2T_B2_TX_DP<2>")
	)
	(segment
		(start -180.659146 30.812402)
		(end -180.298199 30.451455)
		(width 0.127)
		(layer "B.Cu")
		(net "PCIE_B2T_B2_TX_DP<2>")
	)
	(segment
		(start -156.1265 28.881532)
		(end -155.800633 29.207399)
		(width 0.127)
		(layer "B.Cu")
		(net "PCIE_B2T_B2_TX_DP<2>")
	)
	(segment
		(start -158.112033 27.29992)
		(end -157.469413 27.94254)
		(width 0.127)
		(layer "B.Cu")
		(net "PCIE_B2T_B2_TX_DP<2>")
	)
	(segment
		(start -180.298199 25.312685)
		(end -180.2946 25.309086)
		(width 0.127)
		(layer "B.Cu")
		(net "PCIE_B2T_B2_TX_DP<2>")
	)
	(segment
		(start -160.69088 27.29992)
		(end -158.112033 27.29992)
		(width 0.127)
		(layer "B.Cu")
		(net "PCIE_B2T_B2_TX_DP<2>")
	)
	(segment
		(start -156.1265 28.167853)
		(end -156.1265 28.881532)
		(width 0.127)
		(layer "B.Cu")
		(net "PCIE_B2T_B2_TX_DP<2>")
	)
	(segment
		(start -157.469413 27.94254)
		(end -156.351813 27.94254)
		(width 0.127)
		(layer "B.Cu")
		(net "PCIE_B2T_B2_TX_DP<2>")
	)
	(segment
		(start -156.351813 27.94254)
		(end -156.1265 28.167853)
		(width 0.127)
		(layer "B.Cu")
		(net "PCIE_B2T_B2_TX_DP<2>")
	)
	(segment
		(start -180.298199 30.451455)
		(end -180.298199 25.312685)
		(width 0.127)
		(layer "B.Cu")
		(net "PCIE_B2T_B2_TX_DP<2>")
	)
	(segment
		(start -176.104347 19.812)
		(end -168.1788 19.812)
		(width 0.127)
		(layer "B.Cu")
		(net "PCIE_B2T_B2_TX_DP<2>")
	)
	(segment
		(start -180.2946 25.309086)
		(end -180.2946 24.002253)
		(width 0.127)
		(layer "B.Cu")
		(net "PCIE_B2T_B2_TX_DP<2>")
	)
	(segment
		(start -155.800633 29.207399)
		(end -154.562599 29.207399)
		(width 0.127)
		(layer "B.Cu")
		(net "PCIE_B2T_B2_TX_DP<2>")
	)
	(segment
		(start -168.1788 19.812)
		(end -160.69088 27.29992)
		(width 0.127)
		(layer "B.Cu")
		(net "PCIE_B2T_B2_TX_DP<2>")
	)
	(segment
		(start -181.46 31.360001)
		(end -180.912402 30.812402)
		(width 0.127)
		(layer "B.Cu")
		(net "PCIE_B2T_B2_TX_DP<2>")
	)
	(segment
		(start -180.2946 24.002253)
		(end -176.104347 19.812)
		(width 0.127)
		(layer "B.Cu")
		(net "PCIE_B2T_B2_TX_DP<2>")
	)
	(segment
		(start -152.174999 27.784999)
		(end -152.809999 27.149999)
		(width 0.127)
		(layer "F.Cu")
		(net "PCIE_B2T_B2_TX_DP<1>")
	)
	(via
		(at -152.809999 27.149999)
		(size 0.5588)
		(drill 0.254)
		(layers "F.Cu" "B.Cu")
		(net "PCIE_B2T_B2_TX_DP<1>")
	)
	(segment
		(start -160.73406 25.40254)
		(end -167.5692 18.5674)
		(width 0.127)
		(layer "B.Cu")
		(net "PCIE_B2T_B2_TX_DP<1>")
	)
	(segment
		(start -182.3012 23.799053)
		(end -182.3012 31.838095)
		(width 0.127)
		(layer "B.Cu")
		(net "PCIE_B2T_B2_TX_DP<1>")
	)
	(segment
		(start -154.8565 25.627853)
		(end -155.081813 25.40254)
		(width 0.127)
		(layer "B.Cu")
		(net "PCIE_B2T_B2_TX_DP<1>")
	)
	(segment
		(start -182.3012 31.838095)
		(end -182.575507 32.112402)
		(width 0.127)
		(layer "B.Cu")
		(net "PCIE_B2T_B2_TX_DP<1>")
	)
	(segment
		(start -154.8565 26.341532)
		(end -154.8565 25.627853)
		(width 0.127)
		(layer "B.Cu")
		(net "PCIE_B2T_B2_TX_DP<1>")
	)
	(segment
		(start -153.292599 26.667399)
		(end -154.530633 26.667399)
		(width 0.127)
		(layer "B.Cu")
		(net "PCIE_B2T_B2_TX_DP<1>")
	)
	(segment
		(start -182.9124 32.112402)
		(end -183.459999 32.660001)
		(width 0.127)
		(layer "B.Cu")
		(net "PCIE_B2T_B2_TX_DP<1>")
	)
	(segment
		(start -167.5692 18.5674)
		(end -177.069547 18.5674)
		(width 0.127)
		(layer "B.Cu")
		(net "PCIE_B2T_B2_TX_DP<1>")
	)
	(segment
		(start -154.530633 26.667399)
		(end -154.8565 26.341532)
		(width 0.127)
		(layer "B.Cu")
		(net "PCIE_B2T_B2_TX_DP<1>")
	)
	(segment
		(start -152.809999 27.149999)
		(end -153.292599 26.667399)
		(width 0.127)
		(layer "B.Cu")
		(net "PCIE_B2T_B2_TX_DP<1>")
	)
	(segment
		(start -155.081813 25.40254)
		(end -160.73406 25.40254)
		(width 0.127)
		(layer "B.Cu")
		(net "PCIE_B2T_B2_TX_DP<1>")
	)
	(segment
		(start -182.575507 32.112402)
		(end -182.9124 32.112402)
		(width 0.127)
		(layer "B.Cu")
		(net "PCIE_B2T_B2_TX_DP<1>")
	)
	(segment
		(start -177.069547 18.5674)
		(end -182.3012 23.799053)
		(width 0.127)
		(layer "B.Cu")
		(net "PCIE_B2T_B2_TX_DP<1>")
	)
	(segment
		(start -149.634999 43.024999)
		(end -150.269999 42.389999)
		(width 0.127)
		(layer "F.Cu")
		(net "PCIE_B2T_B2_TX_DP<15>")
	)
	(via
		(at -150.269999 42.389999)
		(size 0.5588)
		(drill 0.254)
		(layers "F.Cu" "B.Cu")
		(net "PCIE_B2T_B2_TX_DP<15>")
	)
	(segment
		(start -150.758949 41.901049)
		(end -151.823336 41.901049)
		(width 0.127)
		(layer "In5.Cu")
		(net "PCIE_B2T_B2_TX_DP<15>")
	)
	(segment
		(start -167.26948 44.03852)
		(end -170.0838 41.2242)
		(width 0.127)
		(layer "In5.Cu")
		(net "PCIE_B2T_B2_TX_DP<15>")
	)
	(segment
		(start -152.39746 43.2816)
		(end -158.24454 43.2816)
		(width 0.127)
		(layer "In5.Cu")
		(net "PCIE_B2T_B2_TX_DP<15>")
	)
	(segment
		(start -150.269999 42.389999)
		(end -150.758949 41.901049)
		(width 0.127)
		(layer "In5.Cu")
		(net "PCIE_B2T_B2_TX_DP<15>")
	)
	(segment
		(start -152.01392 42.89806)
		(end -152.39746 43.2816)
		(width 0.127)
		(layer "In5.Cu")
		(net "PCIE_B2T_B2_TX_DP<15>")
	)
	(segment
		(start -170.0838 33.610893)
		(end -170.441033 33.25366)
		(width 0.127)
		(layer "In5.Cu")
		(net "PCIE_B2T_B2_TX_DP<15>")
	)
	(segment
		(start -170.0838 41.2242)
		(end -170.0838 33.610893)
		(width 0.127)
		(layer "In5.Cu")
		(net "PCIE_B2T_B2_TX_DP<15>")
	)
	(segment
		(start -159.00146 44.03852)
		(end -167.26948 44.03852)
		(width 0.127)
		(layer "In5.Cu")
		(net "PCIE_B2T_B2_TX_DP<15>")
	)
	(segment
		(start -152.01392 42.091633)
		(end -152.01392 42.89806)
		(width 0.127)
		(layer "In5.Cu")
		(net "PCIE_B2T_B2_TX_DP<15>")
	)
	(segment
		(start -158.24454 43.2816)
		(end -159.00146 44.03852)
		(width 0.127)
		(layer "In5.Cu")
		(net "PCIE_B2T_B2_TX_DP<15>")
	)
	(segment
		(start -170.441033 33.25366)
		(end -170.441033 28.244071)
		(width 0.127)
		(layer "In5.Cu")
		(net "PCIE_B2T_B2_TX_DP<15>")
	)
	(segment
		(start -170.779051 27.906053)
		(end -170.906051 27.906053)
		(width 0.127)
		(layer "In5.Cu")
		(net "PCIE_B2T_B2_TX_DP<15>")
	)
	(segment
		(start -151.823336 41.901049)
		(end -152.01392 42.091633)
		(width 0.127)
		(layer "In5.Cu")
		(net "PCIE_B2T_B2_TX_DP<15>")
	)
	(segment
		(start -170.906051 27.906053)
		(end -171.46 28.460002)
		(width 0.127)
		(layer "In5.Cu")
		(net "PCIE_B2T_B2_TX_DP<15>")
	)
	(segment
		(start -170.441033 28.244071)
		(end -170.779051 27.906053)
		(width 0.127)
		(layer "In5.Cu")
		(net "PCIE_B2T_B2_TX_DP<15>")
	)
	(segment
		(start -150.904999 40.484999)
		(end -151.539999 39.849999)
		(width 0.127)
		(layer "F.Cu")
		(net "PCIE_B2T_B2_TX_DP<14>")
	)
	(via
		(at -151.539999 39.849999)
		(size 0.5588)
		(drill 0.254)
		(layers "F.Cu" "B.Cu")
		(net "PCIE_B2T_B2_TX_DP<14>")
	)
	(segment
		(start -153.57348 38.2959)
		(end -153.77954 38.08984)
		(width 0.127)
		(layer "In5.Cu")
		(net "PCIE_B2T_B2_TX_DP<14>")
	)
	(segment
		(start -171.055693 24.7904)
		(end -172.020448 24.7904)
		(width 0.127)
		(layer "In5.Cu")
		(net "PCIE_B2T_B2_TX_DP<14>")
	)
	(segment
		(start -153.300811 39.361049)
		(end -153.57348 39.08838)
		(width 0.127)
		(layer "In5.Cu")
		(net "PCIE_B2T_B2_TX_DP<14>")
	)
	(segment
		(start -168.9916 30.639093)
		(end -168.9916 26.854493)
		(width 0.127)
		(layer "In5.Cu")
		(net "PCIE_B2T_B2_TX_DP<14>")
	)
	(segment
		(start -151.539999 39.849999)
		(end -152.028949 39.361049)
		(width 0.127)
		(layer "In5.Cu")
		(net "PCIE_B2T_B2_TX_DP<14>")
	)
	(segment
		(start -172.020448 24.7904)
		(end -172.35995 25.129901)
		(width 0.127)
		(layer "In5.Cu")
		(net "PCIE_B2T_B2_TX_DP<14>")
	)
	(segment
		(start -172.658057 26.606053)
		(end -172.906052 26.606053)
		(width 0.127)
		(layer "In5.Cu")
		(net "PCIE_B2T_B2_TX_DP<14>")
	)
	(segment
		(start -168.9916 26.854493)
		(end -171.055693 24.7904)
		(width 0.127)
		(layer "In5.Cu")
		(net "PCIE_B2T_B2_TX_DP<14>")
	)
	(segment
		(start -162.168233 37.46246)
		(end -168.9916 30.639093)
		(width 0.127)
		(layer "In5.Cu")
		(net "PCIE_B2T_B2_TX_DP<14>")
	)
	(segment
		(start -157.885793 38.08984)
		(end -158.513173 37.46246)
		(width 0.127)
		(layer "In5.Cu")
		(net "PCIE_B2T_B2_TX_DP<14>")
	)
	(segment
		(start -153.77954 38.08984)
		(end -157.885793 38.08984)
		(width 0.127)
		(layer "In5.Cu")
		(net "PCIE_B2T_B2_TX_DP<14>")
	)
	(segment
		(start -172.906052 26.606053)
		(end -173.460001 27.160002)
		(width 0.127)
		(layer "In5.Cu")
		(net "PCIE_B2T_B2_TX_DP<14>")
	)
	(segment
		(start -152.028949 39.361049)
		(end -153.300811 39.361049)
		(width 0.127)
		(layer "In5.Cu")
		(net "PCIE_B2T_B2_TX_DP<14>")
	)
	(segment
		(start -172.35995 25.129901)
		(end -172.35995 26.307946)
		(width 0.127)
		(layer "In5.Cu")
		(net "PCIE_B2T_B2_TX_DP<14>")
	)
	(segment
		(start -158.513173 37.46246)
		(end -162.168233 37.46246)
		(width 0.127)
		(layer "In5.Cu")
		(net "PCIE_B2T_B2_TX_DP<14>")
	)
	(segment
		(start -153.57348 39.08838)
		(end -153.57348 38.2959)
		(width 0.127)
		(layer "In5.Cu")
		(net "PCIE_B2T_B2_TX_DP<14>")
	)
	(segment
		(start -172.35995 26.307946)
		(end -172.658057 26.606053)
		(width 0.127)
		(layer "In5.Cu")
		(net "PCIE_B2T_B2_TX_DP<14>")
	)
	(segment
		(start -149.634999 37.944999)
		(end -150.269999 37.309999)
		(width 0.127)
		(layer "F.Cu")
		(net "PCIE_B2T_B2_TX_DP<13>")
	)
	(via
		(at -150.269999 37.309999)
		(size 0.5588)
		(drill 0.254)
		(layers "F.Cu" "B.Cu")
		(net "PCIE_B2T_B2_TX_DP<13>")
	)
	(segment
		(start -174.3002 27.654946)
		(end -174.551307 27.906053)
		(width 0.127)
		(layer "In5.Cu")
		(net "PCIE_B2T_B2_TX_DP<13>")
	)
	(segment
		(start -173.810907 23.5204)
		(end -174.3002 24.009693)
		(width 0.127)
		(layer "In5.Cu")
		(net "PCIE_B2T_B2_TX_DP<13>")
	)
	(segment
		(start -152.030811 36.821049)
		(end -152.30602 36.54584)
		(width 0.127)
		(layer "In5.Cu")
		(net "PCIE_B2T_B2_TX_DP<13>")
	)
	(segment
		(start -174.551307 27.906053)
		(end -174.906051 27.906053)
		(width 0.127)
		(layer "In5.Cu")
		(net "PCIE_B2T_B2_TX_DP<13>")
	)
	(segment
		(start -150.269999 37.309999)
		(end -150.758949 36.821049)
		(width 0.127)
		(layer "In5.Cu")
		(net "PCIE_B2T_B2_TX_DP<13>")
	)
	(segment
		(start -174.906051 27.906053)
		(end -175.46 28.460002)
		(width 0.127)
		(layer "In5.Cu")
		(net "PCIE_B2T_B2_TX_DP<13>")
	)
	(segment
		(start -167.6835 29.381793)
		(end -167.6835 26.587793)
		(width 0.127)
		(layer "In5.Cu")
		(net "PCIE_B2T_B2_TX_DP<13>")
	)
	(segment
		(start -162.074253 34.99104)
		(end -167.6835 29.381793)
		(width 0.127)
		(layer "In5.Cu")
		(net "PCIE_B2T_B2_TX_DP<13>")
	)
	(segment
		(start -150.758949 36.821049)
		(end -152.030811 36.821049)
		(width 0.127)
		(layer "In5.Cu")
		(net "PCIE_B2T_B2_TX_DP<13>")
	)
	(segment
		(start -174.3002 24.009693)
		(end -174.3002 27.654946)
		(width 0.127)
		(layer "In5.Cu")
		(net "PCIE_B2T_B2_TX_DP<13>")
	)
	(segment
		(start -152.30602 36.54584)
		(end -152.30602 35.75336)
		(width 0.127)
		(layer "In5.Cu")
		(net "PCIE_B2T_B2_TX_DP<13>")
	)
	(segment
		(start -167.6835 26.587793)
		(end -170.750893 23.5204)
		(width 0.127)
		(layer "In5.Cu")
		(net "PCIE_B2T_B2_TX_DP<13>")
	)
	(segment
		(start -158.479833 35.5473)
		(end -159.036093 34.99104)
		(width 0.127)
		(layer "In5.Cu")
		(net "PCIE_B2T_B2_TX_DP<13>")
	)
	(segment
		(start -152.30602 35.75336)
		(end -152.51208 35.5473)
		(width 0.127)
		(layer "In5.Cu")
		(net "PCIE_B2T_B2_TX_DP<13>")
	)
	(segment
		(start -152.51208 35.5473)
		(end -158.479833 35.5473)
		(width 0.127)
		(layer "In5.Cu")
		(net "PCIE_B2T_B2_TX_DP<13>")
	)
	(segment
		(start -159.036093 34.99104)
		(end -162.074253 34.99104)
		(width 0.127)
		(layer "In5.Cu")
		(net "PCIE_B2T_B2_TX_DP<13>")
	)
	(segment
		(start -170.750893 23.5204)
		(end -173.810907 23.5204)
		(width 0.127)
		(layer "In5.Cu")
		(net "PCIE_B2T_B2_TX_DP<13>")
	)
	(segment
		(start -150.904999 35.404999)
		(end -151.539999 34.769999)
		(width 0.127)
		(layer "F.Cu")
		(net "PCIE_B2T_B2_TX_DP<12>")
	)
	(via
		(at -151.539999 34.769999)
		(size 0.5588)
		(drill 0.254)
		(layers "F.Cu" "B.Cu")
		(net "PCIE_B2T_B2_TX_DP<12>")
	)
	(segment
		(start -153.300811 34.281049)
		(end -153.57348 34.00838)
		(width 0.127)
		(layer "In5.Cu")
		(net "PCIE_B2T_B2_TX_DP<12>")
	)
	(segment
		(start -151.539999 34.769999)
		(end -152.028949 34.281049)
		(width 0.127)
		(layer "In5.Cu")
		(net "PCIE_B2T_B2_TX_DP<12>")
	)
	(segment
		(start -166.5151 27.0637)
		(end -166.5151 26.181393)
		(width 0.127)
		(layer "In5.Cu")
		(net "PCIE_B2T_B2_TX_DP<12>")
	)
	(segment
		(start -176.635451 26.606053)
		(end -176.906052 26.606053)
		(width 0.127)
		(layer "In5.Cu")
		(net "PCIE_B2T_B2_TX_DP<12>")
	)
	(segment
		(start -153.77954 33.00984)
		(end -157.779113 33.00984)
		(width 0.127)
		(layer "In5.Cu")
		(net "PCIE_B2T_B2_TX_DP<12>")
	)
	(segment
		(start -153.57348 33.2159)
		(end -153.77954 33.00984)
		(width 0.127)
		(layer "In5.Cu")
		(net "PCIE_B2T_B2_TX_DP<12>")
	)
	(segment
		(start -176.3068 26.277402)
		(end -176.635451 26.606053)
		(width 0.127)
		(layer "In5.Cu")
		(net "PCIE_B2T_B2_TX_DP<12>")
	)
	(segment
		(start -158.386173 32.40278)
		(end -161.17602 32.40278)
		(width 0.127)
		(layer "In5.Cu")
		(net "PCIE_B2T_B2_TX_DP<12>")
	)
	(segment
		(start -176.3068 23.7744)
		(end -176.3068 26.277402)
		(width 0.127)
		(layer "In5.Cu")
		(net "PCIE_B2T_B2_TX_DP<12>")
	)
	(segment
		(start -175.0114 22.479)
		(end -176.3068 23.7744)
		(width 0.127)
		(layer "In5.Cu")
		(net "PCIE_B2T_B2_TX_DP<12>")
	)
	(segment
		(start -176.906052 26.606053)
		(end -177.460001 27.160002)
		(width 0.127)
		(layer "In5.Cu")
		(net "PCIE_B2T_B2_TX_DP<12>")
	)
	(segment
		(start -157.779113 33.00984)
		(end -158.386173 32.40278)
		(width 0.127)
		(layer "In5.Cu")
		(net "PCIE_B2T_B2_TX_DP<12>")
	)
	(segment
		(start -161.17602 32.40278)
		(end -166.5151 27.0637)
		(width 0.127)
		(layer "In5.Cu")
		(net "PCIE_B2T_B2_TX_DP<12>")
	)
	(segment
		(start -166.5151 26.181393)
		(end -170.217493 22.479)
		(width 0.127)
		(layer "In5.Cu")
		(net "PCIE_B2T_B2_TX_DP<12>")
	)
	(segment
		(start -152.028949 34.281049)
		(end -153.300811 34.281049)
		(width 0.127)
		(layer "In5.Cu")
		(net "PCIE_B2T_B2_TX_DP<12>")
	)
	(segment
		(start -153.57348 34.00838)
		(end -153.57348 33.2159)
		(width 0.127)
		(layer "In5.Cu")
		(net "PCIE_B2T_B2_TX_DP<12>")
	)
	(segment
		(start -170.217493 22.479)
		(end -175.0114 22.479)
		(width 0.127)
		(layer "In5.Cu")
		(net "PCIE_B2T_B2_TX_DP<12>")
	)
	(segment
		(start -149.634999 32.864999)
		(end -150.269999 32.229999)
		(width 0.127)
		(layer "F.Cu")
		(net "PCIE_B2T_B2_TX_DP<11>")
	)
	(via
		(at -150.269999 32.229999)
		(size 0.5588)
		(drill 0.254)
		(layers "F.Cu" "B.Cu")
		(net "PCIE_B2T_B2_TX_DP<11>")
	)
	(segment
		(start -152.30602 30.67336)
		(end -152.50446 30.47492)
		(width 0.127)
		(layer "In5.Cu")
		(net "PCIE_B2T_B2_TX_DP<11>")
	)
	(segment
		(start -175.919107 21.4122)
		(end -178.3134 23.806493)
		(width 0.127)
		(layer "In5.Cu")
		(net "PCIE_B2T_B2_TX_DP<11>")
	)
	(segment
		(start -150.758949 31.741049)
		(end -152.030811 31.741049)
		(width 0.127)
		(layer "In5.Cu")
		(net "PCIE_B2T_B2_TX_DP<11>")
	)
	(segment
		(start -150.269999 32.229999)
		(end -150.758949 31.741049)
		(width 0.127)
		(layer "In5.Cu")
		(net "PCIE_B2T_B2_TX_DP<11>")
	)
	(segment
		(start -178.906051 27.906053)
		(end -179.459999 28.460002)
		(width 0.127)
		(layer "In5.Cu")
		(net "PCIE_B2T_B2_TX_DP<11>")
	)
	(segment
		(start -178.3134 23.806493)
		(end -178.3134 27.622513)
		(width 0.127)
		(layer "In5.Cu")
		(net "PCIE_B2T_B2_TX_DP<11>")
	)
	(segment
		(start -178.59694 27.906053)
		(end -178.906051 27.906053)
		(width 0.127)
		(layer "In5.Cu")
		(net "PCIE_B2T_B2_TX_DP<11>")
	)
	(segment
		(start -178.3134 27.622513)
		(end -178.59694 27.906053)
		(width 0.127)
		(layer "In5.Cu")
		(net "PCIE_B2T_B2_TX_DP<11>")
	)
	(segment
		(start -152.50446 30.47492)
		(end -160.697573 30.47492)
		(width 0.127)
		(layer "In5.Cu")
		(net "PCIE_B2T_B2_TX_DP<11>")
	)
	(segment
		(start -152.30602 31.46584)
		(end -152.30602 30.67336)
		(width 0.127)
		(layer "In5.Cu")
		(net "PCIE_B2T_B2_TX_DP<11>")
	)
	(segment
		(start -169.760293 21.4122)
		(end -175.919107 21.4122)
		(width 0.127)
		(layer "In5.Cu")
		(net "PCIE_B2T_B2_TX_DP<11>")
	)
	(segment
		(start -152.030811 31.741049)
		(end -152.30602 31.46584)
		(width 0.127)
		(layer "In5.Cu")
		(net "PCIE_B2T_B2_TX_DP<11>")
	)
	(segment
		(start -160.697573 30.47492)
		(end -169.760293 21.4122)
		(width 0.127)
		(layer "In5.Cu")
		(net "PCIE_B2T_B2_TX_DP<11>")
	)
	(segment
		(start -150.904999 30.324999)
		(end -151.539999 29.689999)
		(width 0.127)
		(layer "F.Cu")
		(net "PCIE_B2T_B2_TX_DP<10>")
	)
	(via
		(at -151.539999 29.689999)
		(size 0.5588)
		(drill 0.254)
		(layers "F.Cu" "B.Cu")
		(net "PCIE_B2T_B2_TX_DP<10>")
	)
	(segment
		(start -160.77724 27.28976)
		(end -164.489793 23.577207)
		(width 0.127)
		(layer "In5.Cu")
		(net "PCIE_B2T_B2_TX_DP<10>")
	)
	(segment
		(start -180.54687 26.606053)
		(end -180.906052 26.606053)
		(width 0.127)
		(layer "In5.Cu")
		(net "PCIE_B2T_B2_TX_DP<10>")
	)
	(segment
		(start -153.57602 28.13336)
		(end -153.77954 27.92984)
		(width 0.127)
		(layer "In5.Cu")
		(net "PCIE_B2T_B2_TX_DP<10>")
	)
	(segment
		(start -166.071286 23.577207)
		(end -169.277693 20.3708)
		(width 0.127)
		(layer "In5.Cu")
		(net "PCIE_B2T_B2_TX_DP<10>")
	)
	(segment
		(start -180.32 23.749)
		(end -180.32 26.379183)
		(width 0.127)
		(layer "In5.Cu")
		(net "PCIE_B2T_B2_TX_DP<10>")
	)
	(segment
		(start -152.028949 29.201049)
		(end -153.300811 29.201049)
		(width 0.127)
		(layer "In5.Cu")
		(net "PCIE_B2T_B2_TX_DP<10>")
	)
	(segment
		(start -169.277693 20.3708)
		(end -176.9418 20.3708)
		(width 0.127)
		(layer "In5.Cu")
		(net "PCIE_B2T_B2_TX_DP<10>")
	)
	(segment
		(start -153.300811 29.201049)
		(end -153.57602 28.92584)
		(width 0.127)
		(layer "In5.Cu")
		(net "PCIE_B2T_B2_TX_DP<10>")
	)
	(segment
		(start -158.124553 27.92984)
		(end -158.764633 27.28976)
		(width 0.127)
		(layer "In5.Cu")
		(net "PCIE_B2T_B2_TX_DP<10>")
	)
	(segment
		(start -153.57602 28.92584)
		(end -153.57602 28.13336)
		(width 0.127)
		(layer "In5.Cu")
		(net "PCIE_B2T_B2_TX_DP<10>")
	)
	(segment
		(start -180.32 26.379183)
		(end -180.54687 26.606053)
		(width 0.127)
		(layer "In5.Cu")
		(net "PCIE_B2T_B2_TX_DP<10>")
	)
	(segment
		(start -180.906052 26.606053)
		(end -181.46 27.160002)
		(width 0.127)
		(layer "In5.Cu")
		(net "PCIE_B2T_B2_TX_DP<10>")
	)
	(segment
		(start -158.764633 27.28976)
		(end -160.77724 27.28976)
		(width 0.127)
		(layer "In5.Cu")
		(net "PCIE_B2T_B2_TX_DP<10>")
	)
	(segment
		(start -176.9418 20.3708)
		(end -180.32 23.749)
		(width 0.127)
		(layer "In5.Cu")
		(net "PCIE_B2T_B2_TX_DP<10>")
	)
	(segment
		(start -153.77954 27.92984)
		(end -158.124553 27.92984)
		(width 0.127)
		(layer "In5.Cu")
		(net "PCIE_B2T_B2_TX_DP<10>")
	)
	(segment
		(start -164.489793 23.577207)
		(end -166.071286 23.577207)
		(width 0.127)
		(layer "In5.Cu")
		(net "PCIE_B2T_B2_TX_DP<10>")
	)
	(segment
		(start -151.539999 29.689999)
		(end -152.028949 29.201049)
		(width 0.127)
		(layer "In5.Cu")
		(net "PCIE_B2T_B2_TX_DP<10>")
	)
	(segment
		(start -153.444999 25.244999)
		(end -154.079999 24.609999)
		(width 0.127)
		(layer "F.Cu")
		(net "PCIE_B2T_B2_TX_DP<0>")
	)
	(via
		(at -154.079999 24.609999)
		(size 0.5588)
		(drill 0.254)
		(layers "F.Cu" "B.Cu")
		(net "PCIE_B2T_B2_TX_DP<0>")
	)
	(segment
		(start -184.912401 30.812402)
		(end -185.46 31.360001)
		(width 0.127)
		(layer "B.Cu")
		(net "PCIE_B2T_B2_TX_DP<0>")
	)
	(segment
		(start -155.800633 24.127399)
		(end -156.1265 23.801532)
		(width 0.127)
		(layer "B.Cu")
		(net "PCIE_B2T_B2_TX_DP<0>")
	)
	(segment
		(start -159.066027 23.72106)
		(end -160.35814 23.72106)
		(width 0.127)
		(layer "B.Cu")
		(net "PCIE_B2T_B2_TX_DP<0>")
	)
	(segment
		(start -184.659146 30.812402)
		(end -184.912401 30.812402)
		(width 0.127)
		(layer "B.Cu")
		(net "PCIE_B2T_B2_TX_DP<0>")
	)
	(segment
		(start -184.3078 30.461057)
		(end -184.659146 30.812402)
		(width 0.127)
		(layer "B.Cu")
		(net "PCIE_B2T_B2_TX_DP<0>")
	)
	(segment
		(start -166.731 17.3482)
		(end -177.755347 17.3482)
		(width 0.127)
		(layer "B.Cu")
		(net "PCIE_B2T_B2_TX_DP<0>")
	)
	(segment
		(start -177.755347 17.3482)
		(end -184.3078 23.900653)
		(width 0.127)
		(layer "B.Cu")
		(net "PCIE_B2T_B2_TX_DP<0>")
	)
	(segment
		(start -160.35814 23.72106)
		(end -166.731 17.3482)
		(width 0.127)
		(layer "B.Cu")
		(net "PCIE_B2T_B2_TX_DP<0>")
	)
	(segment
		(start -184.3078 23.900653)
		(end -184.3078 30.461057)
		(width 0.127)
		(layer "B.Cu")
		(net "PCIE_B2T_B2_TX_DP<0>")
	)
	(segment
		(start -158.207507 22.86254)
		(end -159.066027 23.72106)
		(width 0.127)
		(layer "B.Cu")
		(net "PCIE_B2T_B2_TX_DP<0>")
	)
	(segment
		(start -156.351813 22.86254)
		(end -158.207507 22.86254)
		(width 0.127)
		(layer "B.Cu")
		(net "PCIE_B2T_B2_TX_DP<0>")
	)
	(segment
		(start -156.1265 23.087853)
		(end -156.351813 22.86254)
		(width 0.127)
		(layer "B.Cu")
		(net "PCIE_B2T_B2_TX_DP<0>")
	)
	(segment
		(start -154.079999 24.609999)
		(end -154.562599 24.127399)
		(width 0.127)
		(layer "B.Cu")
		(net "PCIE_B2T_B2_TX_DP<0>")
	)
	(segment
		(start -154.562599 24.127399)
		(end -155.800633 24.127399)
		(width 0.127)
		(layer "B.Cu")
		(net "PCIE_B2T_B2_TX_DP<0>")
	)
	(segment
		(start -156.1265 23.801532)
		(end -156.1265 23.087853)
		(width 0.127)
		(layer "B.Cu")
		(net "PCIE_B2T_B2_TX_DP<0>")
	)
	(segment
		(start -149.634999 26.514999)
		(end -150.269999 25.879999)
		(width 0.127)
		(layer "F.Cu")
		(net "PCIE_B2T_B2_TX_DN<9>")
	)
	(via
		(at -150.269999 25.879999)
		(size 0.5588)
		(drill 0.254)
		(layers "F.Cu" "B.Cu")
		(net "PCIE_B2T_B2_TX_DN<9>")
	)
	(segment
		(start -182.6187 27.536191)
		(end -182.6187 23.018407)
		(width 0.127)
		(layer "In5.Cu")
		(net "PCIE_B2T_B2_TX_DN<9>")
	)
	(segment
		(start -178.637593 19.0373)
		(end -167.1247 19.0373)
		(width 0.127)
		(layer "In5.Cu")
		(net "PCIE_B2T_B2_TX_DN<9>")
	)
	(segment
		(start -183.459999 27.060002)
		(end -182.906048 27.613953)
		(width 0.127)
		(layer "In5.Cu")
		(net "PCIE_B2T_B2_TX_DN<9>")
	)
	(segment
		(start -182.906048 27.613953)
		(end -182.696462 27.613953)
		(width 0.127)
		(layer "In5.Cu")
		(net "PCIE_B2T_B2_TX_DN<9>")
	)
	(segment
		(start -151.909818 26.368949)
		(end -150.758949 26.368949)
		(width 0.127)
		(layer "In5.Cu")
		(net "PCIE_B2T_B2_TX_DN<9>")
	)
	(segment
		(start -182.696462 27.613953)
		(end -182.6187 27.536191)
		(width 0.127)
		(layer "In5.Cu")
		(net "PCIE_B2T_B2_TX_DN<9>")
	)
	(segment
		(start -167.1247 19.0373)
		(end -161.06426 25.09774)
		(width 0.127)
		(layer "In5.Cu")
		(net "PCIE_B2T_B2_TX_DN<9>")
	)
	(segment
		(start -152.01646 25.469827)
		(end -152.01646 26.262307)
		(width 0.127)
		(layer "In5.Cu")
		(net "PCIE_B2T_B2_TX_DN<9>")
	)
	(segment
		(start -161.06426 25.09774)
		(end -152.388547 25.09774)
		(width 0.127)
		(layer "In5.Cu")
		(net "PCIE_B2T_B2_TX_DN<9>")
	)
	(segment
		(start -152.01646 26.262307)
		(end -151.909818 26.368949)
		(width 0.127)
		(layer "In5.Cu")
		(net "PCIE_B2T_B2_TX_DN<9>")
	)
	(segment
		(start -150.758949 26.368949)
		(end -150.269999 25.879999)
		(width 0.127)
		(layer "In5.Cu")
		(net "PCIE_B2T_B2_TX_DN<9>")
	)
	(segment
		(start -152.388547 25.09774)
		(end -152.01646 25.469827)
		(width 0.127)
		(layer "In5.Cu")
		(net "PCIE_B2T_B2_TX_DN<9>")
	)
	(segment
		(start -182.6187 23.018407)
		(end -178.637593 19.0373)
		(width 0.127)
		(layer "In5.Cu")
		(net "PCIE_B2T_B2_TX_DN<9>")
	)
	(segment
		(start -150.904999 23.974999)
		(end -151.539999 23.339999)
		(width 0.127)
		(layer "F.Cu")
		(net "PCIE_B2T_B2_TX_DN<8>")
	)
	(via
		(at -151.539999 23.339999)
		(size 0.5588)
		(drill 0.254)
		(layers "F.Cu" "B.Cu")
		(net "PCIE_B2T_B2_TX_DN<8>")
	)
	(segment
		(start -185.46 25.760002)
		(end -184.906049 26.313953)
		(width 0.127)
		(layer "In5.Cu")
		(net "PCIE_B2T_B2_TX_DN<8>")
	)
	(segment
		(start -152.028949 23.828949)
		(end -151.539999 23.339999)
		(width 0.127)
		(layer "In5.Cu")
		(net "PCIE_B2T_B2_TX_DN<8>")
	)
	(segment
		(start -184.790194 26.313953)
		(end -184.590893 26.114652)
		(width 0.127)
		(layer "In5.Cu")
		(net "PCIE_B2T_B2_TX_DN<8>")
	)
	(segment
		(start -158.236313 22.5552)
		(end -153.661087 22.5552)
		(width 0.127)
		(layer "In5.Cu")
		(net "PCIE_B2T_B2_TX_DN<8>")
	)
	(segment
		(start -153.661087 22.5552)
		(end -153.28138 22.934907)
		(width 0.127)
		(layer "In5.Cu")
		(net "PCIE_B2T_B2_TX_DN<8>")
	)
	(segment
		(start -180.186993 17.9959)
		(end -166.6929 17.9959)
		(width 0.127)
		(layer "In5.Cu")
		(net "PCIE_B2T_B2_TX_DN<8>")
	)
	(segment
		(start -153.28138 22.934907)
		(end -153.28138 23.727387)
		(width 0.127)
		(layer "In5.Cu")
		(net "PCIE_B2T_B2_TX_DN<8>")
	)
	(segment
		(start -166.6929 17.9959)
		(end -161.25984 23.42896)
		(width 0.127)
		(layer "In5.Cu")
		(net "PCIE_B2T_B2_TX_DN<8>")
	)
	(segment
		(start -159.110073 23.42896)
		(end -158.236313 22.5552)
		(width 0.127)
		(layer "In5.Cu")
		(net "PCIE_B2T_B2_TX_DN<8>")
	)
	(segment
		(start -184.590893 26.114652)
		(end -184.590893 22.3998)
		(width 0.127)
		(layer "In5.Cu")
		(net "PCIE_B2T_B2_TX_DN<8>")
	)
	(segment
		(start -184.906049 26.313953)
		(end -184.790194 26.313953)
		(width 0.127)
		(layer "In5.Cu")
		(net "PCIE_B2T_B2_TX_DN<8>")
	)
	(segment
		(start -184.590893 22.3998)
		(end -180.186993 17.9959)
		(width 0.127)
		(layer "In5.Cu")
		(net "PCIE_B2T_B2_TX_DN<8>")
	)
	(segment
		(start -161.25984 23.42896)
		(end -159.110073 23.42896)
		(width 0.127)
		(layer "In5.Cu")
		(net "PCIE_B2T_B2_TX_DN<8>")
	)
	(segment
		(start -153.179818 23.828949)
		(end -152.028949 23.828949)
		(width 0.127)
		(layer "In5.Cu")
		(net "PCIE_B2T_B2_TX_DN<8>")
	)
	(segment
		(start -153.28138 23.727387)
		(end -153.179818 23.828949)
		(width 0.127)
		(layer "In5.Cu")
		(net "PCIE_B2T_B2_TX_DN<8>")
	)
	(segment
		(start -152.174999 41.754999)
		(end -152.809999 41.119999)
		(width 0.127)
		(layer "F.Cu")
		(net "PCIE_B2T_B2_TX_DN<7>")
	)
	(via
		(at -152.809999 41.119999)
		(size 0.5588)
		(drill 0.254)
		(layers "F.Cu" "B.Cu")
		(net "PCIE_B2T_B2_TX_DN<7>")
	)
	(segment
		(start -167.804125 31.807602)
		(end -165.499527 34.1122)
		(width 0.127)
		(layer "B.Cu")
		(net "PCIE_B2T_B2_TX_DN<7>")
	)
	(segment
		(start -153.292599 41.602599)
		(end -152.809999 41.119999)
		(width 0.127)
		(layer "B.Cu")
		(net "PCIE_B2T_B2_TX_DN<7>")
	)
	(segment
		(start -170.912399 31.807602)
		(end -167.804125 31.807602)
		(width 0.127)
		(layer "B.Cu")
		(net "PCIE_B2T_B2_TX_DN<7>")
	)
	(segment
		(start -154.5517 40.7416)
		(end -154.5517 41.455279)
		(width 0.127)
		(layer "B.Cu")
		(net "PCIE_B2T_B2_TX_DN<7>")
	)
	(segment
		(start -154.95556 40.33774)
		(end -154.5517 40.7416)
		(width 0.127)
		(layer "B.Cu")
		(net "PCIE_B2T_B2_TX_DN<7>")
	)
	(segment
		(start -154.40438 41.602599)
		(end -153.292599 41.602599)
		(width 0.127)
		(layer "B.Cu")
		(net "PCIE_B2T_B2_TX_DN<7>")
	)
	(segment
		(start -171.46 31.260001)
		(end -170.912399 31.807602)
		(width 0.127)
		(layer "B.Cu")
		(net "PCIE_B2T_B2_TX_DN<7>")
	)
	(segment
		(start -165.499527 34.1122)
		(end -163.62934 34.1122)
		(width 0.127)
		(layer "B.Cu")
		(net "PCIE_B2T_B2_TX_DN<7>")
	)
	(segment
		(start -163.62934 34.1122)
		(end -160.19272 37.54882)
		(width 0.127)
		(layer "B.Cu")
		(net "PCIE_B2T_B2_TX_DN<7>")
	)
	(segment
		(start -158.66142 40.33774)
		(end -154.95556 40.33774)
		(width 0.127)
		(layer "B.Cu")
		(net "PCIE_B2T_B2_TX_DN<7>")
	)
	(segment
		(start -160.19272 37.54882)
		(end -160.19272 38.80644)
		(width 0.127)
		(layer "B.Cu")
		(net "PCIE_B2T_B2_TX_DN<7>")
	)
	(segment
		(start -160.19272 38.80644)
		(end -158.66142 40.33774)
		(width 0.127)
		(layer "B.Cu")
		(net "PCIE_B2T_B2_TX_DN<7>")
	)
	(segment
		(start -154.5517 41.455279)
		(end -154.40438 41.602599)
		(width 0.127)
		(layer "B.Cu")
		(net "PCIE_B2T_B2_TX_DN<7>")
	)
	(segment
		(start -153.444999 39.214999)
		(end -154.079999 38.579999)
		(width 0.127)
		(layer "F.Cu")
		(net "PCIE_B2T_B2_TX_DN<6>")
	)
	(via
		(at -154.079999 38.579999)
		(size 0.5588)
		(drill 0.254)
		(layers "F.Cu" "B.Cu")
		(net "PCIE_B2T_B2_TX_DN<6>")
	)
	(segment
		(start -173.460001 29.960001)
		(end -172.9124 30.507602)
		(width 0.127)
		(layer "B.Cu")
		(net "PCIE_B2T_B2_TX_DN<6>")
	)
	(segment
		(start -155.67438 39.062599)
		(end -154.562599 39.062599)
		(width 0.127)
		(layer "B.Cu")
		(net "PCIE_B2T_B2_TX_DN<6>")
	)
	(segment
		(start -159.291767 36.4998)
		(end -158.35662 36.4998)
		(width 0.127)
		(layer "B.Cu")
		(net "PCIE_B2T_B2_TX_DN<6>")
	)
	(segment
		(start -158.35662 36.4998)
		(end -157.05868 37.79774)
		(width 0.127)
		(layer "B.Cu")
		(net "PCIE_B2T_B2_TX_DN<6>")
	)
	(segment
		(start -172.9124 30.507602)
		(end -172.721646 30.507602)
		(width 0.127)
		(layer "B.Cu")
		(net "PCIE_B2T_B2_TX_DN<6>")
	)
	(segment
		(start -171.9888 24.511)
		(end -171.4554 24.511)
		(width 0.127)
		(layer "B.Cu")
		(net "PCIE_B2T_B2_TX_DN<6>")
	)
	(segment
		(start -156.22556 37.79774)
		(end -155.8217 38.2016)
		(width 0.127)
		(layer "B.Cu")
		(net "PCIE_B2T_B2_TX_DN<6>")
	)
	(segment
		(start -170.986516 24.517002)
		(end -170.317 25.186518)
		(width 0.127)
		(layer "B.Cu")
		(net "PCIE_B2T_B2_TX_DN<6>")
	)
	(segment
		(start -155.8217 38.2016)
		(end -155.8217 38.915279)
		(width 0.127)
		(layer "B.Cu")
		(net "PCIE_B2T_B2_TX_DN<6>")
	)
	(segment
		(start -172.603 30.388956)
		(end -172.603 25.1252)
		(width 0.127)
		(layer "B.Cu")
		(net "PCIE_B2T_B2_TX_DN<6>")
	)
	(segment
		(start -172.603 25.1252)
		(end -171.9888 24.511)
		(width 0.127)
		(layer "B.Cu")
		(net "PCIE_B2T_B2_TX_DN<6>")
	)
	(segment
		(start -163.350687 32.44088)
		(end -159.291767 36.4998)
		(width 0.127)
		(layer "B.Cu")
		(net "PCIE_B2T_B2_TX_DN<6>")
	)
	(segment
		(start -170.317 25.186518)
		(end -170.317 25.7964)
		(width 0.127)
		(layer "B.Cu")
		(net "PCIE_B2T_B2_TX_DN<6>")
	)
	(segment
		(start -171.4554 24.511)
		(end -171.449398 24.517002)
		(width 0.127)
		(layer "B.Cu")
		(net "PCIE_B2T_B2_TX_DN<6>")
	)
	(segment
		(start -157.05868 37.79774)
		(end -156.22556 37.79774)
		(width 0.127)
		(layer "B.Cu")
		(net "PCIE_B2T_B2_TX_DN<6>")
	)
	(segment
		(start -163.67252 32.44088)
		(end -163.350687 32.44088)
		(width 0.127)
		(layer "B.Cu")
		(net "PCIE_B2T_B2_TX_DN<6>")
	)
	(segment
		(start -170.317 25.7964)
		(end -163.67252 32.44088)
		(width 0.127)
		(layer "B.Cu")
		(net "PCIE_B2T_B2_TX_DN<6>")
	)
	(segment
		(start -171.449398 24.517002)
		(end -170.986516 24.517002)
		(width 0.127)
		(layer "B.Cu")
		(net "PCIE_B2T_B2_TX_DN<6>")
	)
	(segment
		(start -154.562599 39.062599)
		(end -154.079999 38.579999)
		(width 0.127)
		(layer "B.Cu")
		(net "PCIE_B2T_B2_TX_DN<6>")
	)
	(segment
		(start -155.8217 38.915279)
		(end -155.67438 39.062599)
		(width 0.127)
		(layer "B.Cu")
		(net "PCIE_B2T_B2_TX_DN<6>")
	)
	(segment
		(start -172.721646 30.507602)
		(end -172.603 30.388956)
		(width 0.127)
		(layer "B.Cu")
		(net "PCIE_B2T_B2_TX_DN<6>")
	)
	(segment
		(start -152.174999 36.674999)
		(end -152.809999 36.039999)
		(width 0.127)
		(layer "F.Cu")
		(net "PCIE_B2T_B2_TX_DN<5>")
	)
	(via
		(at -152.809999 36.039999)
		(size 0.5588)
		(drill 0.254)
		(layers "F.Cu" "B.Cu")
		(net "PCIE_B2T_B2_TX_DN<5>")
	)
	(segment
		(start -174.605 31.646284)
		(end -174.605 23.901314)
		(width 0.127)
		(layer "B.Cu")
		(net "PCIE_B2T_B2_TX_DN<5>")
	)
	(segment
		(start -154.5517 36.375279)
		(end -154.40438 36.522599)
		(width 0.127)
		(layer "B.Cu")
		(net "PCIE_B2T_B2_TX_DN<5>")
	)
	(segment
		(start -174.603001 23.899315)
		(end -174.603001 23.886518)
		(width 0.127)
		(layer "B.Cu")
		(net "PCIE_B2T_B2_TX_DN<5>")
	)
	(segment
		(start -158.2928 35.25774)
		(end -154.95556 35.25774)
		(width 0.127)
		(layer "B.Cu")
		(net "PCIE_B2T_B2_TX_DN<5>")
	)
	(segment
		(start -174.766318 31.807602)
		(end -174.605 31.646284)
		(width 0.127)
		(layer "B.Cu")
		(net "PCIE_B2T_B2_TX_DN<5>")
	)
	(segment
		(start -153.292599 36.522599)
		(end -152.809999 36.039999)
		(width 0.127)
		(layer "B.Cu")
		(net "PCIE_B2T_B2_TX_DN<5>")
	)
	(segment
		(start -154.5517 35.6616)
		(end -154.5517 36.375279)
		(width 0.127)
		(layer "B.Cu")
		(net "PCIE_B2T_B2_TX_DN<5>")
	)
	(segment
		(start -154.95556 35.25774)
		(end -154.5517 35.6616)
		(width 0.127)
		(layer "B.Cu")
		(net "PCIE_B2T_B2_TX_DN<5>")
	)
	(segment
		(start -175.46 31.260001)
		(end -174.912398 31.807602)
		(width 0.127)
		(layer "B.Cu")
		(net "PCIE_B2T_B2_TX_DN<5>")
	)
	(segment
		(start -174.605 23.901314)
		(end -174.603001 23.899315)
		(width 0.127)
		(layer "B.Cu")
		(net "PCIE_B2T_B2_TX_DN<5>")
	)
	(segment
		(start -173.933485 23.217002)
		(end -170.333538 23.217002)
		(width 0.127)
		(layer "B.Cu")
		(net "PCIE_B2T_B2_TX_DN<5>")
	)
	(segment
		(start -154.40438 36.522599)
		(end -153.292599 36.522599)
		(width 0.127)
		(layer "B.Cu")
		(net "PCIE_B2T_B2_TX_DN<5>")
	)
	(segment
		(start -174.603001 23.886518)
		(end -173.933485 23.217002)
		(width 0.127)
		(layer "B.Cu")
		(net "PCIE_B2T_B2_TX_DN<5>")
	)
	(segment
		(start -170.333538 23.217002)
		(end -158.2928 35.25774)
		(width 0.127)
		(layer "B.Cu")
		(net "PCIE_B2T_B2_TX_DN<5>")
	)
	(segment
		(start -174.912398 31.807602)
		(end -174.766318 31.807602)
		(width 0.127)
		(layer "B.Cu")
		(net "PCIE_B2T_B2_TX_DN<5>")
	)
	(segment
		(start -153.444999 34.134999)
		(end -154.079999 33.499999)
		(width 0.127)
		(layer "F.Cu")
		(net "PCIE_B2T_B2_TX_DN<4>")
	)
	(via
		(at -154.079999 33.499999)
		(size 0.5588)
		(drill 0.254)
		(layers "F.Cu" "B.Cu")
		(net "PCIE_B2T_B2_TX_DN<4>")
	)
	(segment
		(start -176.9124 30.507602)
		(end -176.802204 30.507602)
		(width 0.127)
		(layer "B.Cu")
		(net "PCIE_B2T_B2_TX_DN<4>")
	)
	(segment
		(start -159.746 32.0802)
		(end -158.50648 32.0802)
		(width 0.127)
		(layer "B.Cu")
		(net "PCIE_B2T_B2_TX_DN<4>")
	)
	(segment
		(start -158.50648 32.0802)
		(end -157.86894 32.71774)
		(width 0.127)
		(layer "B.Cu")
		(net "PCIE_B2T_B2_TX_DN<4>")
	)
	(segment
		(start -154.562599 33.982599)
		(end -154.079999 33.499999)
		(width 0.127)
		(layer "B.Cu")
		(net "PCIE_B2T_B2_TX_DN<4>")
	)
	(segment
		(start -155.8217 33.1216)
		(end -155.8217 33.835279)
		(width 0.127)
		(layer "B.Cu")
		(net "PCIE_B2T_B2_TX_DN<4>")
	)
	(segment
		(start -177.460001 29.960001)
		(end -176.9124 30.507602)
		(width 0.127)
		(layer "B.Cu")
		(net "PCIE_B2T_B2_TX_DN<4>")
	)
	(segment
		(start -169.8298 21.9964)
		(end -159.746 32.0802)
		(width 0.127)
		(layer "B.Cu")
		(net "PCIE_B2T_B2_TX_DN<4>")
	)
	(segment
		(start -176.6116 24.0538)
		(end -174.5542 21.9964)
		(width 0.127)
		(layer "B.Cu")
		(net "PCIE_B2T_B2_TX_DN<4>")
	)
	(segment
		(start -155.67438 33.982599)
		(end -154.562599 33.982599)
		(width 0.127)
		(layer "B.Cu")
		(net "PCIE_B2T_B2_TX_DN<4>")
	)
	(segment
		(start -176.802204 30.507602)
		(end -176.6116 30.316998)
		(width 0.127)
		(layer "B.Cu")
		(net "PCIE_B2T_B2_TX_DN<4>")
	)
	(segment
		(start -156.22556 32.71774)
		(end -155.8217 33.1216)
		(width 0.127)
		(layer "B.Cu")
		(net "PCIE_B2T_B2_TX_DN<4>")
	)
	(segment
		(start -176.6116 30.316998)
		(end -176.6116 24.0538)
		(width 0.127)
		(layer "B.Cu")
		(net "PCIE_B2T_B2_TX_DN<4>")
	)
	(segment
		(start -157.86894 32.71774)
		(end -156.22556 32.71774)
		(width 0.127)
		(layer "B.Cu")
		(net "PCIE_B2T_B2_TX_DN<4>")
	)
	(segment
		(start -174.5542 21.9964)
		(end -169.8298 21.9964)
		(width 0.127)
		(layer "B.Cu")
		(net "PCIE_B2T_B2_TX_DN<4>")
	)
	(segment
		(start -155.8217 33.835279)
		(end -155.67438 33.982599)
		(width 0.127)
		(layer "B.Cu")
		(net "PCIE_B2T_B2_TX_DN<4>")
	)
	(segment
		(start -152.174999 31.594999)
		(end -152.809999 30.959999)
		(width 0.127)
		(layer "F.Cu")
		(net "PCIE_B2T_B2_TX_DN<3>")
	)
	(via
		(at -152.809999 30.959999)
		(size 0.5588)
		(drill 0.254)
		(layers "F.Cu" "B.Cu")
		(net "PCIE_B2T_B2_TX_DN<3>")
	)
	(segment
		(start -159.515607 30.17774)
		(end -154.95556 30.17774)
		(width 0.127)
		(layer "B.Cu")
		(net "PCIE_B2T_B2_TX_DN<3>")
	)
	(segment
		(start -168.919322 20.777015)
		(end -168.919136 20.7772)
		(width 0.127)
		(layer "B.Cu")
		(net "PCIE_B2T_B2_TX_DN<3>")
	)
	(segment
		(start -178.618264 23.774461)
		(end -178.6182 23.774397)
		(width 0.127)
		(layer "B.Cu")
		(net "PCIE_B2T_B2_TX_DN<3>")
	)
	(segment
		(start -154.95556 30.17774)
		(end -154.5517 30.5816)
		(width 0.127)
		(layer "B.Cu")
		(net "PCIE_B2T_B2_TX_DN<3>")
	)
	(segment
		(start -178.6182 23.774311)
		(end -178.43974 23.595851)
		(width 0.127)
		(layer "B.Cu")
		(net "PCIE_B2T_B2_TX_DN<3>")
	)
	(segment
		(start -153.292599 31.442599)
		(end -152.809999 30.959999)
		(width 0.127)
		(layer "B.Cu")
		(net "PCIE_B2T_B2_TX_DN<3>")
	)
	(segment
		(start -154.40438 31.442599)
		(end -153.292599 31.442599)
		(width 0.127)
		(layer "B.Cu")
		(net "PCIE_B2T_B2_TX_DN<3>")
	)
	(segment
		(start -178.43974 23.595851)
		(end -178.439653 23.595851)
		(width 0.127)
		(layer "B.Cu")
		(net "PCIE_B2T_B2_TX_DN<3>")
	)
	(segment
		(start -178.912398 31.807602)
		(end -178.785398 31.807602)
		(width 0.127)
		(layer "B.Cu")
		(net "PCIE_B2T_B2_TX_DN<3>")
	)
	(segment
		(start -178.618264 24.026846)
		(end -178.618264 23.774461)
		(width 0.127)
		(layer "B.Cu")
		(net "PCIE_B2T_B2_TX_DN<3>")
	)
	(segment
		(start -178.439653 23.595851)
		(end -175.621003 20.7772)
		(width 0.127)
		(layer "B.Cu")
		(net "PCIE_B2T_B2_TX_DN<3>")
	)
	(segment
		(start -175.621003 20.7772)
		(end -169.929157 20.7772)
		(width 0.127)
		(layer "B.Cu")
		(net "PCIE_B2T_B2_TX_DN<3>")
	)
	(segment
		(start -168.916147 20.7772)
		(end -159.515607 30.17774)
		(width 0.127)
		(layer "B.Cu")
		(net "PCIE_B2T_B2_TX_DN<3>")
	)
	(segment
		(start -178.6182 31.640404)
		(end -178.6182 24.026909)
		(width 0.127)
		(layer "B.Cu")
		(net "PCIE_B2T_B2_TX_DN<3>")
	)
	(segment
		(start -178.785398 31.807602)
		(end -178.6182 31.640404)
		(width 0.127)
		(layer "B.Cu")
		(net "PCIE_B2T_B2_TX_DN<3>")
	)
	(segment
		(start -169.929157 20.7772)
		(end -169.928972 20.777015)
		(width 0.127)
		(layer "B.Cu")
		(net "PCIE_B2T_B2_TX_DN<3>")
	)
	(segment
		(start -178.6182 23.774397)
		(end -178.6182 23.774311)
		(width 0.127)
		(layer "B.Cu")
		(net "PCIE_B2T_B2_TX_DN<3>")
	)
	(segment
		(start -178.6182 24.026909)
		(end -178.618264 24.026846)
		(width 0.127)
		(layer "B.Cu")
		(net "PCIE_B2T_B2_TX_DN<3>")
	)
	(segment
		(start -179.459999 31.260001)
		(end -178.912398 31.807602)
		(width 0.127)
		(layer "B.Cu")
		(net "PCIE_B2T_B2_TX_DN<3>")
	)
	(segment
		(start -154.5517 30.5816)
		(end -154.5517 31.295279)
		(width 0.127)
		(layer "B.Cu")
		(net "PCIE_B2T_B2_TX_DN<3>")
	)
	(segment
		(start -169.928972 20.777015)
		(end -168.919322 20.777015)
		(width 0.127)
		(layer "B.Cu")
		(net "PCIE_B2T_B2_TX_DN<3>")
	)
	(segment
		(start -154.5517 31.295279)
		(end -154.40438 31.442599)
		(width 0.127)
		(layer "B.Cu")
		(net "PCIE_B2T_B2_TX_DN<3>")
	)
	(segment
		(start -168.919136 20.7772)
		(end -168.916147 20.7772)
		(width 0.127)
		(layer "B.Cu")
		(net "PCIE_B2T_B2_TX_DN<3>")
	)
	(segment
		(start -153.444999 29.054999)
		(end -154.079999 28.419999)
		(width 0.127)
		(layer "F.Cu")
		(net "PCIE_B2T_B2_TX_DN<2>")
	)
	(via
		(at -154.079999 28.419999)
		(size 0.5588)
		(drill 0.254)
		(layers "F.Cu" "B.Cu")
		(net "PCIE_B2T_B2_TX_DN<2>")
	)
	(segment
		(start -176.2306 19.5072)
		(end -168.052547 19.5072)
		(width 0.127)
		(layer "B.Cu")
		(net "PCIE_B2T_B2_TX_DN<2>")
	)
	(segment
		(start -168.052547 19.5072)
		(end -160.564627 26.99512)
		(width 0.127)
		(layer "B.Cu")
		(net "PCIE_B2T_B2_TX_DN<2>")
	)
	(segment
		(start -180.785399 30.507602)
		(end -180.602999 30.325202)
		(width 0.127)
		(layer "B.Cu")
		(net "PCIE_B2T_B2_TX_DN<2>")
	)
	(segment
		(start -155.8217 28.755279)
		(end -155.67438 28.902599)
		(width 0.127)
		(layer "B.Cu")
		(net "PCIE_B2T_B2_TX_DN<2>")
	)
	(segment
		(start -157.98578 26.99512)
		(end -157.34316 27.63774)
		(width 0.127)
		(layer "B.Cu")
		(net "PCIE_B2T_B2_TX_DN<2>")
	)
	(segment
		(start -181.46 29.960001)
		(end -180.912399 30.507602)
		(width 0.127)
		(layer "B.Cu")
		(net "PCIE_B2T_B2_TX_DN<2>")
	)
	(segment
		(start -180.912399 30.507602)
		(end -180.785399 30.507602)
		(width 0.127)
		(layer "B.Cu")
		(net "PCIE_B2T_B2_TX_DN<2>")
	)
	(segment
		(start -157.34316 27.63774)
		(end -156.22556 27.63774)
		(width 0.127)
		(layer "B.Cu")
		(net "PCIE_B2T_B2_TX_DN<2>")
	)
	(segment
		(start -160.564627 26.99512)
		(end -157.98578 26.99512)
		(width 0.127)
		(layer "B.Cu")
		(net "PCIE_B2T_B2_TX_DN<2>")
	)
	(segment
		(start -180.602999 25.186432)
		(end -180.5994 25.182833)
		(width 0.127)
		(layer "B.Cu")
		(net "PCIE_B2T_B2_TX_DN<2>")
	)
	(segment
		(start -154.562599 28.902599)
		(end -154.079999 28.419999)
		(width 0.127)
		(layer "B.Cu")
		(net "PCIE_B2T_B2_TX_DN<2>")
	)
	(segment
		(start -156.22556 27.63774)
		(end -155.8217 28.0416)
		(width 0.127)
		(layer "B.Cu")
		(net "PCIE_B2T_B2_TX_DN<2>")
	)
	(segment
		(start -180.5994 23.876)
		(end -176.2306 19.5072)
		(width 0.127)
		(layer "B.Cu")
		(net "PCIE_B2T_B2_TX_DN<2>")
	)
	(segment
		(start -180.5994 25.182833)
		(end -180.5994 23.876)
		(width 0.127)
		(layer "B.Cu")
		(net "PCIE_B2T_B2_TX_DN<2>")
	)
	(segment
		(start -155.8217 28.0416)
		(end -155.8217 28.755279)
		(width 0.127)
		(layer "B.Cu")
		(net "PCIE_B2T_B2_TX_DN<2>")
	)
	(segment
		(start -180.602999 30.325202)
		(end -180.602999 25.186432)
		(width 0.127)
		(layer "B.Cu")
		(net "PCIE_B2T_B2_TX_DN<2>")
	)
	(segment
		(start -155.67438 28.902599)
		(end -154.562599 28.902599)
		(width 0.127)
		(layer "B.Cu")
		(net "PCIE_B2T_B2_TX_DN<2>")
	)
	(segment
		(start -152.174999 26.514999)
		(end -152.809999 25.879999)
		(width 0.127)
		(layer "F.Cu")
		(net "PCIE_B2T_B2_TX_DN<1>")
	)
	(via
		(at -152.809999 25.879999)
		(size 0.5588)
		(drill 0.254)
		(layers "F.Cu" "B.Cu")
		(net "PCIE_B2T_B2_TX_DN<1>")
	)
	(segment
		(start -182.701761 31.807602)
		(end -182.912398 31.807602)
		(width 0.127)
		(layer "B.Cu")
		(net "PCIE_B2T_B2_TX_DN<1>")
	)
	(segment
		(start -154.95556 25.09774)
		(end -160.607807 25.09774)
		(width 0.127)
		(layer "B.Cu")
		(net "PCIE_B2T_B2_TX_DN<1>")
	)
	(segment
		(start -182.606 31.711842)
		(end -182.701761 31.807602)
		(width 0.127)
		(layer "B.Cu")
		(net "PCIE_B2T_B2_TX_DN<1>")
	)
	(segment
		(start -154.40438 26.362599)
		(end -154.5517 26.215279)
		(width 0.127)
		(layer "B.Cu")
		(net "PCIE_B2T_B2_TX_DN<1>")
	)
	(segment
		(start -167.442947 18.2626)
		(end -177.1958 18.2626)
		(width 0.127)
		(layer "B.Cu")
		(net "PCIE_B2T_B2_TX_DN<1>")
	)
	(segment
		(start -182.606 23.6728)
		(end -182.606 31.711842)
		(width 0.127)
		(layer "B.Cu")
		(net "PCIE_B2T_B2_TX_DN<1>")
	)
	(segment
		(start -154.5517 25.5016)
		(end -154.95556 25.09774)
		(width 0.127)
		(layer "B.Cu")
		(net "PCIE_B2T_B2_TX_DN<1>")
	)
	(segment
		(start -177.1958 18.2626)
		(end -182.606 23.6728)
		(width 0.127)
		(layer "B.Cu")
		(net "PCIE_B2T_B2_TX_DN<1>")
	)
	(segment
		(start -154.5517 26.215279)
		(end -154.5517 25.5016)
		(width 0.127)
		(layer "B.Cu")
		(net "PCIE_B2T_B2_TX_DN<1>")
	)
	(segment
		(start -182.912398 31.807602)
		(end -183.459999 31.260001)
		(width 0.127)
		(layer "B.Cu")
		(net "PCIE_B2T_B2_TX_DN<1>")
	)
	(segment
		(start -160.607807 25.09774)
		(end -167.442947 18.2626)
		(width 0.127)
		(layer "B.Cu")
		(net "PCIE_B2T_B2_TX_DN<1>")
	)
	(segment
		(start -152.809999 25.879999)
		(end -153.292599 26.362599)
		(width 0.127)
		(layer "B.Cu")
		(net "PCIE_B2T_B2_TX_DN<1>")
	)
	(segment
		(start -153.292599 26.362599)
		(end -154.40438 26.362599)
		(width 0.127)
		(layer "B.Cu")
		(net "PCIE_B2T_B2_TX_DN<1>")
	)
	(segment
		(start -149.634999 41.754999)
		(end -150.269999 41.119999)
		(width 0.127)
		(layer "F.Cu")
		(net "PCIE_B2T_B2_TX_DN<15>")
	)
	(via
		(at -150.269999 41.119999)
		(size 0.5588)
		(drill 0.254)
		(layers "F.Cu" "B.Cu")
		(net "PCIE_B2T_B2_TX_DN<15>")
	)
	(segment
		(start -152.30602 41.97064)
		(end -152.30602 42.777067)
		(width 0.127)
		(layer "In5.Cu")
		(net "PCIE_B2T_B2_TX_DN<15>")
	)
	(segment
		(start -150.758949 41.608949)
		(end -151.944329 41.608949)
		(width 0.127)
		(layer "In5.Cu")
		(net "PCIE_B2T_B2_TX_DN<15>")
	)
	(segment
		(start -158.365533 42.9895)
		(end -159.122453 43.74642)
		(width 0.127)
		(layer "In5.Cu")
		(net "PCIE_B2T_B2_TX_DN<15>")
	)
	(segment
		(start -170.658058 27.613953)
		(end -170.906049 27.613953)
		(width 0.127)
		(layer "In5.Cu")
		(net "PCIE_B2T_B2_TX_DN<15>")
	)
	(segment
		(start -170.148933 28.123078)
		(end -170.658058 27.613953)
		(width 0.127)
		(layer "In5.Cu")
		(net "PCIE_B2T_B2_TX_DN<15>")
	)
	(segment
		(start -170.148933 33.132667)
		(end -170.148933 28.123078)
		(width 0.127)
		(layer "In5.Cu")
		(net "PCIE_B2T_B2_TX_DN<15>")
	)
	(segment
		(start -169.962807 33.318793)
		(end -170.148933 33.132667)
		(width 0.127)
		(layer "In5.Cu")
		(net "PCIE_B2T_B2_TX_DN<15>")
	)
	(segment
		(start -150.269999 41.119999)
		(end -150.758949 41.608949)
		(width 0.127)
		(layer "In5.Cu")
		(net "PCIE_B2T_B2_TX_DN<15>")
	)
	(segment
		(start -159.122453 43.74642)
		(end -167.148487 43.74642)
		(width 0.127)
		(layer "In5.Cu")
		(net "PCIE_B2T_B2_TX_DN<15>")
	)
	(segment
		(start -170.906049 27.613953)
		(end -171.46 27.060002)
		(width 0.127)
		(layer "In5.Cu")
		(net "PCIE_B2T_B2_TX_DN<15>")
	)
	(segment
		(start -151.944329 41.608949)
		(end -152.30602 41.97064)
		(width 0.127)
		(layer "In5.Cu")
		(net "PCIE_B2T_B2_TX_DN<15>")
	)
	(segment
		(start -167.148487 43.74642)
		(end -169.7917 41.103207)
		(width 0.127)
		(layer "In5.Cu")
		(net "PCIE_B2T_B2_TX_DN<15>")
	)
	(segment
		(start -152.30602 42.777067)
		(end -152.518453 42.9895)
		(width 0.127)
		(layer "In5.Cu")
		(net "PCIE_B2T_B2_TX_DN<15>")
	)
	(segment
		(start -169.7917 33.489816)
		(end -169.962723 33.318793)
		(width 0.127)
		(layer "In5.Cu")
		(net "PCIE_B2T_B2_TX_DN<15>")
	)
	(segment
		(start -152.518453 42.9895)
		(end -158.365533 42.9895)
		(width 0.127)
		(layer "In5.Cu")
		(net "PCIE_B2T_B2_TX_DN<15>")
	)
	(segment
		(start -169.962723 33.318793)
		(end -169.962807 33.318793)
		(width 0.127)
		(layer "In5.Cu")
		(net "PCIE_B2T_B2_TX_DN<15>")
	)
	(segment
		(start -169.7917 41.103207)
		(end -169.7917 33.489816)
		(width 0.127)
		(layer "In5.Cu")
		(net "PCIE_B2T_B2_TX_DN<15>")
	)
	(segment
		(start -150.904999 39.214999)
		(end -151.539999 38.579999)
		(width 0.127)
		(layer "F.Cu")
		(net "PCIE_B2T_B2_TX_DN<14>")
	)
	(via
		(at -151.539999 38.579999)
		(size 0.5588)
		(drill 0.254)
		(layers "F.Cu" "B.Cu")
		(net "PCIE_B2T_B2_TX_DN<14>")
	)
	(segment
		(start -173.460001 25.760002)
		(end -172.90605 26.313953)
		(width 0.127)
		(layer "In5.Cu")
		(net "PCIE_B2T_B2_TX_DN<14>")
	)
	(segment
		(start -168.6995 26.7335)
		(end -168.6995 30.5181)
		(width 0.127)
		(layer "In5.Cu")
		(net "PCIE_B2T_B2_TX_DN<14>")
	)
	(segment
		(start -152.028949 39.068949)
		(end -151.539999 38.579999)
		(width 0.127)
		(layer "In5.Cu")
		(net "PCIE_B2T_B2_TX_DN<14>")
	)
	(segment
		(start -172.141441 24.4983)
		(end -170.9347 24.4983)
		(width 0.127)
		(layer "In5.Cu")
		(net "PCIE_B2T_B2_TX_DN<14>")
	)
	(segment
		(start -153.28138 38.967387)
		(end -153.179818 39.068949)
		(width 0.127)
		(layer "In5.Cu")
		(net "PCIE_B2T_B2_TX_DN<14>")
	)
	(segment
		(start -157.7648 37.79774)
		(end -153.658547 37.79774)
		(width 0.127)
		(layer "In5.Cu")
		(net "PCIE_B2T_B2_TX_DN<14>")
	)
	(segment
		(start -153.28138 38.174907)
		(end -153.28138 38.967387)
		(width 0.127)
		(layer "In5.Cu")
		(net "PCIE_B2T_B2_TX_DN<14>")
	)
	(segment
		(start -172.65205 26.186953)
		(end -172.65205 25.008909)
		(width 0.127)
		(layer "In5.Cu")
		(net "PCIE_B2T_B2_TX_DN<14>")
	)
	(segment
		(start -153.179818 39.068949)
		(end -152.028949 39.068949)
		(width 0.127)
		(layer "In5.Cu")
		(net "PCIE_B2T_B2_TX_DN<14>")
	)
	(segment
		(start -153.658547 37.79774)
		(end -153.28138 38.174907)
		(width 0.127)
		(layer "In5.Cu")
		(net "PCIE_B2T_B2_TX_DN<14>")
	)
	(segment
		(start -158.39218 37.17036)
		(end -157.7648 37.79774)
		(width 0.127)
		(layer "In5.Cu")
		(net "PCIE_B2T_B2_TX_DN<14>")
	)
	(segment
		(start -172.77905 26.313953)
		(end -172.65205 26.186953)
		(width 0.127)
		(layer "In5.Cu")
		(net "PCIE_B2T_B2_TX_DN<14>")
	)
	(segment
		(start -170.9347 24.4983)
		(end -168.6995 26.7335)
		(width 0.127)
		(layer "In5.Cu")
		(net "PCIE_B2T_B2_TX_DN<14>")
	)
	(segment
		(start -162.04724 37.17036)
		(end -158.39218 37.17036)
		(width 0.127)
		(layer "In5.Cu")
		(net "PCIE_B2T_B2_TX_DN<14>")
	)
	(segment
		(start -172.90605 26.313953)
		(end -172.77905 26.313953)
		(width 0.127)
		(layer "In5.Cu")
		(net "PCIE_B2T_B2_TX_DN<14>")
	)
	(segment
		(start -168.6995 30.5181)
		(end -162.04724 37.17036)
		(width 0.127)
		(layer "In5.Cu")
		(net "PCIE_B2T_B2_TX_DN<14>")
	)
	(segment
		(start -172.65205 25.008909)
		(end -172.141441 24.4983)
		(width 0.127)
		(layer "In5.Cu")
		(net "PCIE_B2T_B2_TX_DN<14>")
	)
	(segment
		(start -149.634999 36.674999)
		(end -150.269999 36.039999)
		(width 0.127)
		(layer "F.Cu")
		(net "PCIE_B2T_B2_TX_DN<13>")
	)
	(via
		(at -150.269999 36.039999)
		(size 0.5588)
		(drill 0.254)
		(layers "F.Cu" "B.Cu")
		(net "PCIE_B2T_B2_TX_DN<13>")
	)
	(segment
		(start -175.46 27.060002)
		(end -174.906048 27.613953)
		(width 0.127)
		(layer "In5.Cu")
		(net "PCIE_B2T_B2_TX_DN<13>")
	)
	(segment
		(start -151.909818 36.528949)
		(end -150.758949 36.528949)
		(width 0.127)
		(layer "In5.Cu")
		(net "PCIE_B2T_B2_TX_DN<13>")
	)
	(segment
		(start -152.391087 35.2552)
		(end -152.01392 35.632367)
		(width 0.127)
		(layer "In5.Cu")
		(net "PCIE_B2T_B2_TX_DN<13>")
	)
	(segment
		(start -173.9319 23.2283)
		(end -170.6299 23.2283)
		(width 0.127)
		(layer "In5.Cu")
		(net "PCIE_B2T_B2_TX_DN<13>")
	)
	(segment
		(start -174.6723 27.613953)
		(end -174.5923 27.533953)
		(width 0.127)
		(layer "In5.Cu")
		(net "PCIE_B2T_B2_TX_DN<13>")
	)
	(segment
		(start -170.6299 23.2283)
		(end -167.3914 26.4668)
		(width 0.127)
		(layer "In5.Cu")
		(net "PCIE_B2T_B2_TX_DN<13>")
	)
	(segment
		(start -174.906048 27.613953)
		(end -174.6723 27.613953)
		(width 0.127)
		(layer "In5.Cu")
		(net "PCIE_B2T_B2_TX_DN<13>")
	)
	(segment
		(start -158.9151 34.69894)
		(end -158.35884 35.2552)
		(width 0.127)
		(layer "In5.Cu")
		(net "PCIE_B2T_B2_TX_DN<13>")
	)
	(segment
		(start -158.35884 35.2552)
		(end -152.391087 35.2552)
		(width 0.127)
		(layer "In5.Cu")
		(net "PCIE_B2T_B2_TX_DN<13>")
	)
	(segment
		(start -174.5923 23.8887)
		(end -173.9319 23.2283)
		(width 0.127)
		(layer "In5.Cu")
		(net "PCIE_B2T_B2_TX_DN<13>")
	)
	(segment
		(start -150.758949 36.528949)
		(end -150.269999 36.039999)
		(width 0.127)
		(layer "In5.Cu")
		(net "PCIE_B2T_B2_TX_DN<13>")
	)
	(segment
		(start -152.01392 35.632367)
		(end -152.01392 36.424847)
		(width 0.127)
		(layer "In5.Cu")
		(net "PCIE_B2T_B2_TX_DN<13>")
	)
	(segment
		(start -174.5923 27.533953)
		(end -174.5923 23.8887)
		(width 0.127)
		(layer "In5.Cu")
		(net "PCIE_B2T_B2_TX_DN<13>")
	)
	(segment
		(start -167.3914 29.2608)
		(end -161.95326 34.69894)
		(width 0.127)
		(layer "In5.Cu")
		(net "PCIE_B2T_B2_TX_DN<13>")
	)
	(segment
		(start -167.3914 26.4668)
		(end -167.3914 29.2608)
		(width 0.127)
		(layer "In5.Cu")
		(net "PCIE_B2T_B2_TX_DN<13>")
	)
	(segment
		(start -152.01392 36.424847)
		(end -151.909818 36.528949)
		(width 0.127)
		(layer "In5.Cu")
		(net "PCIE_B2T_B2_TX_DN<13>")
	)
	(segment
		(start -161.95326 34.69894)
		(end -158.9151 34.69894)
		(width 0.127)
		(layer "In5.Cu")
		(net "PCIE_B2T_B2_TX_DN<13>")
	)
	(segment
		(start -150.904999 34.134999)
		(end -151.539999 33.499999)
		(width 0.127)
		(layer "F.Cu")
		(net "PCIE_B2T_B2_TX_DN<12>")
	)
	(via
		(at -151.539999 33.499999)
		(size 0.5588)
		(drill 0.254)
		(layers "F.Cu" "B.Cu")
		(net "PCIE_B2T_B2_TX_DN<12>")
	)
	(segment
		(start -166.223 26.0604)
		(end -166.223 26.942707)
		(width 0.127)
		(layer "In5.Cu")
		(net "PCIE_B2T_B2_TX_DN<12>")
	)
	(segment
		(start -176.5989 23.653407)
		(end -175.132393 22.1869)
		(width 0.127)
		(layer "In5.Cu")
		(net "PCIE_B2T_B2_TX_DN<12>")
	)
	(segment
		(start -176.90605 26.313953)
		(end -176.756444 26.313953)
		(width 0.127)
		(layer "In5.Cu")
		(net "PCIE_B2T_B2_TX_DN<12>")
	)
	(segment
		(start -153.28138 33.094907)
		(end -153.28138 33.887387)
		(width 0.127)
		(layer "In5.Cu")
		(net "PCIE_B2T_B2_TX_DN<12>")
	)
	(segment
		(start -158.26518 32.11068)
		(end -157.65812 32.71774)
		(width 0.127)
		(layer "In5.Cu")
		(net "PCIE_B2T_B2_TX_DN<12>")
	)
	(segment
		(start -157.65812 32.71774)
		(end -153.658547 32.71774)
		(width 0.127)
		(layer "In5.Cu")
		(net "PCIE_B2T_B2_TX_DN<12>")
	)
	(segment
		(start -176.756444 26.313953)
		(end -176.5989 26.156409)
		(width 0.127)
		(layer "In5.Cu")
		(net "PCIE_B2T_B2_TX_DN<12>")
	)
	(segment
		(start -152.028949 33.988949)
		(end -151.539999 33.499999)
		(width 0.127)
		(layer "In5.Cu")
		(net "PCIE_B2T_B2_TX_DN<12>")
	)
	(segment
		(start -170.0965 22.1869)
		(end -166.223 26.0604)
		(width 0.127)
		(layer "In5.Cu")
		(net "PCIE_B2T_B2_TX_DN<12>")
	)
	(segment
		(start -176.5989 26.156409)
		(end -176.5989 23.653407)
		(width 0.127)
		(layer "In5.Cu")
		(net "PCIE_B2T_B2_TX_DN<12>")
	)
	(segment
		(start -153.658547 32.71774)
		(end -153.28138 33.094907)
		(width 0.127)
		(layer "In5.Cu")
		(net "PCIE_B2T_B2_TX_DN<12>")
	)
	(segment
		(start -161.055027 32.11068)
		(end -158.26518 32.11068)
		(width 0.127)
		(layer "In5.Cu")
		(net "PCIE_B2T_B2_TX_DN<12>")
	)
	(segment
		(start -166.223 26.942707)
		(end -161.055027 32.11068)
		(width 0.127)
		(layer "In5.Cu")
		(net "PCIE_B2T_B2_TX_DN<12>")
	)
	(segment
		(start -177.460001 25.760002)
		(end -176.90605 26.313953)
		(width 0.127)
		(layer "In5.Cu")
		(net "PCIE_B2T_B2_TX_DN<12>")
	)
	(segment
		(start -175.132393 22.1869)
		(end -170.0965 22.1869)
		(width 0.127)
		(layer "In5.Cu")
		(net "PCIE_B2T_B2_TX_DN<12>")
	)
	(segment
		(start -153.28138 33.887387)
		(end -153.179818 33.988949)
		(width 0.127)
		(layer "In5.Cu")
		(net "PCIE_B2T_B2_TX_DN<12>")
	)
	(segment
		(start -153.179818 33.988949)
		(end -152.028949 33.988949)
		(width 0.127)
		(layer "In5.Cu")
		(net "PCIE_B2T_B2_TX_DN<12>")
	)
	(segment
		(start -149.634999 31.594999)
		(end -150.269999 30.959999)
		(width 0.127)
		(layer "F.Cu")
		(net "PCIE_B2T_B2_TX_DN<11>")
	)
	(via
		(at -150.269999 30.959999)
		(size 0.5588)
		(drill 0.254)
		(layers "F.Cu" "B.Cu")
		(net "PCIE_B2T_B2_TX_DN<11>")
	)
	(segment
		(start -150.758949 31.448949)
		(end -150.269999 30.959999)
		(width 0.127)
		(layer "In5.Cu")
		(net "PCIE_B2T_B2_TX_DN<11>")
	)
	(segment
		(start -178.6055 23.6855)
		(end -176.0401 21.1201)
		(width 0.127)
		(layer "In5.Cu")
		(net "PCIE_B2T_B2_TX_DN<11>")
	)
	(segment
		(start -178.6055 27.50152)
		(end -178.6055 23.6855)
		(width 0.127)
		(layer "In5.Cu")
		(net "PCIE_B2T_B2_TX_DN<11>")
	)
	(segment
		(start -151.909818 31.448949)
		(end -150.758949 31.448949)
		(width 0.127)
		(layer "In5.Cu")
		(net "PCIE_B2T_B2_TX_DN<11>")
	)
	(segment
		(start -152.383467 30.18282)
		(end -152.01392 30.552367)
		(width 0.127)
		(layer "In5.Cu")
		(net "PCIE_B2T_B2_TX_DN<11>")
	)
	(segment
		(start -152.01392 31.344847)
		(end -151.909818 31.448949)
		(width 0.127)
		(layer "In5.Cu")
		(net "PCIE_B2T_B2_TX_DN<11>")
	)
	(segment
		(start -178.906048 27.613953)
		(end -178.717933 27.613953)
		(width 0.127)
		(layer "In5.Cu")
		(net "PCIE_B2T_B2_TX_DN<11>")
	)
	(segment
		(start -160.57658 30.18282)
		(end -152.383467 30.18282)
		(width 0.127)
		(layer "In5.Cu")
		(net "PCIE_B2T_B2_TX_DN<11>")
	)
	(segment
		(start -178.717933 27.613953)
		(end -178.6055 27.50152)
		(width 0.127)
		(layer "In5.Cu")
		(net "PCIE_B2T_B2_TX_DN<11>")
	)
	(segment
		(start -179.459999 27.060002)
		(end -178.906048 27.613953)
		(width 0.127)
		(layer "In5.Cu")
		(net "PCIE_B2T_B2_TX_DN<11>")
	)
	(segment
		(start -152.01392 30.552367)
		(end -152.01392 31.344847)
		(width 0.127)
		(layer "In5.Cu")
		(net "PCIE_B2T_B2_TX_DN<11>")
	)
	(segment
		(start -169.6393 21.1201)
		(end -160.57658 30.18282)
		(width 0.127)
		(layer "In5.Cu")
		(net "PCIE_B2T_B2_TX_DN<11>")
	)
	(segment
		(start -176.0401 21.1201)
		(end -169.6393 21.1201)
		(width 0.127)
		(layer "In5.Cu")
		(net "PCIE_B2T_B2_TX_DN<11>")
	)
	(segment
		(start -150.904999 29.054999)
		(end -151.539999 28.419999)
		(width 0.127)
		(layer "F.Cu")
		(net "PCIE_B2T_B2_TX_DN<10>")
	)
	(via
		(at -151.539999 28.419999)
		(size 0.5588)
		(drill 0.254)
		(layers "F.Cu" "B.Cu")
		(net "PCIE_B2T_B2_TX_DN<10>")
	)
	(segment
		(start -180.6121 23.628007)
		(end -177.062793 20.0787)
		(width 0.127)
		(layer "In5.Cu")
		(net "PCIE_B2T_B2_TX_DN<10>")
	)
	(segment
		(start -153.658547 27.63774)
		(end -153.28392 28.012367)
		(width 0.127)
		(layer "In5.Cu")
		(net "PCIE_B2T_B2_TX_DN<10>")
	)
	(segment
		(start -169.1567 20.0787)
		(end -165.950293 23.285107)
		(width 0.127)
		(layer "In5.Cu")
		(net "PCIE_B2T_B2_TX_DN<10>")
	)
	(segment
		(start -180.906049 26.313953)
		(end -180.667863 26.313953)
		(width 0.127)
		(layer "In5.Cu")
		(net "PCIE_B2T_B2_TX_DN<10>")
	)
	(segment
		(start -160.656247 26.99766)
		(end -158.64364 26.99766)
		(width 0.127)
		(layer "In5.Cu")
		(net "PCIE_B2T_B2_TX_DN<10>")
	)
	(segment
		(start -177.062793 20.0787)
		(end -169.1567 20.0787)
		(width 0.127)
		(layer "In5.Cu")
		(net "PCIE_B2T_B2_TX_DN<10>")
	)
	(segment
		(start -153.28392 28.804847)
		(end -153.179818 28.908949)
		(width 0.127)
		(layer "In5.Cu")
		(net "PCIE_B2T_B2_TX_DN<10>")
	)
	(segment
		(start -181.46 25.760002)
		(end -180.906049 26.313953)
		(width 0.127)
		(layer "In5.Cu")
		(net "PCIE_B2T_B2_TX_DN<10>")
	)
	(segment
		(start -158.64364 26.99766)
		(end -158.00356 27.63774)
		(width 0.127)
		(layer "In5.Cu")
		(net "PCIE_B2T_B2_TX_DN<10>")
	)
	(segment
		(start -152.028949 28.908949)
		(end -151.539999 28.419999)
		(width 0.127)
		(layer "In5.Cu")
		(net "PCIE_B2T_B2_TX_DN<10>")
	)
	(segment
		(start -180.667863 26.313953)
		(end -180.6121 26.25819)
		(width 0.127)
		(layer "In5.Cu")
		(net "PCIE_B2T_B2_TX_DN<10>")
	)
	(segment
		(start -158.00356 27.63774)
		(end -153.658547 27.63774)
		(width 0.127)
		(layer "In5.Cu")
		(net "PCIE_B2T_B2_TX_DN<10>")
	)
	(segment
		(start -164.3688 23.285107)
		(end -160.656247 26.99766)
		(width 0.127)
		(layer "In5.Cu")
		(net "PCIE_B2T_B2_TX_DN<10>")
	)
	(segment
		(start -153.179818 28.908949)
		(end -152.028949 28.908949)
		(width 0.127)
		(layer "In5.Cu")
		(net "PCIE_B2T_B2_TX_DN<10>")
	)
	(segment
		(start -180.6121 26.25819)
		(end -180.6121 23.628007)
		(width 0.127)
		(layer "In5.Cu")
		(net "PCIE_B2T_B2_TX_DN<10>")
	)
	(segment
		(start -153.28392 28.012367)
		(end -153.28392 28.804847)
		(width 0.127)
		(layer "In5.Cu")
		(net "PCIE_B2T_B2_TX_DN<10>")
	)
	(segment
		(start -165.950293 23.285107)
		(end -164.3688 23.285107)
		(width 0.127)
		(layer "In5.Cu")
		(net "PCIE_B2T_B2_TX_DN<10>")
	)
	(segment
		(start -153.444999 23.974999)
		(end -154.079999 23.339999)
		(width 0.127)
		(layer "F.Cu")
		(net "PCIE_B2T_B2_TX_DN<0>")
	)
	(via
		(at -154.079999 23.339999)
		(size 0.5588)
		(drill 0.254)
		(layers "F.Cu" "B.Cu")
		(net "PCIE_B2T_B2_TX_DN<0>")
	)
	(segment
		(start -184.6126 30.334803)
		(end -184.785399 30.507602)
		(width 0.127)
		(layer "B.Cu")
		(net "PCIE_B2T_B2_TX_DN<0>")
	)
	(segment
		(start -184.785399 30.507602)
		(end -184.912399 30.507602)
		(width 0.127)
		(layer "B.Cu")
		(net "PCIE_B2T_B2_TX_DN<0>")
	)
	(segment
		(start -184.6126 23.7744)
		(end -184.6126 30.334803)
		(width 0.127)
		(layer "B.Cu")
		(net "PCIE_B2T_B2_TX_DN<0>")
	)
	(segment
		(start -155.67438 23.822599)
		(end -155.8217 23.675279)
		(width 0.127)
		(layer "B.Cu")
		(net "PCIE_B2T_B2_TX_DN<0>")
	)
	(segment
		(start -154.079999 23.339999)
		(end -154.562599 23.822599)
		(width 0.127)
		(layer "B.Cu")
		(net "PCIE_B2T_B2_TX_DN<0>")
	)
	(segment
		(start -155.8217 22.9616)
		(end -156.22556 22.55774)
		(width 0.127)
		(layer "B.Cu")
		(net "PCIE_B2T_B2_TX_DN<0>")
	)
	(segment
		(start -158.33376 22.55774)
		(end -159.19228 23.41626)
		(width 0.127)
		(layer "B.Cu")
		(net "PCIE_B2T_B2_TX_DN<0>")
	)
	(segment
		(start -159.19228 23.41626)
		(end -160.231887 23.41626)
		(width 0.127)
		(layer "B.Cu")
		(net "PCIE_B2T_B2_TX_DN<0>")
	)
	(segment
		(start -155.8217 23.675279)
		(end -155.8217 22.9616)
		(width 0.127)
		(layer "B.Cu")
		(net "PCIE_B2T_B2_TX_DN<0>")
	)
	(segment
		(start -166.604747 17.0434)
		(end -177.8816 17.0434)
		(width 0.127)
		(layer "B.Cu")
		(net "PCIE_B2T_B2_TX_DN<0>")
	)
	(segment
		(start -177.8816 17.0434)
		(end -184.6126 23.7744)
		(width 0.127)
		(layer "B.Cu")
		(net "PCIE_B2T_B2_TX_DN<0>")
	)
	(segment
		(start -154.562599 23.822599)
		(end -155.67438 23.822599)
		(width 0.127)
		(layer "B.Cu")
		(net "PCIE_B2T_B2_TX_DN<0>")
	)
	(segment
		(start -160.231887 23.41626)
		(end -166.604747 17.0434)
		(width 0.127)
		(layer "B.Cu")
		(net "PCIE_B2T_B2_TX_DN<0>")
	)
	(segment
		(start -156.22556 22.55774)
		(end -158.33376 22.55774)
		(width 0.127)
		(layer "B.Cu")
		(net "PCIE_B2T_B2_TX_DN<0>")
	)
	(segment
		(start -184.912399 30.507602)
		(end -185.46 29.960001)
		(width 0.127)
		(layer "B.Cu")
		(net "PCIE_B2T_B2_TX_DN<0>")
	)
	(segment
		(start -370.634999 27.784999)
		(end -371.269999 27.149999)
		(width 0.127)
		(layer "F.Cu")
		(net "PCIE_B2T_B1_TX_DP<9>")
	)
	(via
		(at -371.269999 27.149999)
		(size 0.5588)
		(drill 0.254)
		(layers "F.Cu" "B.Cu")
		(net "PCIE_B2T_B1_TX_DP<9>")
	)
	(segment
		(start -399.5166 19.3294)
		(end -403.3266 23.1394)
		(width 0.127)
		(layer "In5.Cu")
		(net "PCIE_B2T_B1_TX_DP<9>")
	)
	(segment
		(start -403.575469 27.906053)
		(end -403.90605 27.906053)
		(width 0.127)
		(layer "In5.Cu")
		(net "PCIE_B2T_B1_TX_DP<9>")
	)
	(segment
		(start -382.195413 25.37968)
		(end -388.245693 19.3294)
		(width 0.127)
		(layer "In5.Cu")
		(net "PCIE_B2T_B1_TX_DP<9>")
	)
	(segment
		(start -373.030811 26.661049)
		(end -373.3165 26.37536)
		(width 0.127)
		(layer "In5.Cu")
		(net "PCIE_B2T_B1_TX_DP<9>")
	)
	(segment
		(start -373.3165 25.58288)
		(end -373.5197 25.37968)
		(width 0.127)
		(layer "In5.Cu")
		(net "PCIE_B2T_B1_TX_DP<9>")
	)
	(segment
		(start -403.3266 23.1394)
		(end -403.3266 27.657184)
		(width 0.127)
		(layer "In5.Cu")
		(net "PCIE_B2T_B1_TX_DP<9>")
	)
	(segment
		(start -388.245693 19.3294)
		(end -399.5166 19.3294)
		(width 0.127)
		(layer "In5.Cu")
		(net "PCIE_B2T_B1_TX_DP<9>")
	)
	(segment
		(start -371.758949 26.661049)
		(end -373.030811 26.661049)
		(width 0.127)
		(layer "In5.Cu")
		(net "PCIE_B2T_B1_TX_DP<9>")
	)
	(segment
		(start -373.3165 26.37536)
		(end -373.3165 25.58288)
		(width 0.127)
		(layer "In5.Cu")
		(net "PCIE_B2T_B1_TX_DP<9>")
	)
	(segment
		(start -373.5197 25.37968)
		(end -382.195413 25.37968)
		(width 0.127)
		(layer "In5.Cu")
		(net "PCIE_B2T_B1_TX_DP<9>")
	)
	(segment
		(start -403.3266 27.657184)
		(end -403.575469 27.906053)
		(width 0.127)
		(layer "In5.Cu")
		(net "PCIE_B2T_B1_TX_DP<9>")
	)
	(segment
		(start -371.269999 27.149999)
		(end -371.758949 26.661049)
		(width 0.127)
		(layer "In5.Cu")
		(net "PCIE_B2T_B1_TX_DP<9>")
	)
	(segment
		(start -403.90605 27.906053)
		(end -404.459999 28.460002)
		(width 0.127)
		(layer "In5.Cu")
		(net "PCIE_B2T_B1_TX_DP<9>")
	)
	(segment
		(start -371.904999 25.244999)
		(end -372.539999 24.609999)
		(width 0.127)
		(layer "F.Cu")
		(net "PCIE_B2T_B1_TX_DP<8>")
	)
	(via
		(at -372.539999 24.609999)
		(size 0.5588)
		(drill 0.254)
		(layers "F.Cu" "B.Cu")
		(net "PCIE_B2T_B1_TX_DP<8>")
	)
	(segment
		(start -379.98908 23.72106)
		(end -382.380833 23.72106)
		(width 0.127)
		(layer "In5.Cu")
		(net "PCIE_B2T_B1_TX_DP<8>")
	)
	(segment
		(start -405.298793 22.520793)
		(end -405.298793 26.235645)
		(width 0.127)
		(layer "In5.Cu")
		(net "PCIE_B2T_B1_TX_DP<8>")
	)
	(segment
		(start -405.906051 26.606053)
		(end -406.46 27.160002)
		(width 0.127)
		(layer "In5.Cu")
		(net "PCIE_B2T_B1_TX_DP<8>")
	)
	(segment
		(start -405.298793 26.235645)
		(end -405.669201 26.606053)
		(width 0.127)
		(layer "In5.Cu")
		(net "PCIE_B2T_B1_TX_DP<8>")
	)
	(segment
		(start -372.539999 24.609999)
		(end -373.028949 24.121049)
		(width 0.127)
		(layer "In5.Cu")
		(net "PCIE_B2T_B1_TX_DP<8>")
	)
	(segment
		(start -374.300811 24.121049)
		(end -374.5865 23.83536)
		(width 0.127)
		(layer "In5.Cu")
		(net "PCIE_B2T_B1_TX_DP<8>")
	)
	(segment
		(start -374.5865 23.04288)
		(end -374.7897 22.83968)
		(width 0.127)
		(layer "In5.Cu")
		(net "PCIE_B2T_B1_TX_DP<8>")
	)
	(segment
		(start -373.028949 24.121049)
		(end -374.300811 24.121049)
		(width 0.127)
		(layer "In5.Cu")
		(net "PCIE_B2T_B1_TX_DP<8>")
	)
	(segment
		(start -405.669201 26.606053)
		(end -405.906051 26.606053)
		(width 0.127)
		(layer "In5.Cu")
		(net "PCIE_B2T_B1_TX_DP<8>")
	)
	(segment
		(start -401.066 18.288)
		(end -405.298793 22.520793)
		(width 0.127)
		(layer "In5.Cu")
		(net "PCIE_B2T_B1_TX_DP<8>")
	)
	(segment
		(start -382.380833 23.72106)
		(end -387.813893 18.288)
		(width 0.127)
		(layer "In5.Cu")
		(net "PCIE_B2T_B1_TX_DP<8>")
	)
	(segment
		(start -374.7897 22.83968)
		(end -379.1077 22.83968)
		(width 0.127)
		(layer "In5.Cu")
		(net "PCIE_B2T_B1_TX_DP<8>")
	)
	(segment
		(start -379.1077 22.83968)
		(end -379.98908 23.72106)
		(width 0.127)
		(layer "In5.Cu")
		(net "PCIE_B2T_B1_TX_DP<8>")
	)
	(segment
		(start -387.813893 18.288)
		(end -401.066 18.288)
		(width 0.127)
		(layer "In5.Cu")
		(net "PCIE_B2T_B1_TX_DP<8>")
	)
	(segment
		(start -374.5865 23.83536)
		(end -374.5865 23.04288)
		(width 0.127)
		(layer "In5.Cu")
		(net "PCIE_B2T_B1_TX_DP<8>")
	)
	(segment
		(start -373.174999 43.024999)
		(end -373.809999 42.389999)
		(width 0.127)
		(layer "F.Cu")
		(net "PCIE_B2T_B1_TX_DP<7>")
	)
	(via
		(at -373.809999 42.389999)
		(size 0.5588)
		(drill 0.254)
		(layers "F.Cu" "B.Cu")
		(net "PCIE_B2T_B1_TX_DP<7>")
	)
	(segment
		(start -375.530633 41.907399)
		(end -375.8565 41.581532)
		(width 0.127)
		(layer "B.Cu")
		(net "PCIE_B2T_B1_TX_DP<7>")
	)
	(segment
		(start -391.912401 32.112402)
		(end -392.46 32.660001)
		(width 0.127)
		(layer "B.Cu")
		(net "PCIE_B2T_B1_TX_DP<7>")
	)
	(segment
		(start -389.933251 32.112402)
		(end -391.912401 32.112402)
		(width 0.127)
		(layer "B.Cu")
		(net "PCIE_B2T_B1_TX_DP<7>")
	)
	(segment
		(start -382.24714 38.183073)
		(end -382.24714 37.428693)
		(width 0.127)
		(layer "B.Cu")
		(net "PCIE_B2T_B1_TX_DP<7>")
	)
	(segment
		(start -375.8565 40.867853)
		(end -376.081813 40.64254)
		(width 0.127)
		(layer "B.Cu")
		(net "PCIE_B2T_B1_TX_DP<7>")
	)
	(segment
		(start -384.928633 34.7472)
		(end -387.298453 34.7472)
		(width 0.127)
		(layer "B.Cu")
		(net "PCIE_B2T_B1_TX_DP<7>")
	)
	(segment
		(start -379.787673 40.64254)
		(end -382.24714 38.183073)
		(width 0.127)
		(layer "B.Cu")
		(net "PCIE_B2T_B1_TX_DP<7>")
	)
	(segment
		(start -373.809999 42.389999)
		(end -374.292599 41.907399)
		(width 0.127)
		(layer "B.Cu")
		(net "PCIE_B2T_B1_TX_DP<7>")
	)
	(segment
		(start -382.24714 37.428693)
		(end -384.928633 34.7472)
		(width 0.127)
		(layer "B.Cu")
		(net "PCIE_B2T_B1_TX_DP<7>")
	)
	(segment
		(start -387.298453 34.7472)
		(end -389.933251 32.112402)
		(width 0.127)
		(layer "B.Cu")
		(net "PCIE_B2T_B1_TX_DP<7>")
	)
	(segment
		(start -374.292599 41.907399)
		(end -375.530633 41.907399)
		(width 0.127)
		(layer "B.Cu")
		(net "PCIE_B2T_B1_TX_DP<7>")
	)
	(segment
		(start -375.8565 41.581532)
		(end -375.8565 40.867853)
		(width 0.127)
		(layer "B.Cu")
		(net "PCIE_B2T_B1_TX_DP<7>")
	)
	(segment
		(start -376.081813 40.64254)
		(end -379.787673 40.64254)
		(width 0.127)
		(layer "B.Cu")
		(net "PCIE_B2T_B1_TX_DP<7>")
	)
	(segment
		(start -374.444999 40.484999)
		(end -375.079999 39.849999)
		(width 0.127)
		(layer "F.Cu")
		(net "PCIE_B2T_B1_TX_DP<6>")
	)
	(via
		(at -375.079999 39.849999)
		(size 0.5588)
		(drill 0.254)
		(layers "F.Cu" "B.Cu")
		(net "PCIE_B2T_B1_TX_DP<6>")
	)
	(segment
		(start -381.06858 36.979113)
		(end -381.06858 36.760673)
		(width 0.127)
		(layer "B.Cu")
		(net "PCIE_B2T_B1_TX_DP<6>")
	)
	(segment
		(start -392.862547 24.8158)
		(end -393.2982 25.251453)
		(width 0.127)
		(layer "B.Cu")
		(net "PCIE_B2T_B1_TX_DP<6>")
	)
	(segment
		(start -393.2982 25.251453)
		(end -393.2982 30.515209)
		(width 0.127)
		(layer "B.Cu")
		(net "PCIE_B2T_B1_TX_DP<6>")
	)
	(segment
		(start -377.351813 38.10254)
		(end -378.184933 38.10254)
		(width 0.127)
		(layer "B.Cu")
		(net "PCIE_B2T_B1_TX_DP<6>")
	)
	(segment
		(start -375.079999 39.849999)
		(end -375.562599 39.367399)
		(width 0.127)
		(layer "B.Cu")
		(net "PCIE_B2T_B1_TX_DP<6>")
	)
	(segment
		(start -378.184933 38.10254)
		(end -378.832633 37.45484)
		(width 0.127)
		(layer "B.Cu")
		(net "PCIE_B2T_B1_TX_DP<6>")
	)
	(segment
		(start -392.575651 24.821802)
		(end -392.581653 24.8158)
		(width 0.127)
		(layer "B.Cu")
		(net "PCIE_B2T_B1_TX_DP<6>")
	)
	(segment
		(start -375.562599 39.367399)
		(end -376.800633 39.367399)
		(width 0.127)
		(layer "B.Cu")
		(net "PCIE_B2T_B1_TX_DP<6>")
	)
	(segment
		(start -380.592853 37.45484)
		(end -381.06858 36.979113)
		(width 0.127)
		(layer "B.Cu")
		(net "PCIE_B2T_B1_TX_DP<6>")
	)
	(segment
		(start -378.832633 37.45484)
		(end -380.592853 37.45484)
		(width 0.127)
		(layer "B.Cu")
		(net "PCIE_B2T_B1_TX_DP<6>")
	)
	(segment
		(start -393.912402 30.812402)
		(end -394.460001 31.360001)
		(width 0.127)
		(layer "B.Cu")
		(net "PCIE_B2T_B1_TX_DP<6>")
	)
	(segment
		(start -391.6218 25.312771)
		(end -392.112769 24.821802)
		(width 0.127)
		(layer "B.Cu")
		(net "PCIE_B2T_B1_TX_DP<6>")
	)
	(segment
		(start -392.112769 24.821802)
		(end -392.575651 24.821802)
		(width 0.127)
		(layer "B.Cu")
		(net "PCIE_B2T_B1_TX_DP<6>")
	)
	(segment
		(start -377.1265 39.041532)
		(end -377.1265 38.327853)
		(width 0.127)
		(layer "B.Cu")
		(net "PCIE_B2T_B1_TX_DP<6>")
	)
	(segment
		(start -393.2982 30.515209)
		(end -393.595393 30.812402)
		(width 0.127)
		(layer "B.Cu")
		(net "PCIE_B2T_B1_TX_DP<6>")
	)
	(segment
		(start -377.1265 38.327853)
		(end -377.351813 38.10254)
		(width 0.127)
		(layer "B.Cu")
		(net "PCIE_B2T_B1_TX_DP<6>")
	)
	(segment
		(start -393.595393 30.812402)
		(end -393.912402 30.812402)
		(width 0.127)
		(layer "B.Cu")
		(net "PCIE_B2T_B1_TX_DP<6>")
	)
	(segment
		(start -376.800633 39.367399)
		(end -377.1265 39.041532)
		(width 0.127)
		(layer "B.Cu")
		(net "PCIE_B2T_B1_TX_DP<6>")
	)
	(segment
		(start -392.581653 24.8158)
		(end -392.862547 24.8158)
		(width 0.127)
		(layer "B.Cu")
		(net "PCIE_B2T_B1_TX_DP<6>")
	)
	(segment
		(start -381.06858 36.760673)
		(end -391.6218 26.207453)
		(width 0.127)
		(layer "B.Cu")
		(net "PCIE_B2T_B1_TX_DP<6>")
	)
	(segment
		(start -391.6218 26.207453)
		(end -391.6218 25.312771)
		(width 0.127)
		(layer "B.Cu")
		(net "PCIE_B2T_B1_TX_DP<6>")
	)
	(segment
		(start -373.174999 37.944999)
		(end -373.809999 37.309999)
		(width 0.127)
		(layer "F.Cu")
		(net "PCIE_B2T_B1_TX_DP<5>")
	)
	(via
		(at -373.809999 37.309999)
		(size 0.5588)
		(drill 0.254)
		(layers "F.Cu" "B.Cu")
		(net "PCIE_B2T_B1_TX_DP<5>")
	)
	(segment
		(start -375.8565 35.787853)
		(end -375.8565 36.501532)
		(width 0.127)
		(layer "B.Cu")
		(net "PCIE_B2T_B1_TX_DP<5>")
	)
	(segment
		(start -381.083073 33.7693)
		(end -379.289833 35.56254)
		(width 0.127)
		(layer "B.Cu")
		(net "PCIE_B2T_B1_TX_DP<5>")
	)
	(segment
		(start -388.9756 26.135853)
		(end -388.9756 27.085813)
		(width 0.127)
		(layer "B.Cu")
		(net "PCIE_B2T_B1_TX_DP<5>")
	)
	(segment
		(start -379.289833 35.56254)
		(end -376.081813 35.56254)
		(width 0.127)
		(layer "B.Cu")
		(net "PCIE_B2T_B1_TX_DP<5>")
	)
	(segment
		(start -395.640065 32.112402)
		(end -395.3002 31.772537)
		(width 0.127)
		(layer "B.Cu")
		(net "PCIE_B2T_B1_TX_DP<5>")
	)
	(segment
		(start -396.46 32.660001)
		(end -395.912401 32.112402)
		(width 0.127)
		(layer "B.Cu")
		(net "PCIE_B2T_B1_TX_DP<5>")
	)
	(segment
		(start -375.8565 36.501532)
		(end -375.530633 36.827399)
		(width 0.127)
		(layer "B.Cu")
		(net "PCIE_B2T_B1_TX_DP<5>")
	)
	(segment
		(start -395.3002 31.772537)
		(end -395.3002 24.027567)
		(width 0.127)
		(layer "B.Cu")
		(net "PCIE_B2T_B1_TX_DP<5>")
	)
	(segment
		(start -395.298201 24.025568)
		(end -395.298201 24.012771)
		(width 0.127)
		(layer "B.Cu")
		(net "PCIE_B2T_B1_TX_DP<5>")
	)
	(segment
		(start -374.292599 36.827399)
		(end -373.809999 37.309999)
		(width 0.127)
		(layer "B.Cu")
		(net "PCIE_B2T_B1_TX_DP<5>")
	)
	(segment
		(start -391.589651 23.521802)
		(end -388.9756 26.135853)
		(width 0.127)
		(layer "B.Cu")
		(net "PCIE_B2T_B1_TX_DP<5>")
	)
	(segment
		(start -395.298201 24.012771)
		(end -394.807232 23.521802)
		(width 0.127)
		(layer "B.Cu")
		(net "PCIE_B2T_B1_TX_DP<5>")
	)
	(segment
		(start -382.292113 33.7693)
		(end -381.083073 33.7693)
		(width 0.127)
		(layer "B.Cu")
		(net "PCIE_B2T_B1_TX_DP<5>")
	)
	(segment
		(start -375.530633 36.827399)
		(end -374.292599 36.827399)
		(width 0.127)
		(layer "B.Cu")
		(net "PCIE_B2T_B1_TX_DP<5>")
	)
	(segment
		(start -388.9756 27.085813)
		(end -382.292113 33.7693)
		(width 0.127)
		(layer "B.Cu")
		(net "PCIE_B2T_B1_TX_DP<5>")
	)
	(segment
		(start -395.912401 32.112402)
		(end -395.640065 32.112402)
		(width 0.127)
		(layer "B.Cu")
		(net "PCIE_B2T_B1_TX_DP<5>")
	)
	(segment
		(start -394.807232 23.521802)
		(end -391.589651 23.521802)
		(width 0.127)
		(layer "B.Cu")
		(net "PCIE_B2T_B1_TX_DP<5>")
	)
	(segment
		(start -376.081813 35.56254)
		(end -375.8565 35.787853)
		(width 0.127)
		(layer "B.Cu")
		(net "PCIE_B2T_B1_TX_DP<5>")
	)
	(segment
		(start -395.3002 24.027567)
		(end -395.298201 24.025568)
		(width 0.127)
		(layer "B.Cu")
		(net "PCIE_B2T_B1_TX_DP<5>")
	)
	(segment
		(start -374.444999 35.404999)
		(end -375.079999 34.769999)
		(width 0.127)
		(layer "F.Cu")
		(net "PCIE_B2T_B1_TX_DP<4>")
	)
	(via
		(at -375.079999 34.769999)
		(size 0.5588)
		(drill 0.254)
		(layers "F.Cu" "B.Cu")
		(net "PCIE_B2T_B1_TX_DP<4>")
	)
	(segment
		(start -397.3068 30.443251)
		(end -397.3068 24.180053)
		(width 0.127)
		(layer "B.Cu")
		(net "PCIE_B2T_B1_TX_DP<4>")
	)
	(segment
		(start -390.956053 22.3012)
		(end -386.7912 26.466053)
		(width 0.127)
		(layer "B.Cu")
		(net "PCIE_B2T_B1_TX_DP<4>")
	)
	(segment
		(start -397.912402 30.812402)
		(end -397.675951 30.812402)
		(width 0.127)
		(layer "B.Cu")
		(net "PCIE_B2T_B1_TX_DP<4>")
	)
	(segment
		(start -377.351813 33.02254)
		(end -377.1265 33.247853)
		(width 0.127)
		(layer "B.Cu")
		(net "PCIE_B2T_B1_TX_DP<4>")
	)
	(segment
		(start -379.632733 32.385)
		(end -378.995193 33.02254)
		(width 0.127)
		(layer "B.Cu")
		(net "PCIE_B2T_B1_TX_DP<4>")
	)
	(segment
		(start -397.3068 24.180053)
		(end -395.427947 22.3012)
		(width 0.127)
		(layer "B.Cu")
		(net "PCIE_B2T_B1_TX_DP<4>")
	)
	(segment
		(start -375.562599 34.287399)
		(end -375.079999 34.769999)
		(width 0.127)
		(layer "B.Cu")
		(net "PCIE_B2T_B1_TX_DP<4>")
	)
	(segment
		(start -377.1265 33.247853)
		(end -377.1265 33.961532)
		(width 0.127)
		(layer "B.Cu")
		(net "PCIE_B2T_B1_TX_DP<4>")
	)
	(segment
		(start -378.995193 33.02254)
		(end -377.351813 33.02254)
		(width 0.127)
		(layer "B.Cu")
		(net "PCIE_B2T_B1_TX_DP<4>")
	)
	(segment
		(start -376.800633 34.287399)
		(end -375.562599 34.287399)
		(width 0.127)
		(layer "B.Cu")
		(net "PCIE_B2T_B1_TX_DP<4>")
	)
	(segment
		(start -398.460001 31.360001)
		(end -397.912402 30.812402)
		(width 0.127)
		(layer "B.Cu")
		(net "PCIE_B2T_B1_TX_DP<4>")
	)
	(segment
		(start -377.1265 33.961532)
		(end -376.800633 34.287399)
		(width 0.127)
		(layer "B.Cu")
		(net "PCIE_B2T_B1_TX_DP<4>")
	)
	(segment
		(start -381.837453 32.385)
		(end -379.632733 32.385)
		(width 0.127)
		(layer "B.Cu")
		(net "PCIE_B2T_B1_TX_DP<4>")
	)
	(segment
		(start -386.7912 27.431253)
		(end -381.837453 32.385)
		(width 0.127)
		(layer "B.Cu")
		(net "PCIE_B2T_B1_TX_DP<4>")
	)
	(segment
		(start -397.675951 30.812402)
		(end -397.3068 30.443251)
		(width 0.127)
		(layer "B.Cu")
		(net "PCIE_B2T_B1_TX_DP<4>")
	)
	(segment
		(start -395.427947 22.3012)
		(end -390.956053 22.3012)
		(width 0.127)
		(layer "B.Cu")
		(net "PCIE_B2T_B1_TX_DP<4>")
	)
	(segment
		(start -386.7912 26.466053)
		(end -386.7912 27.431253)
		(width 0.127)
		(layer "B.Cu")
		(net "PCIE_B2T_B1_TX_DP<4>")
	)
	(segment
		(start -373.174999 32.864999)
		(end -373.809999 32.229999)
		(width 0.127)
		(layer "F.Cu")
		(net "PCIE_B2T_B1_TX_DP<3>")
	)
	(via
		(at -373.809999 32.229999)
		(size 0.5588)
		(drill 0.254)
		(layers "F.Cu" "B.Cu")
		(net "PCIE_B2T_B1_TX_DP<3>")
	)
	(segment
		(start -375.8565 31.421532)
		(end -375.8565 30.707853)
		(width 0.127)
		(layer "B.Cu")
		(net "PCIE_B2T_B1_TX_DP<3>")
	)
	(segment
		(start -376.081813 30.48254)
		(end -381.32766 30.48254)
		(width 0.127)
		(layer "B.Cu")
		(net "PCIE_B2T_B1_TX_DP<3>")
	)
	(segment
		(start -375.8565 30.707853)
		(end -376.081813 30.48254)
		(width 0.127)
		(layer "B.Cu")
		(net "PCIE_B2T_B1_TX_DP<3>")
	)
	(segment
		(start -390.802719 21.081815)
		(end -390.802904 21.082)
		(width 0.127)
		(layer "B.Cu")
		(net "PCIE_B2T_B1_TX_DP<3>")
	)
	(segment
		(start -399.3134 31.766657)
		(end -399.659145 32.112402)
		(width 0.127)
		(layer "B.Cu")
		(net "PCIE_B2T_B1_TX_DP<3>")
	)
	(segment
		(start -390.802904 21.082)
		(end -396.494749 21.082)
		(width 0.127)
		(layer "B.Cu")
		(net "PCIE_B2T_B1_TX_DP<3>")
	)
	(segment
		(start -375.530633 31.747399)
		(end -375.8565 31.421532)
		(width 0.127)
		(layer "B.Cu")
		(net "PCIE_B2T_B1_TX_DP<3>")
	)
	(segment
		(start -381.32766 30.48254)
		(end -384.3274 27.4828)
		(width 0.127)
		(layer "B.Cu")
		(net "PCIE_B2T_B1_TX_DP<3>")
	)
	(segment
		(start -396.494749 21.082)
		(end -399.3134 23.900651)
		(width 0.127)
		(layer "B.Cu")
		(net "PCIE_B2T_B1_TX_DP<3>")
	)
	(segment
		(start -390.0424 21.082)
		(end -390.04539 21.082)
		(width 0.127)
		(layer "B.Cu")
		(net "PCIE_B2T_B1_TX_DP<3>")
	)
	(segment
		(start -374.292599 31.747399)
		(end -375.530633 31.747399)
		(width 0.127)
		(layer "B.Cu")
		(net "PCIE_B2T_B1_TX_DP<3>")
	)
	(segment
		(start -384.3274 26.797)
		(end -390.0424 21.082)
		(width 0.127)
		(layer "B.Cu")
		(net "PCIE_B2T_B1_TX_DP<3>")
	)
	(segment
		(start -399.912401 32.112402)
		(end -400.459999 32.660001)
		(width 0.127)
		(layer "B.Cu")
		(net "PCIE_B2T_B1_TX_DP<3>")
	)
	(segment
		(start -384.3274 27.4828)
		(end -384.3274 26.797)
		(width 0.127)
		(layer "B.Cu")
		(net "PCIE_B2T_B1_TX_DP<3>")
	)
	(segment
		(start -399.3134 23.900651)
		(end -399.3134 31.766657)
		(width 0.127)
		(layer "B.Cu")
		(net "PCIE_B2T_B1_TX_DP<3>")
	)
	(segment
		(start -399.659145 32.112402)
		(end -399.912401 32.112402)
		(width 0.127)
		(layer "B.Cu")
		(net "PCIE_B2T_B1_TX_DP<3>")
	)
	(segment
		(start -390.045575 21.081815)
		(end -390.802719 21.081815)
		(width 0.127)
		(layer "B.Cu")
		(net "PCIE_B2T_B1_TX_DP<3>")
	)
	(segment
		(start -390.04539 21.082)
		(end -390.045575 21.081815)
		(width 0.127)
		(layer "B.Cu")
		(net "PCIE_B2T_B1_TX_DP<3>")
	)
	(segment
		(start -373.809999 32.229999)
		(end -374.292599 31.747399)
		(width 0.127)
		(layer "B.Cu")
		(net "PCIE_B2T_B1_TX_DP<3>")
	)
	(segment
		(start -374.444999 30.324999)
		(end -375.079999 29.689999)
		(width 0.127)
		(layer "F.Cu")
		(net "PCIE_B2T_B1_TX_DP<2>")
	)
	(via
		(at -375.079999 29.689999)
		(size 0.5588)
		(drill 0.254)
		(layers "F.Cu" "B.Cu")
		(net "PCIE_B2T_B1_TX_DP<2>")
	)
	(segment
		(start -377.1265 28.167853)
		(end -377.1265 28.881532)
		(width 0.127)
		(layer "B.Cu")
		(net "PCIE_B2T_B1_TX_DP<2>")
	)
	(segment
		(start -402.46 31.360001)
		(end -401.912402 30.812402)
		(width 0.127)
		(layer "B.Cu")
		(net "PCIE_B2T_B1_TX_DP<2>")
	)
	(segment
		(start -401.912402 30.812402)
		(end -401.659146 30.812402)
		(width 0.127)
		(layer "B.Cu")
		(net "PCIE_B2T_B1_TX_DP<2>")
	)
	(segment
		(start -397.104347 19.812)
		(end -389.1788 19.812)
		(width 0.127)
		(layer "B.Cu")
		(net "PCIE_B2T_B1_TX_DP<2>")
	)
	(segment
		(start -379.112033 27.29992)
		(end -378.469413 27.94254)
		(width 0.127)
		(layer "B.Cu")
		(net "PCIE_B2T_B1_TX_DP<2>")
	)
	(segment
		(start -377.1265 28.881532)
		(end -376.800633 29.207399)
		(width 0.127)
		(layer "B.Cu")
		(net "PCIE_B2T_B1_TX_DP<2>")
	)
	(segment
		(start -381.69088 27.29992)
		(end -379.112033 27.29992)
		(width 0.127)
		(layer "B.Cu")
		(net "PCIE_B2T_B1_TX_DP<2>")
	)
	(segment
		(start -389.1788 19.812)
		(end -381.69088 27.29992)
		(width 0.127)
		(layer "B.Cu")
		(net "PCIE_B2T_B1_TX_DP<2>")
	)
	(segment
		(start -401.659146 30.812402)
		(end -401.298199 30.451455)
		(width 0.127)
		(layer "B.Cu")
		(net "PCIE_B2T_B1_TX_DP<2>")
	)
	(segment
		(start -378.469413 27.94254)
		(end -377.351813 27.94254)
		(width 0.127)
		(layer "B.Cu")
		(net "PCIE_B2T_B1_TX_DP<2>")
	)
	(segment
		(start -401.298199 30.451455)
		(end -401.298199 25.312685)
		(width 0.127)
		(layer "B.Cu")
		(net "PCIE_B2T_B1_TX_DP<2>")
	)
	(segment
		(start -401.298199 25.312685)
		(end -401.2946 25.309086)
		(width 0.127)
		(layer "B.Cu")
		(net "PCIE_B2T_B1_TX_DP<2>")
	)
	(segment
		(start -401.2946 24.002253)
		(end -397.104347 19.812)
		(width 0.127)
		(layer "B.Cu")
		(net "PCIE_B2T_B1_TX_DP<2>")
	)
	(segment
		(start -376.800633 29.207399)
		(end -375.562599 29.207399)
		(width 0.127)
		(layer "B.Cu")
		(net "PCIE_B2T_B1_TX_DP<2>")
	)
	(segment
		(start -401.2946 25.309086)
		(end -401.2946 24.002253)
		(width 0.127)
		(layer "B.Cu")
		(net "PCIE_B2T_B1_TX_DP<2>")
	)
	(segment
		(start -377.351813 27.94254)
		(end -377.1265 28.167853)
		(width 0.127)
		(layer "B.Cu")
		(net "PCIE_B2T_B1_TX_DP<2>")
	)
	(segment
		(start -375.562599 29.207399)
		(end -375.079999 29.689999)
		(width 0.127)
		(layer "B.Cu")
		(net "PCIE_B2T_B1_TX_DP<2>")
	)
	(segment
		(start -373.174999 27.784999)
		(end -373.809999 27.149999)
		(width 0.127)
		(layer "F.Cu")
		(net "PCIE_B2T_B1_TX_DP<1>")
	)
	(via
		(at -373.809999 27.149999)
		(size 0.5588)
		(drill 0.254)
		(layers "F.Cu" "B.Cu")
		(net "PCIE_B2T_B1_TX_DP<1>")
	)
	(segment
		(start -398.069547 18.5674)
		(end -403.3012 23.799053)
		(width 0.127)
		(layer "B.Cu")
		(net "PCIE_B2T_B1_TX_DP<1>")
	)
	(segment
		(start -376.081813 25.40254)
		(end -381.73406 25.40254)
		(width 0.127)
		(layer "B.Cu")
		(net "PCIE_B2T_B1_TX_DP<1>")
	)
	(segment
		(start -388.5692 18.5674)
		(end -398.069547 18.5674)
		(width 0.127)
		(layer "B.Cu")
		(net "PCIE_B2T_B1_TX_DP<1>")
	)
	(segment
		(start -374.292599 26.667399)
		(end -375.530633 26.667399)
		(width 0.127)
		(layer "B.Cu")
		(net "PCIE_B2T_B1_TX_DP<1>")
	)
	(segment
		(start -403.3012 31.838095)
		(end -403.575507 32.112402)
		(width 0.127)
		(layer "B.Cu")
		(net "PCIE_B2T_B1_TX_DP<1>")
	)
	(segment
		(start -403.9124 32.112402)
		(end -404.459999 32.660001)
		(width 0.127)
		(layer "B.Cu")
		(net "PCIE_B2T_B1_TX_DP<1>")
	)
	(segment
		(start -375.8565 26.341532)
		(end -375.8565 25.627853)
		(width 0.127)
		(layer "B.Cu")
		(net "PCIE_B2T_B1_TX_DP<1>")
	)
	(segment
		(start -375.8565 25.627853)
		(end -376.081813 25.40254)
		(width 0.127)
		(layer "B.Cu")
		(net "PCIE_B2T_B1_TX_DP<1>")
	)
	(segment
		(start -381.73406 25.40254)
		(end -388.5692 18.5674)
		(width 0.127)
		(layer "B.Cu")
		(net "PCIE_B2T_B1_TX_DP<1>")
	)
	(segment
		(start -403.3012 23.799053)
		(end -403.3012 31.838095)
		(width 0.127)
		(layer "B.Cu")
		(net "PCIE_B2T_B1_TX_DP<1>")
	)
	(segment
		(start -375.530633 26.667399)
		(end -375.8565 26.341532)
		(width 0.127)
		(layer "B.Cu")
		(net "PCIE_B2T_B1_TX_DP<1>")
	)
	(segment
		(start -373.809999 27.149999)
		(end -374.292599 26.667399)
		(width 0.127)
		(layer "B.Cu")
		(net "PCIE_B2T_B1_TX_DP<1>")
	)
	(segment
		(start -403.575507 32.112402)
		(end -403.9124 32.112402)
		(width 0.127)
		(layer "B.Cu")
		(net "PCIE_B2T_B1_TX_DP<1>")
	)
	(segment
		(start -370.634999 43.024999)
		(end -371.269999 42.389999)
		(width 0.127)
		(layer "F.Cu")
		(net "PCIE_B2T_B1_TX_DP<15>")
	)
	(via
		(at -371.269999 42.389999)
		(size 0.5588)
		(drill 0.254)
		(layers "F.Cu" "B.Cu")
		(net "PCIE_B2T_B1_TX_DP<15>")
	)
	(segment
		(start -373.01424 43.069853)
		(end -373.01424 42.091953)
		(width 0.127)
		(layer "In5.Cu")
		(net "PCIE_B2T_B1_TX_DP<15>")
	)
	(segment
		(start -391.906051 27.906053)
		(end -391.779051 27.906053)
		(width 0.127)
		(layer "In5.Cu")
		(net "PCIE_B2T_B1_TX_DP<15>")
	)
	(segment
		(start -391.441033 28.244071)
		(end -391.441033 33.25366)
		(width 0.127)
		(layer "In5.Cu")
		(net "PCIE_B2T_B1_TX_DP<15>")
	)
	(segment
		(start -373.01424 42.091953)
		(end -372.823336 41.901049)
		(width 0.127)
		(layer "In5.Cu")
		(net "PCIE_B2T_B1_TX_DP<15>")
	)
	(segment
		(start -373.822887 43.8785)
		(end -373.01424 43.069853)
		(width 0.127)
		(layer "In5.Cu")
		(net "PCIE_B2T_B1_TX_DP<15>")
	)
	(segment
		(start -372.823336 41.901049)
		(end -371.758949 41.901049)
		(width 0.127)
		(layer "In5.Cu")
		(net "PCIE_B2T_B1_TX_DP<15>")
	)
	(segment
		(start -392.46 28.460002)
		(end -391.906051 27.906053)
		(width 0.127)
		(layer "In5.Cu")
		(net "PCIE_B2T_B1_TX_DP<15>")
	)
	(segment
		(start -391.0838 41.2242)
		(end -388.4295 43.8785)
		(width 0.127)
		(layer "In5.Cu")
		(net "PCIE_B2T_B1_TX_DP<15>")
	)
	(segment
		(start -388.4295 43.8785)
		(end -373.822887 43.8785)
		(width 0.127)
		(layer "In5.Cu")
		(net "PCIE_B2T_B1_TX_DP<15>")
	)
	(segment
		(start -371.758949 41.901049)
		(end -371.269999 42.389999)
		(width 0.127)
		(layer "In5.Cu")
		(net "PCIE_B2T_B1_TX_DP<15>")
	)
	(segment
		(start -391.779051 27.906053)
		(end -391.441033 28.244071)
		(width 0.127)
		(layer "In5.Cu")
		(net "PCIE_B2T_B1_TX_DP<15>")
	)
	(segment
		(start -391.441033 33.25366)
		(end -391.0838 33.610893)
		(width 0.127)
		(layer "In5.Cu")
		(net "PCIE_B2T_B1_TX_DP<15>")
	)
	(segment
		(start -391.0838 33.610893)
		(end -391.0838 41.2242)
		(width 0.127)
		(layer "In5.Cu")
		(net "PCIE_B2T_B1_TX_DP<15>")
	)
	(segment
		(start -371.904999 40.484999)
		(end -372.539999 39.849999)
		(width 0.127)
		(layer "F.Cu")
		(net "PCIE_B2T_B1_TX_DP<14>")
	)
	(via
		(at -372.539999 39.849999)
		(size 0.5588)
		(drill 0.254)
		(layers "F.Cu" "B.Cu")
		(net "PCIE_B2T_B1_TX_DP<14>")
	)
	(segment
		(start -383.168233 37.46246)
		(end -379.513173 37.46246)
		(width 0.127)
		(layer "In5.Cu")
		(net "PCIE_B2T_B1_TX_DP<14>")
	)
	(segment
		(start -393.35995 26.307946)
		(end -393.35995 25.129901)
		(width 0.127)
		(layer "In5.Cu")
		(net "PCIE_B2T_B1_TX_DP<14>")
	)
	(segment
		(start -393.35995 25.129901)
		(end -393.020448 24.7904)
		(width 0.127)
		(layer "In5.Cu")
		(net "PCIE_B2T_B1_TX_DP<14>")
	)
	(segment
		(start -389.9916 30.639093)
		(end -383.168233 37.46246)
		(width 0.127)
		(layer "In5.Cu")
		(net "PCIE_B2T_B1_TX_DP<14>")
	)
	(segment
		(start -393.020448 24.7904)
		(end -392.055693 24.7904)
		(width 0.127)
		(layer "In5.Cu")
		(net "PCIE_B2T_B1_TX_DP<14>")
	)
	(segment
		(start -393.906052 26.606053)
		(end -393.658057 26.606053)
		(width 0.127)
		(layer "In5.Cu")
		(net "PCIE_B2T_B1_TX_DP<14>")
	)
	(segment
		(start -374.5865 38.28288)
		(end -374.5865 39.07536)
		(width 0.127)
		(layer "In5.Cu")
		(net "PCIE_B2T_B1_TX_DP<14>")
	)
	(segment
		(start -394.460001 27.160002)
		(end -393.906052 26.606053)
		(width 0.127)
		(layer "In5.Cu")
		(net "PCIE_B2T_B1_TX_DP<14>")
	)
	(segment
		(start -389.9916 26.854493)
		(end -389.9916 30.639093)
		(width 0.127)
		(layer "In5.Cu")
		(net "PCIE_B2T_B1_TX_DP<14>")
	)
	(segment
		(start -379.513173 37.46246)
		(end -378.895953 38.07968)
		(width 0.127)
		(layer "In5.Cu")
		(net "PCIE_B2T_B1_TX_DP<14>")
	)
	(segment
		(start -374.7897 38.07968)
		(end -374.5865 38.28288)
		(width 0.127)
		(layer "In5.Cu")
		(net "PCIE_B2T_B1_TX_DP<14>")
	)
	(segment
		(start -374.300811 39.361049)
		(end -373.028949 39.361049)
		(width 0.127)
		(layer "In5.Cu")
		(net "PCIE_B2T_B1_TX_DP<14>")
	)
	(segment
		(start -374.5865 39.07536)
		(end -374.300811 39.361049)
		(width 0.127)
		(layer "In5.Cu")
		(net "PCIE_B2T_B1_TX_DP<14>")
	)
	(segment
		(start -373.028949 39.361049)
		(end -372.539999 39.849999)
		(width 0.127)
		(layer "In5.Cu")
		(net "PCIE_B2T_B1_TX_DP<14>")
	)
	(segment
		(start -393.658057 26.606053)
		(end -393.35995 26.307946)
		(width 0.127)
		(layer "In5.Cu")
		(net "PCIE_B2T_B1_TX_DP<14>")
	)
	(segment
		(start -378.895953 38.07968)
		(end -374.7897 38.07968)
		(width 0.127)
		(layer "In5.Cu")
		(net "PCIE_B2T_B1_TX_DP<14>")
	)
	(segment
		(start -392.055693 24.7904)
		(end -389.9916 26.854493)
		(width 0.127)
		(layer "In5.Cu")
		(net "PCIE_B2T_B1_TX_DP<14>")
	)
	(segment
		(start -370.634999 37.944999)
		(end -371.269999 37.309999)
		(width 0.127)
		(layer "F.Cu")
		(net "PCIE_B2T_B1_TX_DP<13>")
	)
	(via
		(at -371.269999 37.309999)
		(size 0.5588)
		(drill 0.254)
		(layers "F.Cu" "B.Cu")
		(net "PCIE_B2T_B1_TX_DP<13>")
	)
	(segment
		(start -395.3002 27.654946)
		(end -395.551307 27.906053)
		(width 0.127)
		(layer "In5.Cu")
		(net "PCIE_B2T_B1_TX_DP<13>")
	)
	(segment
		(start -371.758949 36.821049)
		(end -373.030811 36.821049)
		(width 0.127)
		(layer "In5.Cu")
		(net "PCIE_B2T_B1_TX_DP<13>")
	)
	(segment
		(start -395.551307 27.906053)
		(end -395.906051 27.906053)
		(width 0.127)
		(layer "In5.Cu")
		(net "PCIE_B2T_B1_TX_DP<13>")
	)
	(segment
		(start -388.6835 29.381793)
		(end -388.6835 26.587793)
		(width 0.127)
		(layer "In5.Cu")
		(net "PCIE_B2T_B1_TX_DP<13>")
	)
	(segment
		(start -373.3165 36.53536)
		(end -373.3165 35.74288)
		(width 0.127)
		(layer "In5.Cu")
		(net "PCIE_B2T_B1_TX_DP<13>")
	)
	(segment
		(start -391.750893 23.5204)
		(end -394.810907 23.5204)
		(width 0.127)
		(layer "In5.Cu")
		(net "PCIE_B2T_B1_TX_DP<13>")
	)
	(segment
		(start -395.3002 24.009693)
		(end -395.3002 27.654946)
		(width 0.127)
		(layer "In5.Cu")
		(net "PCIE_B2T_B1_TX_DP<13>")
	)
	(segment
		(start -373.5197 35.53968)
		(end -382.525613 35.53968)
		(width 0.127)
		(layer "In5.Cu")
		(net "PCIE_B2T_B1_TX_DP<13>")
	)
	(segment
		(start -373.3165 35.74288)
		(end -373.5197 35.53968)
		(width 0.127)
		(layer "In5.Cu")
		(net "PCIE_B2T_B1_TX_DP<13>")
	)
	(segment
		(start -371.269999 37.309999)
		(end -371.758949 36.821049)
		(width 0.127)
		(layer "In5.Cu")
		(net "PCIE_B2T_B1_TX_DP<13>")
	)
	(segment
		(start -382.525613 35.53968)
		(end -388.6835 29.381793)
		(width 0.127)
		(layer "In5.Cu")
		(net "PCIE_B2T_B1_TX_DP<13>")
	)
	(segment
		(start -394.810907 23.5204)
		(end -395.3002 24.009693)
		(width 0.127)
		(layer "In5.Cu")
		(net "PCIE_B2T_B1_TX_DP<13>")
	)
	(segment
		(start -395.906051 27.906053)
		(end -396.46 28.460002)
		(width 0.127)
		(layer "In5.Cu")
		(net "PCIE_B2T_B1_TX_DP<13>")
	)
	(segment
		(start -388.6835 26.587793)
		(end -391.750893 23.5204)
		(width 0.127)
		(layer "In5.Cu")
		(net "PCIE_B2T_B1_TX_DP<13>")
	)
	(segment
		(start -373.030811 36.821049)
		(end -373.3165 36.53536)
		(width 0.127)
		(layer "In5.Cu")
		(net "PCIE_B2T_B1_TX_DP<13>")
	)
	(segment
		(start -371.904999 35.404999)
		(end -372.539999 34.769999)
		(width 0.127)
		(layer "F.Cu")
		(net "PCIE_B2T_B1_TX_DP<12>")
	)
	(via
		(at -372.539999 34.769999)
		(size 0.5588)
		(drill 0.254)
		(layers "F.Cu" "B.Cu")
		(net "PCIE_B2T_B1_TX_DP<12>")
	)
	(segment
		(start -397.3068 26.277402)
		(end -397.3068 23.7744)
		(width 0.127)
		(layer "In5.Cu")
		(net "PCIE_B2T_B1_TX_DP<12>")
	)
	(segment
		(start -391.217493 22.479)
		(end -387.5151 26.181393)
		(width 0.127)
		(layer "In5.Cu")
		(net "PCIE_B2T_B1_TX_DP<12>")
	)
	(segment
		(start -387.5151 27.0637)
		(end -382.21158 32.36722)
		(width 0.127)
		(layer "In5.Cu")
		(net "PCIE_B2T_B1_TX_DP<12>")
	)
	(segment
		(start -387.5151 26.181393)
		(end -387.5151 27.0637)
		(width 0.127)
		(layer "In5.Cu")
		(net "PCIE_B2T_B1_TX_DP<12>")
	)
	(segment
		(start -396.0114 22.479)
		(end -391.217493 22.479)
		(width 0.127)
		(layer "In5.Cu")
		(net "PCIE_B2T_B1_TX_DP<12>")
	)
	(segment
		(start -378.789273 32.99968)
		(end -374.7897 32.99968)
		(width 0.127)
		(layer "In5.Cu")
		(net "PCIE_B2T_B1_TX_DP<12>")
	)
	(segment
		(start -374.300811 34.281049)
		(end -373.028949 34.281049)
		(width 0.127)
		(layer "In5.Cu")
		(net "PCIE_B2T_B1_TX_DP<12>")
	)
	(segment
		(start -382.21158 32.36722)
		(end -379.421733 32.36722)
		(width 0.127)
		(layer "In5.Cu")
		(net "PCIE_B2T_B1_TX_DP<12>")
	)
	(segment
		(start -397.906052 26.606053)
		(end -397.635451 26.606053)
		(width 0.127)
		(layer "In5.Cu")
		(net "PCIE_B2T_B1_TX_DP<12>")
	)
	(segment
		(start -398.460001 27.160002)
		(end -397.906052 26.606053)
		(width 0.127)
		(layer "In5.Cu")
		(net "PCIE_B2T_B1_TX_DP<12>")
	)
	(segment
		(start -374.5865 33.20288)
		(end -374.5865 33.99536)
		(width 0.127)
		(layer "In5.Cu")
		(net "PCIE_B2T_B1_TX_DP<12>")
	)
	(segment
		(start -397.635451 26.606053)
		(end -397.3068 26.277402)
		(width 0.127)
		(layer "In5.Cu")
		(net "PCIE_B2T_B1_TX_DP<12>")
	)
	(segment
		(start -373.028949 34.281049)
		(end -372.539999 34.769999)
		(width 0.127)
		(layer "In5.Cu")
		(net "PCIE_B2T_B1_TX_DP<12>")
	)
	(segment
		(start -374.7897 32.99968)
		(end -374.5865 33.20288)
		(width 0.127)
		(layer "In5.Cu")
		(net "PCIE_B2T_B1_TX_DP<12>")
	)
	(segment
		(start -397.3068 23.7744)
		(end -396.0114 22.479)
		(width 0.127)
		(layer "In5.Cu")
		(net "PCIE_B2T_B1_TX_DP<12>")
	)
	(segment
		(start -374.5865 33.99536)
		(end -374.300811 34.281049)
		(width 0.127)
		(layer "In5.Cu")
		(net "PCIE_B2T_B1_TX_DP<12>")
	)
	(segment
		(start -379.421733 32.36722)
		(end -378.789273 32.99968)
		(width 0.127)
		(layer "In5.Cu")
		(net "PCIE_B2T_B1_TX_DP<12>")
	)
	(segment
		(start -370.634999 32.864999)
		(end -371.269999 32.229999)
		(width 0.127)
		(layer "F.Cu")
		(net "PCIE_B2T_B1_TX_DP<11>")
	)
	(via
		(at -371.269999 32.229999)
		(size 0.5588)
		(drill 0.254)
		(layers "F.Cu" "B.Cu")
		(net "PCIE_B2T_B1_TX_DP<11>")
	)
	(segment
		(start -373.5197 30.45968)
		(end -381.712813 30.45968)
		(width 0.127)
		(layer "In5.Cu")
		(net "PCIE_B2T_B1_TX_DP<11>")
	)
	(segment
		(start -371.269999 32.229999)
		(end -371.758949 31.741049)
		(width 0.127)
		(layer "In5.Cu")
		(net "PCIE_B2T_B1_TX_DP<11>")
	)
	(segment
		(start -373.030811 31.741049)
		(end -373.3165 31.45536)
		(width 0.127)
		(layer "In5.Cu")
		(net "PCIE_B2T_B1_TX_DP<11>")
	)
	(segment
		(start -396.919107 21.4122)
		(end -399.3134 23.806493)
		(width 0.127)
		(layer "In5.Cu")
		(net "PCIE_B2T_B1_TX_DP<11>")
	)
	(segment
		(start -399.906051 27.906053)
		(end -400.459999 28.460002)
		(width 0.127)
		(layer "In5.Cu")
		(net "PCIE_B2T_B1_TX_DP<11>")
	)
	(segment
		(start -399.59694 27.906053)
		(end -399.906051 27.906053)
		(width 0.127)
		(layer "In5.Cu")
		(net "PCIE_B2T_B1_TX_DP<11>")
	)
	(segment
		(start -373.3165 30.66288)
		(end -373.5197 30.45968)
		(width 0.127)
		(layer "In5.Cu")
		(net "PCIE_B2T_B1_TX_DP<11>")
	)
	(segment
		(start -381.712813 30.45968)
		(end -390.760293 21.4122)
		(width 0.127)
		(layer "In5.Cu")
		(net "PCIE_B2T_B1_TX_DP<11>")
	)
	(segment
		(start -399.3134 23.806493)
		(end -399.3134 27.622513)
		(width 0.127)
		(layer "In5.Cu")
		(net "PCIE_B2T_B1_TX_DP<11>")
	)
	(segment
		(start -390.760293 21.4122)
		(end -396.919107 21.4122)
		(width 0.127)
		(layer "In5.Cu")
		(net "PCIE_B2T_B1_TX_DP<11>")
	)
	(segment
		(start -371.758949 31.741049)
		(end -373.030811 31.741049)
		(width 0.127)
		(layer "In5.Cu")
		(net "PCIE_B2T_B1_TX_DP<11>")
	)
	(segment
		(start -399.3134 27.622513)
		(end -399.59694 27.906053)
		(width 0.127)
		(layer "In5.Cu")
		(net "PCIE_B2T_B1_TX_DP<11>")
	)
	(segment
		(start -373.3165 31.45536)
		(end -373.3165 30.66288)
		(width 0.127)
		(layer "In5.Cu")
		(net "PCIE_B2T_B1_TX_DP<11>")
	)
	(segment
		(start -371.904999 30.324999)
		(end -372.539999 29.689999)
		(width 0.127)
		(layer "F.Cu")
		(net "PCIE_B2T_B1_TX_DP<10>")
	)
	(via
		(at -372.539999 29.689999)
		(size 0.5588)
		(drill 0.254)
		(layers "F.Cu" "B.Cu")
		(net "PCIE_B2T_B1_TX_DP<10>")
	)
	(segment
		(start -374.5865 28.12288)
		(end -374.5865 28.91536)
		(width 0.127)
		(layer "In5.Cu")
		(net "PCIE_B2T_B1_TX_DP<10>")
	)
	(segment
		(start -374.300811 29.201049)
		(end -373.028949 29.201049)
		(width 0.127)
		(layer "In5.Cu")
		(net "PCIE_B2T_B1_TX_DP<10>")
	)
	(segment
		(start -373.028949 29.201049)
		(end -372.539999 29.689999)
		(width 0.127)
		(layer "In5.Cu")
		(net "PCIE_B2T_B1_TX_DP<10>")
	)
	(segment
		(start -397.9418 20.3708)
		(end -390.277693 20.3708)
		(width 0.127)
		(layer "In5.Cu")
		(net "PCIE_B2T_B1_TX_DP<10>")
	)
	(segment
		(start -390.277693 20.3708)
		(end -387.071286 23.577207)
		(width 0.127)
		(layer "In5.Cu")
		(net "PCIE_B2T_B1_TX_DP<10>")
	)
	(segment
		(start -401.54687 26.606053)
		(end -401.32 26.379183)
		(width 0.127)
		(layer "In5.Cu")
		(net "PCIE_B2T_B1_TX_DP<10>")
	)
	(segment
		(start -401.32 23.749)
		(end -397.9418 20.3708)
		(width 0.127)
		(layer "In5.Cu")
		(net "PCIE_B2T_B1_TX_DP<10>")
	)
	(segment
		(start -374.5865 28.91536)
		(end -374.300811 29.201049)
		(width 0.127)
		(layer "In5.Cu")
		(net "PCIE_B2T_B1_TX_DP<10>")
	)
	(segment
		(start -387.071286 23.577207)
		(end -385.489793 23.577207)
		(width 0.127)
		(layer "In5.Cu")
		(net "PCIE_B2T_B1_TX_DP<10>")
	)
	(segment
		(start -379.134713 27.91968)
		(end -374.7897 27.91968)
		(width 0.127)
		(layer "In5.Cu")
		(net "PCIE_B2T_B1_TX_DP<10>")
	)
	(segment
		(start -402.46 27.160002)
		(end -401.906052 26.606053)
		(width 0.127)
		(layer "In5.Cu")
		(net "PCIE_B2T_B1_TX_DP<10>")
	)
	(segment
		(start -379.764633 27.28976)
		(end -379.134713 27.91968)
		(width 0.127)
		(layer "In5.Cu")
		(net "PCIE_B2T_B1_TX_DP<10>")
	)
	(segment
		(start -385.489793 23.577207)
		(end -381.77724 27.28976)
		(width 0.127)
		(layer "In5.Cu")
		(net "PCIE_B2T_B1_TX_DP<10>")
	)
	(segment
		(start -374.7897 27.91968)
		(end -374.5865 28.12288)
		(width 0.127)
		(layer "In5.Cu")
		(net "PCIE_B2T_B1_TX_DP<10>")
	)
	(segment
		(start -401.906052 26.606053)
		(end -401.54687 26.606053)
		(width 0.127)
		(layer "In5.Cu")
		(net "PCIE_B2T_B1_TX_DP<10>")
	)
	(segment
		(start -381.77724 27.28976)
		(end -379.764633 27.28976)
		(width 0.127)
		(layer "In5.Cu")
		(net "PCIE_B2T_B1_TX_DP<10>")
	)
	(segment
		(start -401.32 26.379183)
		(end -401.32 23.749)
		(width 0.127)
		(layer "In5.Cu")
		(net "PCIE_B2T_B1_TX_DP<10>")
	)
	(segment
		(start -374.444999 25.244999)
		(end -375.079999 24.609999)
		(width 0.127)
		(layer "F.Cu")
		(net "PCIE_B2T_B1_TX_DP<0>")
	)
	(via
		(at -375.079999 24.609999)
		(size 0.5588)
		(drill 0.254)
		(layers "F.Cu" "B.Cu")
		(net "PCIE_B2T_B1_TX_DP<0>")
	)
	(segment
		(start -405.659146 30.812402)
		(end -405.912401 30.812402)
		(width 0.127)
		(layer "B.Cu")
		(net "PCIE_B2T_B1_TX_DP<0>")
	)
	(segment
		(start -387.731 17.3482)
		(end -398.755347 17.3482)
		(width 0.127)
		(layer "B.Cu")
		(net "PCIE_B2T_B1_TX_DP<0>")
	)
	(segment
		(start -398.755347 17.3482)
		(end -405.3078 23.900653)
		(width 0.127)
		(layer "B.Cu")
		(net "PCIE_B2T_B1_TX_DP<0>")
	)
	(segment
		(start -375.562599 24.127399)
		(end -376.800633 24.127399)
		(width 0.127)
		(layer "B.Cu")
		(net "PCIE_B2T_B1_TX_DP<0>")
	)
	(segment
		(start -377.1265 23.801532)
		(end -377.1265 23.087853)
		(width 0.127)
		(layer "B.Cu")
		(net "PCIE_B2T_B1_TX_DP<0>")
	)
	(segment
		(start -381.35814 23.72106)
		(end -387.731 17.3482)
		(width 0.127)
		(layer "B.Cu")
		(net "PCIE_B2T_B1_TX_DP<0>")
	)
	(segment
		(start -377.1265 23.087853)
		(end -377.351813 22.86254)
		(width 0.127)
		(layer "B.Cu")
		(net "PCIE_B2T_B1_TX_DP<0>")
	)
	(segment
		(start -375.079999 24.609999)
		(end -375.562599 24.127399)
		(width 0.127)
		(layer "B.Cu")
		(net "PCIE_B2T_B1_TX_DP<0>")
	)
	(segment
		(start -380.066027 23.72106)
		(end -381.35814 23.72106)
		(width 0.127)
		(layer "B.Cu")
		(net "PCIE_B2T_B1_TX_DP<0>")
	)
	(segment
		(start -379.207507 22.86254)
		(end -380.066027 23.72106)
		(width 0.127)
		(layer "B.Cu")
		(net "PCIE_B2T_B1_TX_DP<0>")
	)
	(segment
		(start -405.3078 30.461057)
		(end -405.659146 30.812402)
		(width 0.127)
		(layer "B.Cu")
		(net "PCIE_B2T_B1_TX_DP<0>")
	)
	(segment
		(start -405.3078 23.900653)
		(end -405.3078 30.461057)
		(width 0.127)
		(layer "B.Cu")
		(net "PCIE_B2T_B1_TX_DP<0>")
	)
	(segment
		(start -376.800633 24.127399)
		(end -377.1265 23.801532)
		(width 0.127)
		(layer "B.Cu")
		(net "PCIE_B2T_B1_TX_DP<0>")
	)
	(segment
		(start -377.351813 22.86254)
		(end -379.207507 22.86254)
		(width 0.127)
		(layer "B.Cu")
		(net "PCIE_B2T_B1_TX_DP<0>")
	)
	(segment
		(start -405.912401 30.812402)
		(end -406.46 31.360001)
		(width 0.127)
		(layer "B.Cu")
		(net "PCIE_B2T_B1_TX_DP<0>")
	)
	(segment
		(start -370.634999 26.514999)
		(end -371.269999 25.879999)
		(width 0.127)
		(layer "F.Cu")
		(net "PCIE_B2T_B1_TX_DN<9>")
	)
	(via
		(at -371.269999 25.879999)
		(size 0.5588)
		(drill 0.254)
		(layers "F.Cu" "B.Cu")
		(net "PCIE_B2T_B1_TX_DN<9>")
	)
	(segment
		(start -399.637593 19.0373)
		(end -403.6187 23.018407)
		(width 0.127)
		(layer "In5.Cu")
		(net "PCIE_B2T_B1_TX_DN<9>")
	)
	(segment
		(start -382.07442 25.08758)
		(end -388.1247 19.0373)
		(width 0.127)
		(layer "In5.Cu")
		(net "PCIE_B2T_B1_TX_DN<9>")
	)
	(segment
		(start -373.398707 25.08758)
		(end -382.07442 25.08758)
		(width 0.127)
		(layer "In5.Cu")
		(net "PCIE_B2T_B1_TX_DN<9>")
	)
	(segment
		(start -403.6187 23.018407)
		(end -403.6187 27.536191)
		(width 0.127)
		(layer "In5.Cu")
		(net "PCIE_B2T_B1_TX_DN<9>")
	)
	(segment
		(start -372.909818 26.368949)
		(end -373.0244 26.254367)
		(width 0.127)
		(layer "In5.Cu")
		(net "PCIE_B2T_B1_TX_DN<9>")
	)
	(segment
		(start -371.269999 25.879999)
		(end -371.758949 26.368949)
		(width 0.127)
		(layer "In5.Cu")
		(net "PCIE_B2T_B1_TX_DN<9>")
	)
	(segment
		(start -371.758949 26.368949)
		(end -372.909818 26.368949)
		(width 0.127)
		(layer "In5.Cu")
		(net "PCIE_B2T_B1_TX_DN<9>")
	)
	(segment
		(start -388.1247 19.0373)
		(end -399.637593 19.0373)
		(width 0.127)
		(layer "In5.Cu")
		(net "PCIE_B2T_B1_TX_DN<9>")
	)
	(segment
		(start -373.0244 25.461887)
		(end -373.398707 25.08758)
		(width 0.127)
		(layer "In5.Cu")
		(net "PCIE_B2T_B1_TX_DN<9>")
	)
	(segment
		(start -403.696462 27.613953)
		(end -403.906048 27.613953)
		(width 0.127)
		(layer "In5.Cu")
		(net "PCIE_B2T_B1_TX_DN<9>")
	)
	(segment
		(start -403.6187 27.536191)
		(end -403.696462 27.613953)
		(width 0.127)
		(layer "In5.Cu")
		(net "PCIE_B2T_B1_TX_DN<9>")
	)
	(segment
		(start -373.0244 26.254367)
		(end -373.0244 25.461887)
		(width 0.127)
		(layer "In5.Cu")
		(net "PCIE_B2T_B1_TX_DN<9>")
	)
	(segment
		(start -403.906048 27.613953)
		(end -404.459999 27.060002)
		(width 0.127)
		(layer "In5.Cu")
		(net "PCIE_B2T_B1_TX_DN<9>")
	)
	(segment
		(start -371.904999 23.974999)
		(end -372.539999 23.339999)
		(width 0.127)
		(layer "F.Cu")
		(net "PCIE_B2T_B1_TX_DN<8>")
	)
	(via
		(at -372.539999 23.339999)
		(size 0.5588)
		(drill 0.254)
		(layers "F.Cu" "B.Cu")
		(net "PCIE_B2T_B1_TX_DN<8>")
	)
	(segment
		(start -405.590893 26.114652)
		(end -405.790194 26.313953)
		(width 0.127)
		(layer "In5.Cu")
		(net "PCIE_B2T_B1_TX_DN<8>")
	)
	(segment
		(start -382.25984 23.42896)
		(end -387.6929 17.9959)
		(width 0.127)
		(layer "In5.Cu")
		(net "PCIE_B2T_B1_TX_DN<8>")
	)
	(segment
		(start -372.539999 23.339999)
		(end -373.028949 23.828949)
		(width 0.127)
		(layer "In5.Cu")
		(net "PCIE_B2T_B1_TX_DN<8>")
	)
	(segment
		(start -374.179818 23.828949)
		(end -374.2944 23.714367)
		(width 0.127)
		(layer "In5.Cu")
		(net "PCIE_B2T_B1_TX_DN<8>")
	)
	(segment
		(start -405.790194 26.313953)
		(end -405.906049 26.313953)
		(width 0.127)
		(layer "In5.Cu")
		(net "PCIE_B2T_B1_TX_DN<8>")
	)
	(segment
		(start -374.668707 22.54758)
		(end -379.228693 22.54758)
		(width 0.127)
		(layer "In5.Cu")
		(net "PCIE_B2T_B1_TX_DN<8>")
	)
	(segment
		(start -374.2944 22.921887)
		(end -374.668707 22.54758)
		(width 0.127)
		(layer "In5.Cu")
		(net "PCIE_B2T_B1_TX_DN<8>")
	)
	(segment
		(start -379.228693 22.54758)
		(end -380.110073 23.42896)
		(width 0.127)
		(layer "In5.Cu")
		(net "PCIE_B2T_B1_TX_DN<8>")
	)
	(segment
		(start -405.590893 22.3998)
		(end -405.590893 26.114652)
		(width 0.127)
		(layer "In5.Cu")
		(net "PCIE_B2T_B1_TX_DN<8>")
	)
	(segment
		(start -387.6929 17.9959)
		(end -401.186993 17.9959)
		(width 0.127)
		(layer "In5.Cu")
		(net "PCIE_B2T_B1_TX_DN<8>")
	)
	(segment
		(start -380.110073 23.42896)
		(end -382.25984 23.42896)
		(width 0.127)
		(layer "In5.Cu")
		(net "PCIE_B2T_B1_TX_DN<8>")
	)
	(segment
		(start -405.906049 26.313953)
		(end -406.46 25.760002)
		(width 0.127)
		(layer "In5.Cu")
		(net "PCIE_B2T_B1_TX_DN<8>")
	)
	(segment
		(start -401.186993 17.9959)
		(end -405.590893 22.3998)
		(width 0.127)
		(layer "In5.Cu")
		(net "PCIE_B2T_B1_TX_DN<8>")
	)
	(segment
		(start -374.2944 23.714367)
		(end -374.2944 22.921887)
		(width 0.127)
		(layer "In5.Cu")
		(net "PCIE_B2T_B1_TX_DN<8>")
	)
	(segment
		(start -373.028949 23.828949)
		(end -374.179818 23.828949)
		(width 0.127)
		(layer "In5.Cu")
		(net "PCIE_B2T_B1_TX_DN<8>")
	)
	(segment
		(start -373.174999 41.754999)
		(end -373.809999 41.119999)
		(width 0.127)
		(layer "F.Cu")
		(net "PCIE_B2T_B1_TX_DN<7>")
	)
	(via
		(at -373.809999 41.119999)
		(size 0.5588)
		(drill 0.254)
		(layers "F.Cu" "B.Cu")
		(net "PCIE_B2T_B1_TX_DN<7>")
	)
	(segment
		(start -379.66142 40.33774)
		(end -381.94234 38.05682)
		(width 0.127)
		(layer "B.Cu")
		(net "PCIE_B2T_B1_TX_DN<7>")
	)
	(segment
		(start -374.292599 41.602599)
		(end -375.40438 41.602599)
		(width 0.127)
		(layer "B.Cu")
		(net "PCIE_B2T_B1_TX_DN<7>")
	)
	(segment
		(start -375.40438 41.602599)
		(end -375.5517 41.455279)
		(width 0.127)
		(layer "B.Cu")
		(net "PCIE_B2T_B1_TX_DN<7>")
	)
	(segment
		(start -375.95556 40.33774)
		(end -379.66142 40.33774)
		(width 0.127)
		(layer "B.Cu")
		(net "PCIE_B2T_B1_TX_DN<7>")
	)
	(segment
		(start -375.5517 41.455279)
		(end -375.5517 40.7416)
		(width 0.127)
		(layer "B.Cu")
		(net "PCIE_B2T_B1_TX_DN<7>")
	)
	(segment
		(start -389.806998 31.807602)
		(end -391.912399 31.807602)
		(width 0.127)
		(layer "B.Cu")
		(net "PCIE_B2T_B1_TX_DN<7>")
	)
	(segment
		(start -381.94234 37.30244)
		(end -384.80238 34.4424)
		(width 0.127)
		(layer "B.Cu")
		(net "PCIE_B2T_B1_TX_DN<7>")
	)
	(segment
		(start -373.809999 41.119999)
		(end -374.292599 41.602599)
		(width 0.127)
		(layer "B.Cu")
		(net "PCIE_B2T_B1_TX_DN<7>")
	)
	(segment
		(start -391.912399 31.807602)
		(end -392.46 31.260001)
		(width 0.127)
		(layer "B.Cu")
		(net "PCIE_B2T_B1_TX_DN<7>")
	)
	(segment
		(start -381.94234 38.05682)
		(end -381.94234 37.30244)
		(width 0.127)
		(layer "B.Cu")
		(net "PCIE_B2T_B1_TX_DN<7>")
	)
	(segment
		(start -375.5517 40.7416)
		(end -375.95556 40.33774)
		(width 0.127)
		(layer "B.Cu")
		(net "PCIE_B2T_B1_TX_DN<7>")
	)
	(segment
		(start -387.1722 34.4424)
		(end -389.806998 31.807602)
		(width 0.127)
		(layer "B.Cu")
		(net "PCIE_B2T_B1_TX_DN<7>")
	)
	(segment
		(start -384.80238 34.4424)
		(end -387.1722 34.4424)
		(width 0.127)
		(layer "B.Cu")
		(net "PCIE_B2T_B1_TX_DN<7>")
	)
	(segment
		(start -374.444999 39.214999)
		(end -375.079999 38.579999)
		(width 0.127)
		(layer "F.Cu")
		(net "PCIE_B2T_B1_TX_DN<6>")
	)
	(via
		(at -375.079999 38.579999)
		(size 0.5588)
		(drill 0.254)
		(layers "F.Cu" "B.Cu")
		(net "PCIE_B2T_B1_TX_DN<6>")
	)
	(segment
		(start -393.603 30.388956)
		(end -393.721646 30.507602)
		(width 0.127)
		(layer "B.Cu")
		(net "PCIE_B2T_B1_TX_DN<6>")
	)
	(segment
		(start -378.70638 37.15004)
		(end -380.4666 37.15004)
		(width 0.127)
		(layer "B.Cu")
		(net "PCIE_B2T_B1_TX_DN<6>")
	)
	(segment
		(start -380.76378 36.85286)
		(end -380.76378 36.63442)
		(width 0.127)
		(layer "B.Cu")
		(net "PCIE_B2T_B1_TX_DN<6>")
	)
	(segment
		(start -392.449398 24.517002)
		(end -392.4554 24.511)
		(width 0.127)
		(layer "B.Cu")
		(net "PCIE_B2T_B1_TX_DN<6>")
	)
	(segment
		(start -376.67438 39.062599)
		(end -376.8217 38.915279)
		(width 0.127)
		(layer "B.Cu")
		(net "PCIE_B2T_B1_TX_DN<6>")
	)
	(segment
		(start -392.4554 24.511)
		(end -392.9888 24.511)
		(width 0.127)
		(layer "B.Cu")
		(net "PCIE_B2T_B1_TX_DN<6>")
	)
	(segment
		(start -376.8217 38.915279)
		(end -376.8217 38.2016)
		(width 0.127)
		(layer "B.Cu")
		(net "PCIE_B2T_B1_TX_DN<6>")
	)
	(segment
		(start -391.317 26.0812)
		(end -391.317 25.186518)
		(width 0.127)
		(layer "B.Cu")
		(net "PCIE_B2T_B1_TX_DN<6>")
	)
	(segment
		(start -391.317 25.186518)
		(end -391.986516 24.517002)
		(width 0.127)
		(layer "B.Cu")
		(net "PCIE_B2T_B1_TX_DN<6>")
	)
	(segment
		(start -393.721646 30.507602)
		(end -393.9124 30.507602)
		(width 0.127)
		(layer "B.Cu")
		(net "PCIE_B2T_B1_TX_DN<6>")
	)
	(segment
		(start -375.562599 39.062599)
		(end -376.67438 39.062599)
		(width 0.127)
		(layer "B.Cu")
		(net "PCIE_B2T_B1_TX_DN<6>")
	)
	(segment
		(start -393.9124 30.507602)
		(end -394.460001 29.960001)
		(width 0.127)
		(layer "B.Cu")
		(net "PCIE_B2T_B1_TX_DN<6>")
	)
	(segment
		(start -377.22556 37.79774)
		(end -378.05868 37.79774)
		(width 0.127)
		(layer "B.Cu")
		(net "PCIE_B2T_B1_TX_DN<6>")
	)
	(segment
		(start -391.986516 24.517002)
		(end -392.449398 24.517002)
		(width 0.127)
		(layer "B.Cu")
		(net "PCIE_B2T_B1_TX_DN<6>")
	)
	(segment
		(start -392.9888 24.511)
		(end -393.603 25.1252)
		(width 0.127)
		(layer "B.Cu")
		(net "PCIE_B2T_B1_TX_DN<6>")
	)
	(segment
		(start -393.603 25.1252)
		(end -393.603 30.388956)
		(width 0.127)
		(layer "B.Cu")
		(net "PCIE_B2T_B1_TX_DN<6>")
	)
	(segment
		(start -380.4666 37.15004)
		(end -380.76378 36.85286)
		(width 0.127)
		(layer "B.Cu")
		(net "PCIE_B2T_B1_TX_DN<6>")
	)
	(segment
		(start -376.8217 38.2016)
		(end -377.22556 37.79774)
		(width 0.127)
		(layer "B.Cu")
		(net "PCIE_B2T_B1_TX_DN<6>")
	)
	(segment
		(start -380.76378 36.63442)
		(end -391.317 26.0812)
		(width 0.127)
		(layer "B.Cu")
		(net "PCIE_B2T_B1_TX_DN<6>")
	)
	(segment
		(start -378.05868 37.79774)
		(end -378.70638 37.15004)
		(width 0.127)
		(layer "B.Cu")
		(net "PCIE_B2T_B1_TX_DN<6>")
	)
	(segment
		(start -375.079999 38.579999)
		(end -375.562599 39.062599)
		(width 0.127)
		(layer "B.Cu")
		(net "PCIE_B2T_B1_TX_DN<6>")
	)
	(segment
		(start -373.174999 36.674999)
		(end -373.809999 36.039999)
		(width 0.127)
		(layer "F.Cu")
		(net "PCIE_B2T_B1_TX_DN<5>")
	)
	(via
		(at -373.809999 36.039999)
		(size 0.5588)
		(drill 0.254)
		(layers "F.Cu" "B.Cu")
		(net "PCIE_B2T_B1_TX_DN<5>")
	)
	(segment
		(start -375.95556 35.25774)
		(end -375.5517 35.6616)
		(width 0.127)
		(layer "B.Cu")
		(net "PCIE_B2T_B1_TX_DN<5>")
	)
	(segment
		(start -374.292599 36.522599)
		(end -373.809999 36.039999)
		(width 0.127)
		(layer "B.Cu")
		(net "PCIE_B2T_B1_TX_DN<5>")
	)
	(segment
		(start -395.766318 31.807602)
		(end -395.605 31.646284)
		(width 0.127)
		(layer "B.Cu")
		(net "PCIE_B2T_B1_TX_DN<5>")
	)
	(segment
		(start -379.16358 35.25774)
		(end -375.95556 35.25774)
		(width 0.127)
		(layer "B.Cu")
		(net "PCIE_B2T_B1_TX_DN<5>")
	)
	(segment
		(start -395.603001 23.899315)
		(end -395.603001 23.886518)
		(width 0.127)
		(layer "B.Cu")
		(net "PCIE_B2T_B1_TX_DN<5>")
	)
	(segment
		(start -395.605 31.646284)
		(end -395.605 23.901314)
		(width 0.127)
		(layer "B.Cu")
		(net "PCIE_B2T_B1_TX_DN<5>")
	)
	(segment
		(start -388.6708 26.95956)
		(end -382.16586 33.4645)
		(width 0.127)
		(layer "B.Cu")
		(net "PCIE_B2T_B1_TX_DN<5>")
	)
	(segment
		(start -380.95682 33.4645)
		(end -379.16358 35.25774)
		(width 0.127)
		(layer "B.Cu")
		(net "PCIE_B2T_B1_TX_DN<5>")
	)
	(segment
		(start -394.933485 23.217002)
		(end -391.463398 23.217002)
		(width 0.127)
		(layer "B.Cu")
		(net "PCIE_B2T_B1_TX_DN<5>")
	)
	(segment
		(start -395.912398 31.807602)
		(end -395.766318 31.807602)
		(width 0.127)
		(layer "B.Cu")
		(net "PCIE_B2T_B1_TX_DN<5>")
	)
	(segment
		(start -375.5517 35.6616)
		(end -375.5517 36.375279)
		(width 0.127)
		(layer "B.Cu")
		(net "PCIE_B2T_B1_TX_DN<5>")
	)
	(segment
		(start -395.605 23.901314)
		(end -395.603001 23.899315)
		(width 0.127)
		(layer "B.Cu")
		(net "PCIE_B2T_B1_TX_DN<5>")
	)
	(segment
		(start -388.6708 26.0096)
		(end -388.6708 26.95956)
		(width 0.127)
		(layer "B.Cu")
		(net "PCIE_B2T_B1_TX_DN<5>")
	)
	(segment
		(start -382.16586 33.4645)
		(end -380.95682 33.4645)
		(width 0.127)
		(layer "B.Cu")
		(net "PCIE_B2T_B1_TX_DN<5>")
	)
	(segment
		(start -391.463398 23.217002)
		(end -388.6708 26.0096)
		(width 0.127)
		(layer "B.Cu")
		(net "PCIE_B2T_B1_TX_DN<5>")
	)
	(segment
		(start -375.40438 36.522599)
		(end -374.292599 36.522599)
		(width 0.127)
		(layer "B.Cu")
		(net "PCIE_B2T_B1_TX_DN<5>")
	)
	(segment
		(start -375.5517 36.375279)
		(end -375.40438 36.522599)
		(width 0.127)
		(layer "B.Cu")
		(net "PCIE_B2T_B1_TX_DN<5>")
	)
	(segment
		(start -396.46 31.260001)
		(end -395.912398 31.807602)
		(width 0.127)
		(layer "B.Cu")
		(net "PCIE_B2T_B1_TX_DN<5>")
	)
	(segment
		(start -395.603001 23.886518)
		(end -394.933485 23.217002)
		(width 0.127)
		(layer "B.Cu")
		(net "PCIE_B2T_B1_TX_DN<5>")
	)
	(segment
		(start -374.444999 34.134999)
		(end -375.079999 33.499999)
		(width 0.127)
		(layer "F.Cu")
		(net "PCIE_B2T_B1_TX_DN<4>")
	)
	(via
		(at -375.079999 33.499999)
		(size 0.5588)
		(drill 0.254)
		(layers "F.Cu" "B.Cu")
		(net "PCIE_B2T_B1_TX_DN<4>")
	)
	(segment
		(start -386.4864 27.305)
		(end -381.7112 32.0802)
		(width 0.127)
		(layer "B.Cu")
		(net "PCIE_B2T_B1_TX_DN<4>")
	)
	(segment
		(start -376.67438 33.982599)
		(end -375.562599 33.982599)
		(width 0.127)
		(layer "B.Cu")
		(net "PCIE_B2T_B1_TX_DN<4>")
	)
	(segment
		(start -397.802204 30.507602)
		(end -397.6116 30.316998)
		(width 0.127)
		(layer "B.Cu")
		(net "PCIE_B2T_B1_TX_DN<4>")
	)
	(segment
		(start -395.5542 21.9964)
		(end -390.8298 21.9964)
		(width 0.127)
		(layer "B.Cu")
		(net "PCIE_B2T_B1_TX_DN<4>")
	)
	(segment
		(start -376.8217 33.835279)
		(end -376.67438 33.982599)
		(width 0.127)
		(layer "B.Cu")
		(net "PCIE_B2T_B1_TX_DN<4>")
	)
	(segment
		(start -377.22556 32.71774)
		(end -376.8217 33.1216)
		(width 0.127)
		(layer "B.Cu")
		(net "PCIE_B2T_B1_TX_DN<4>")
	)
	(segment
		(start -376.8217 33.1216)
		(end -376.8217 33.835279)
		(width 0.127)
		(layer "B.Cu")
		(net "PCIE_B2T_B1_TX_DN<4>")
	)
	(segment
		(start -398.460001 29.960001)
		(end -397.9124 30.507602)
		(width 0.127)
		(layer "B.Cu")
		(net "PCIE_B2T_B1_TX_DN<4>")
	)
	(segment
		(start -390.8298 21.9964)
		(end -386.4864 26.3398)
		(width 0.127)
		(layer "B.Cu")
		(net "PCIE_B2T_B1_TX_DN<4>")
	)
	(segment
		(start -397.6116 30.316998)
		(end -397.6116 24.0538)
		(width 0.127)
		(layer "B.Cu")
		(net "PCIE_B2T_B1_TX_DN<4>")
	)
	(segment
		(start -397.9124 30.507602)
		(end -397.802204 30.507602)
		(width 0.127)
		(layer "B.Cu")
		(net "PCIE_B2T_B1_TX_DN<4>")
	)
	(segment
		(start -378.86894 32.71774)
		(end -377.22556 32.71774)
		(width 0.127)
		(layer "B.Cu")
		(net "PCIE_B2T_B1_TX_DN<4>")
	)
	(segment
		(start -379.50648 32.0802)
		(end -378.86894 32.71774)
		(width 0.127)
		(layer "B.Cu")
		(net "PCIE_B2T_B1_TX_DN<4>")
	)
	(segment
		(start -375.562599 33.982599)
		(end -375.079999 33.499999)
		(width 0.127)
		(layer "B.Cu")
		(net "PCIE_B2T_B1_TX_DN<4>")
	)
	(segment
		(start -381.7112 32.0802)
		(end -379.50648 32.0802)
		(width 0.127)
		(layer "B.Cu")
		(net "PCIE_B2T_B1_TX_DN<4>")
	)
	(segment
		(start -386.4864 26.3398)
		(end -386.4864 27.305)
		(width 0.127)
		(layer "B.Cu")
		(net "PCIE_B2T_B1_TX_DN<4>")
	)
	(segment
		(start -397.6116 24.0538)
		(end -395.5542 21.9964)
		(width 0.127)
		(layer "B.Cu")
		(net "PCIE_B2T_B1_TX_DN<4>")
	)
	(segment
		(start -373.174999 31.594999)
		(end -373.809999 30.959999)
		(width 0.127)
		(layer "F.Cu")
		(net "PCIE_B2T_B1_TX_DN<3>")
	)
	(via
		(at -373.809999 30.959999)
		(size 0.5588)
		(drill 0.254)
		(layers "F.Cu" "B.Cu")
		(net "PCIE_B2T_B1_TX_DN<3>")
	)
	(segment
		(start -384.0226 26.670747)
		(end -389.916147 20.7772)
		(width 0.127)
		(layer "B.Cu")
		(net "PCIE_B2T_B1_TX_DN<3>")
	)
	(segment
		(start -375.5517 30.5816)
		(end -375.95556 30.17774)
		(width 0.127)
		(layer "B.Cu")
		(net "PCIE_B2T_B1_TX_DN<3>")
	)
	(segment
		(start -375.5517 31.295279)
		(end -375.5517 30.5816)
		(width 0.127)
		(layer "B.Cu")
		(net "PCIE_B2T_B1_TX_DN<3>")
	)
	(segment
		(start -390.929157 20.7772)
		(end -396.621003 20.7772)
		(width 0.127)
		(layer "B.Cu")
		(net "PCIE_B2T_B1_TX_DN<3>")
	)
	(segment
		(start -375.95556 30.17774)
		(end -381.201407 30.17774)
		(width 0.127)
		(layer "B.Cu")
		(net "PCIE_B2T_B1_TX_DN<3>")
	)
	(segment
		(start -399.6182 24.026909)
		(end -399.6182 31.640404)
		(width 0.127)
		(layer "B.Cu")
		(net "PCIE_B2T_B1_TX_DN<3>")
	)
	(segment
		(start -384.0226 27.356547)
		(end -384.0226 26.670747)
		(width 0.127)
		(layer "B.Cu")
		(net "PCIE_B2T_B1_TX_DN<3>")
	)
	(segment
		(start -399.6182 31.640404)
		(end -399.785398 31.807602)
		(width 0.127)
		(layer "B.Cu")
		(net "PCIE_B2T_B1_TX_DN<3>")
	)
	(segment
		(start -389.919322 20.777015)
		(end -390.928972 20.777015)
		(width 0.127)
		(layer "B.Cu")
		(net "PCIE_B2T_B1_TX_DN<3>")
	)
	(segment
		(start -375.40438 31.442599)
		(end -375.5517 31.295279)
		(width 0.127)
		(layer "B.Cu")
		(net "PCIE_B2T_B1_TX_DN<3>")
	)
	(segment
		(start -374.292599 31.442599)
		(end -375.40438 31.442599)
		(width 0.127)
		(layer "B.Cu")
		(net "PCIE_B2T_B1_TX_DN<3>")
	)
	(segment
		(start -373.809999 30.959999)
		(end -374.292599 31.442599)
		(width 0.127)
		(layer "B.Cu")
		(net "PCIE_B2T_B1_TX_DN<3>")
	)
	(segment
		(start -390.928972 20.777015)
		(end -390.929157 20.7772)
		(width 0.127)
		(layer "B.Cu")
		(net "PCIE_B2T_B1_TX_DN<3>")
	)
	(segment
		(start -399.618264 23.774461)
		(end -399.618264 24.026846)
		(width 0.127)
		(layer "B.Cu")
		(net "PCIE_B2T_B1_TX_DN<3>")
	)
	(segment
		(start -399.6182 23.774311)
		(end -399.6182 23.774397)
		(width 0.127)
		(layer "B.Cu")
		(net "PCIE_B2T_B1_TX_DN<3>")
	)
	(segment
		(start -389.916147 20.7772)
		(end -389.919136 20.7772)
		(width 0.127)
		(layer "B.Cu")
		(net "PCIE_B2T_B1_TX_DN<3>")
	)
	(segment
		(start -381.201407 30.17774)
		(end -384.0226 27.356547)
		(width 0.127)
		(layer "B.Cu")
		(net "PCIE_B2T_B1_TX_DN<3>")
	)
	(segment
		(start -399.6182 23.774397)
		(end -399.618264 23.774461)
		(width 0.127)
		(layer "B.Cu")
		(net "PCIE_B2T_B1_TX_DN<3>")
	)
	(segment
		(start -399.439653 23.595851)
		(end -399.43974 23.595851)
		(width 0.127)
		(layer "B.Cu")
		(net "PCIE_B2T_B1_TX_DN<3>")
	)
	(segment
		(start -399.618264 24.026846)
		(end -399.6182 24.026909)
		(width 0.127)
		(layer "B.Cu")
		(net "PCIE_B2T_B1_TX_DN<3>")
	)
	(segment
		(start -389.919136 20.7772)
		(end -389.919322 20.777015)
		(width 0.127)
		(layer "B.Cu")
		(net "PCIE_B2T_B1_TX_DN<3>")
	)
	(segment
		(start -399.43974 23.595851)
		(end -399.6182 23.774311)
		(width 0.127)
		(layer "B.Cu")
		(net "PCIE_B2T_B1_TX_DN<3>")
	)
	(segment
		(start -396.621003 20.7772)
		(end -399.439653 23.595851)
		(width 0.127)
		(layer "B.Cu")
		(net "PCIE_B2T_B1_TX_DN<3>")
	)
	(segment
		(start -399.912398 31.807602)
		(end -400.459999 31.260001)
		(width 0.127)
		(layer "B.Cu")
		(net "PCIE_B2T_B1_TX_DN<3>")
	)
	(segment
		(start -399.785398 31.807602)
		(end -399.912398 31.807602)
		(width 0.127)
		(layer "B.Cu")
		(net "PCIE_B2T_B1_TX_DN<3>")
	)
	(segment
		(start -374.444999 29.054999)
		(end -375.079999 28.419999)
		(width 0.127)
		(layer "F.Cu")
		(net "PCIE_B2T_B1_TX_DN<2>")
	)
	(via
		(at -375.079999 28.419999)
		(size 0.5588)
		(drill 0.254)
		(layers "F.Cu" "B.Cu")
		(net "PCIE_B2T_B1_TX_DN<2>")
	)
	(segment
		(start -401.5994 25.182833)
		(end -401.5994 23.876)
		(width 0.127)
		(layer "B.Cu")
		(net "PCIE_B2T_B1_TX_DN<2>")
	)
	(segment
		(start -375.562599 28.902599)
		(end -375.079999 28.419999)
		(width 0.127)
		(layer "B.Cu")
		(net "PCIE_B2T_B1_TX_DN<2>")
	)
	(segment
		(start -401.602999 25.186432)
		(end -401.5994 25.182833)
		(width 0.127)
		(layer "B.Cu")
		(net "PCIE_B2T_B1_TX_DN<2>")
	)
	(segment
		(start -377.22556 27.63774)
		(end -376.8217 28.0416)
		(width 0.127)
		(layer "B.Cu")
		(net "PCIE_B2T_B1_TX_DN<2>")
	)
	(segment
		(start -376.67438 28.902599)
		(end -375.562599 28.902599)
		(width 0.127)
		(layer "B.Cu")
		(net "PCIE_B2T_B1_TX_DN<2>")
	)
	(segment
		(start -381.564627 26.99512)
		(end -378.98578 26.99512)
		(width 0.127)
		(layer "B.Cu")
		(net "PCIE_B2T_B1_TX_DN<2>")
	)
	(segment
		(start -401.602999 30.325202)
		(end -401.602999 25.186432)
		(width 0.127)
		(layer "B.Cu")
		(net "PCIE_B2T_B1_TX_DN<2>")
	)
	(segment
		(start -376.8217 28.755279)
		(end -376.67438 28.902599)
		(width 0.127)
		(layer "B.Cu")
		(net "PCIE_B2T_B1_TX_DN<2>")
	)
	(segment
		(start -401.785399 30.507602)
		(end -401.602999 30.325202)
		(width 0.127)
		(layer "B.Cu")
		(net "PCIE_B2T_B1_TX_DN<2>")
	)
	(segment
		(start -378.34316 27.63774)
		(end -377.22556 27.63774)
		(width 0.127)
		(layer "B.Cu")
		(net "PCIE_B2T_B1_TX_DN<2>")
	)
	(segment
		(start -397.2306 19.5072)
		(end -389.052547 19.5072)
		(width 0.127)
		(layer "B.Cu")
		(net "PCIE_B2T_B1_TX_DN<2>")
	)
	(segment
		(start -401.5994 23.876)
		(end -397.2306 19.5072)
		(width 0.127)
		(layer "B.Cu")
		(net "PCIE_B2T_B1_TX_DN<2>")
	)
	(segment
		(start -401.912399 30.507602)
		(end -401.785399 30.507602)
		(width 0.127)
		(layer "B.Cu")
		(net "PCIE_B2T_B1_TX_DN<2>")
	)
	(segment
		(start -402.46 29.960001)
		(end -401.912399 30.507602)
		(width 0.127)
		(layer "B.Cu")
		(net "PCIE_B2T_B1_TX_DN<2>")
	)
	(segment
		(start -389.052547 19.5072)
		(end -381.564627 26.99512)
		(width 0.127)
		(layer "B.Cu")
		(net "PCIE_B2T_B1_TX_DN<2>")
	)
	(segment
		(start -378.98578 26.99512)
		(end -378.34316 27.63774)
		(width 0.127)
		(layer "B.Cu")
		(net "PCIE_B2T_B1_TX_DN<2>")
	)
	(segment
		(start -376.8217 28.0416)
		(end -376.8217 28.755279)
		(width 0.127)
		(layer "B.Cu")
		(net "PCIE_B2T_B1_TX_DN<2>")
	)
	(segment
		(start -373.174999 26.514999)
		(end -373.809999 25.879999)
		(width 0.127)
		(layer "F.Cu")
		(net "PCIE_B2T_B1_TX_DN<1>")
	)
	(via
		(at -373.809999 25.879999)
		(size 0.5588)
		(drill 0.254)
		(layers "F.Cu" "B.Cu")
		(net "PCIE_B2T_B1_TX_DN<1>")
	)
	(segment
		(start -403.606 31.711842)
		(end -403.701761 31.807602)
		(width 0.127)
		(layer "B.Cu")
		(net "PCIE_B2T_B1_TX_DN<1>")
	)
	(segment
		(start -403.701761 31.807602)
		(end -403.912398 31.807602)
		(width 0.127)
		(layer "B.Cu")
		(net "PCIE_B2T_B1_TX_DN<1>")
	)
	(segment
		(start -373.809999 25.879999)
		(end -374.292599 26.362599)
		(width 0.127)
		(layer "B.Cu")
		(net "PCIE_B2T_B1_TX_DN<1>")
	)
	(segment
		(start -388.442947 18.2626)
		(end -398.1958 18.2626)
		(width 0.127)
		(layer "B.Cu")
		(net "PCIE_B2T_B1_TX_DN<1>")
	)
	(segment
		(start -374.292599 26.362599)
		(end -375.40438 26.362599)
		(width 0.127)
		(layer "B.Cu")
		(net "PCIE_B2T_B1_TX_DN<1>")
	)
	(segment
		(start -375.5517 26.215279)
		(end -375.5517 25.5016)
		(width 0.127)
		(layer "B.Cu")
		(net "PCIE_B2T_B1_TX_DN<1>")
	)
	(segment
		(start -403.606 23.6728)
		(end -403.606 31.711842)
		(width 0.127)
		(layer "B.Cu")
		(net "PCIE_B2T_B1_TX_DN<1>")
	)
	(segment
		(start -375.5517 25.5016)
		(end -375.95556 25.09774)
		(width 0.127)
		(layer "B.Cu")
		(net "PCIE_B2T_B1_TX_DN<1>")
	)
	(segment
		(start -403.912398 31.807602)
		(end -404.459999 31.260001)
		(width 0.127)
		(layer "B.Cu")
		(net "PCIE_B2T_B1_TX_DN<1>")
	)
	(segment
		(start -381.607807 25.09774)
		(end -388.442947 18.2626)
		(width 0.127)
		(layer "B.Cu")
		(net "PCIE_B2T_B1_TX_DN<1>")
	)
	(segment
		(start -375.95556 25.09774)
		(end -381.607807 25.09774)
		(width 0.127)
		(layer "B.Cu")
		(net "PCIE_B2T_B1_TX_DN<1>")
	)
	(segment
		(start -398.1958 18.2626)
		(end -403.606 23.6728)
		(width 0.127)
		(layer "B.Cu")
		(net "PCIE_B2T_B1_TX_DN<1>")
	)
	(segment
		(start -375.40438 26.362599)
		(end -375.5517 26.215279)
		(width 0.127)
		(layer "B.Cu")
		(net "PCIE_B2T_B1_TX_DN<1>")
	)
	(segment
		(start -370.634999 41.754999)
		(end -371.269999 41.119999)
		(width 0.127)
		(layer "F.Cu")
		(net "PCIE_B2T_B1_TX_DN<15>")
	)
	(via
		(at -371.269999 41.119999)
		(size 0.5588)
		(drill 0.254)
		(layers "F.Cu" "B.Cu")
		(net "PCIE_B2T_B1_TX_DN<15>")
	)
	(segment
		(start -390.962723 33.318793)
		(end -390.7917 33.489816)
		(width 0.127)
		(layer "In5.Cu")
		(net "PCIE_B2T_B1_TX_DN<15>")
	)
	(segment
		(start -373.30634 41.97096)
		(end -372.944329 41.608949)
		(width 0.127)
		(layer "In5.Cu")
		(net "PCIE_B2T_B1_TX_DN<15>")
	)
	(segment
		(start -390.7917 33.489816)
		(end -390.7917 41.103207)
		(width 0.127)
		(layer "In5.Cu")
		(net "PCIE_B2T_B1_TX_DN<15>")
	)
	(segment
		(start -391.148933 33.132667)
		(end -390.962807 33.318793)
		(width 0.127)
		(layer "In5.Cu")
		(net "PCIE_B2T_B1_TX_DN<15>")
	)
	(segment
		(start -390.7917 41.103207)
		(end -388.308507 43.5864)
		(width 0.127)
		(layer "In5.Cu")
		(net "PCIE_B2T_B1_TX_DN<15>")
	)
	(segment
		(start -390.962807 33.318793)
		(end -390.962723 33.318793)
		(width 0.127)
		(layer "In5.Cu")
		(net "PCIE_B2T_B1_TX_DN<15>")
	)
	(segment
		(start -392.46 27.060002)
		(end -391.906049 27.613953)
		(width 0.127)
		(layer "In5.Cu")
		(net "PCIE_B2T_B1_TX_DN<15>")
	)
	(segment
		(start -373.30634 42.94886)
		(end -373.30634 41.97096)
		(width 0.127)
		(layer "In5.Cu")
		(net "PCIE_B2T_B1_TX_DN<15>")
	)
	(segment
		(start -391.148933 28.123078)
		(end -391.148933 33.132667)
		(width 0.127)
		(layer "In5.Cu")
		(net "PCIE_B2T_B1_TX_DN<15>")
	)
	(segment
		(start -391.658058 27.613953)
		(end -391.148933 28.123078)
		(width 0.127)
		(layer "In5.Cu")
		(net "PCIE_B2T_B1_TX_DN<15>")
	)
	(segment
		(start -391.906049 27.613953)
		(end -391.658058 27.613953)
		(width 0.127)
		(layer "In5.Cu")
		(net "PCIE_B2T_B1_TX_DN<15>")
	)
	(segment
		(start -373.94388 43.5864)
		(end -373.30634 42.94886)
		(width 0.127)
		(layer "In5.Cu")
		(net "PCIE_B2T_B1_TX_DN<15>")
	)
	(segment
		(start -371.758949 41.608949)
		(end -371.269999 41.119999)
		(width 0.127)
		(layer "In5.Cu")
		(net "PCIE_B2T_B1_TX_DN<15>")
	)
	(segment
		(start -372.944329 41.608949)
		(end -371.758949 41.608949)
		(width 0.127)
		(layer "In5.Cu")
		(net "PCIE_B2T_B1_TX_DN<15>")
	)
	(segment
		(start -388.308507 43.5864)
		(end -373.94388 43.5864)
		(width 0.127)
		(layer "In5.Cu")
		(net "PCIE_B2T_B1_TX_DN<15>")
	)
	(segment
		(start -371.904999 39.214999)
		(end -372.539999 38.579999)
		(width 0.127)
		(layer "F.Cu")
		(net "PCIE_B2T_B1_TX_DN<14>")
	)
	(via
		(at -372.539999 38.579999)
		(size 0.5588)
		(drill 0.254)
		(layers "F.Cu" "B.Cu")
		(net "PCIE_B2T_B1_TX_DN<14>")
	)
	(segment
		(start -374.2944 38.954367)
		(end -374.179818 39.068949)
		(width 0.127)
		(layer "In5.Cu")
		(net "PCIE_B2T_B1_TX_DN<14>")
	)
	(segment
		(start -393.141441 24.4983)
		(end -391.9347 24.4983)
		(width 0.127)
		(layer "In5.Cu")
		(net "PCIE_B2T_B1_TX_DN<14>")
	)
	(segment
		(start -389.6995 30.5181)
		(end -383.04724 37.17036)
		(width 0.127)
		(layer "In5.Cu")
		(net "PCIE_B2T_B1_TX_DN<14>")
	)
	(segment
		(start -374.668707 37.78758)
		(end -374.2944 38.161887)
		(width 0.127)
		(layer "In5.Cu")
		(net "PCIE_B2T_B1_TX_DN<14>")
	)
	(segment
		(start -374.2944 38.161887)
		(end -374.2944 38.954367)
		(width 0.127)
		(layer "In5.Cu")
		(net "PCIE_B2T_B1_TX_DN<14>")
	)
	(segment
		(start -374.179818 39.068949)
		(end -373.028949 39.068949)
		(width 0.127)
		(layer "In5.Cu")
		(net "PCIE_B2T_B1_TX_DN<14>")
	)
	(segment
		(start -389.6995 26.7335)
		(end -389.6995 30.5181)
		(width 0.127)
		(layer "In5.Cu")
		(net "PCIE_B2T_B1_TX_DN<14>")
	)
	(segment
		(start -393.90605 26.313953)
		(end -393.77905 26.313953)
		(width 0.127)
		(layer "In5.Cu")
		(net "PCIE_B2T_B1_TX_DN<14>")
	)
	(segment
		(start -379.39218 37.17036)
		(end -378.77496 37.78758)
		(width 0.127)
		(layer "In5.Cu")
		(net "PCIE_B2T_B1_TX_DN<14>")
	)
	(segment
		(start -393.77905 26.313953)
		(end -393.65205 26.186953)
		(width 0.127)
		(layer "In5.Cu")
		(net "PCIE_B2T_B1_TX_DN<14>")
	)
	(segment
		(start -393.65205 26.186953)
		(end -393.65205 25.008909)
		(width 0.127)
		(layer "In5.Cu")
		(net "PCIE_B2T_B1_TX_DN<14>")
	)
	(segment
		(start -378.77496 37.78758)
		(end -374.668707 37.78758)
		(width 0.127)
		(layer "In5.Cu")
		(net "PCIE_B2T_B1_TX_DN<14>")
	)
	(segment
		(start -373.028949 39.068949)
		(end -372.539999 38.579999)
		(width 0.127)
		(layer "In5.Cu")
		(net "PCIE_B2T_B1_TX_DN<14>")
	)
	(segment
		(start -383.04724 37.17036)
		(end -379.39218 37.17036)
		(width 0.127)
		(layer "In5.Cu")
		(net "PCIE_B2T_B1_TX_DN<14>")
	)
	(segment
		(start -391.9347 24.4983)
		(end -389.6995 26.7335)
		(width 0.127)
		(layer "In5.Cu")
		(net "PCIE_B2T_B1_TX_DN<14>")
	)
	(segment
		(start -393.65205 25.008909)
		(end -393.141441 24.4983)
		(width 0.127)
		(layer "In5.Cu")
		(net "PCIE_B2T_B1_TX_DN<14>")
	)
	(segment
		(start -394.460001 25.760002)
		(end -393.90605 26.313953)
		(width 0.127)
		(layer "In5.Cu")
		(net "PCIE_B2T_B1_TX_DN<14>")
	)
	(segment
		(start -370.634999 36.674999)
		(end -371.269999 36.039999)
		(width 0.127)
		(layer "F.Cu")
		(net "PCIE_B2T_B1_TX_DN<13>")
	)
	(via
		(at -371.269999 36.039999)
		(size 0.5588)
		(drill 0.254)
		(layers "F.Cu" "B.Cu")
		(net "PCIE_B2T_B1_TX_DN<13>")
	)
	(segment
		(start -372.909818 36.528949)
		(end -373.0244 36.414367)
		(width 0.127)
		(layer "In5.Cu")
		(net "PCIE_B2T_B1_TX_DN<13>")
	)
	(segment
		(start -395.6723 27.613953)
		(end -395.906048 27.613953)
		(width 0.127)
		(layer "In5.Cu")
		(net "PCIE_B2T_B1_TX_DN<13>")
	)
	(segment
		(start -371.758949 36.528949)
		(end -372.909818 36.528949)
		(width 0.127)
		(layer "In5.Cu")
		(net "PCIE_B2T_B1_TX_DN<13>")
	)
	(segment
		(start -395.906048 27.613953)
		(end -396.46 27.060002)
		(width 0.127)
		(layer "In5.Cu")
		(net "PCIE_B2T_B1_TX_DN<13>")
	)
	(segment
		(start -388.3914 29.2608)
		(end -388.3914 26.4668)
		(width 0.127)
		(layer "In5.Cu")
		(net "PCIE_B2T_B1_TX_DN<13>")
	)
	(segment
		(start -395.5923 23.8887)
		(end -395.5923 27.533953)
		(width 0.127)
		(layer "In5.Cu")
		(net "PCIE_B2T_B1_TX_DN<13>")
	)
	(segment
		(start -395.5923 27.533953)
		(end -395.6723 27.613953)
		(width 0.127)
		(layer "In5.Cu")
		(net "PCIE_B2T_B1_TX_DN<13>")
	)
	(segment
		(start -373.0244 36.414367)
		(end -373.0244 35.621887)
		(width 0.127)
		(layer "In5.Cu")
		(net "PCIE_B2T_B1_TX_DN<13>")
	)
	(segment
		(start -391.6299 23.2283)
		(end -394.9319 23.2283)
		(width 0.127)
		(layer "In5.Cu")
		(net "PCIE_B2T_B1_TX_DN<13>")
	)
	(segment
		(start -373.398707 35.24758)
		(end -382.40462 35.24758)
		(width 0.127)
		(layer "In5.Cu")
		(net "PCIE_B2T_B1_TX_DN<13>")
	)
	(segment
		(start -373.0244 35.621887)
		(end -373.398707 35.24758)
		(width 0.127)
		(layer "In5.Cu")
		(net "PCIE_B2T_B1_TX_DN<13>")
	)
	(segment
		(start -382.40462 35.24758)
		(end -388.3914 29.2608)
		(width 0.127)
		(layer "In5.Cu")
		(net "PCIE_B2T_B1_TX_DN<13>")
	)
	(segment
		(start -388.3914 26.4668)
		(end -391.6299 23.2283)
		(width 0.127)
		(layer "In5.Cu")
		(net "PCIE_B2T_B1_TX_DN<13>")
	)
	(segment
		(start -371.269999 36.039999)
		(end -371.758949 36.528949)
		(width 0.127)
		(layer "In5.Cu")
		(net "PCIE_B2T_B1_TX_DN<13>")
	)
	(segment
		(start -394.9319 23.2283)
		(end -395.5923 23.8887)
		(width 0.127)
		(layer "In5.Cu")
		(net "PCIE_B2T_B1_TX_DN<13>")
	)
	(segment
		(start -371.904999 34.134999)
		(end -372.539999 33.499999)
		(width 0.127)
		(layer "F.Cu")
		(net "PCIE_B2T_B1_TX_DN<12>")
	)
	(via
		(at -372.539999 33.499999)
		(size 0.5588)
		(drill 0.254)
		(layers "F.Cu" "B.Cu")
		(net "PCIE_B2T_B1_TX_DN<12>")
	)
	(segment
		(start -396.132393 22.1869)
		(end -391.0965 22.1869)
		(width 0.127)
		(layer "In5.Cu")
		(net "PCIE_B2T_B1_TX_DN<12>")
	)
	(segment
		(start -374.2944 33.081887)
		(end -374.2944 33.874367)
		(width 0.127)
		(layer "In5.Cu")
		(net "PCIE_B2T_B1_TX_DN<12>")
	)
	(segment
		(start -374.668707 32.70758)
		(end -374.2944 33.081887)
		(width 0.127)
		(layer "In5.Cu")
		(net "PCIE_B2T_B1_TX_DN<12>")
	)
	(segment
		(start -391.0965 22.1869)
		(end -387.223 26.0604)
		(width 0.127)
		(layer "In5.Cu")
		(net "PCIE_B2T_B1_TX_DN<12>")
	)
	(segment
		(start -378.66828 32.70758)
		(end -374.668707 32.70758)
		(width 0.127)
		(layer "In5.Cu")
		(net "PCIE_B2T_B1_TX_DN<12>")
	)
	(segment
		(start -387.223 26.942707)
		(end -382.090587 32.07512)
		(width 0.127)
		(layer "In5.Cu")
		(net "PCIE_B2T_B1_TX_DN<12>")
	)
	(segment
		(start -387.223 26.0604)
		(end -387.223 26.942707)
		(width 0.127)
		(layer "In5.Cu")
		(net "PCIE_B2T_B1_TX_DN<12>")
	)
	(segment
		(start -398.460001 25.760002)
		(end -397.90605 26.313953)
		(width 0.127)
		(layer "In5.Cu")
		(net "PCIE_B2T_B1_TX_DN<12>")
	)
	(segment
		(start -397.5989 26.156409)
		(end -397.5989 23.653407)
		(width 0.127)
		(layer "In5.Cu")
		(net "PCIE_B2T_B1_TX_DN<12>")
	)
	(segment
		(start -379.30074 32.07512)
		(end -378.66828 32.70758)
		(width 0.127)
		(layer "In5.Cu")
		(net "PCIE_B2T_B1_TX_DN<12>")
	)
	(segment
		(start -373.028949 33.988949)
		(end -372.539999 33.499999)
		(width 0.127)
		(layer "In5.Cu")
		(net "PCIE_B2T_B1_TX_DN<12>")
	)
	(segment
		(start -374.2944 33.874367)
		(end -374.179818 33.988949)
		(width 0.127)
		(layer "In5.Cu")
		(net "PCIE_B2T_B1_TX_DN<12>")
	)
	(segment
		(start -374.179818 33.988949)
		(end -373.028949 33.988949)
		(width 0.127)
		(layer "In5.Cu")
		(net "PCIE_B2T_B1_TX_DN<12>")
	)
	(segment
		(start -397.756444 26.313953)
		(end -397.5989 26.156409)
		(width 0.127)
		(layer "In5.Cu")
		(net "PCIE_B2T_B1_TX_DN<12>")
	)
	(segment
		(start -382.090587 32.07512)
		(end -379.30074 32.07512)
		(width 0.127)
		(layer "In5.Cu")
		(net "PCIE_B2T_B1_TX_DN<12>")
	)
	(segment
		(start -397.90605 26.313953)
		(end -397.756444 26.313953)
		(width 0.127)
		(layer "In5.Cu")
		(net "PCIE_B2T_B1_TX_DN<12>")
	)
	(segment
		(start -397.5989 23.653407)
		(end -396.132393 22.1869)
		(width 0.127)
		(layer "In5.Cu")
		(net "PCIE_B2T_B1_TX_DN<12>")
	)
	(segment
		(start -370.634999 31.594999)
		(end -371.269999 30.959999)
		(width 0.127)
		(layer "F.Cu")
		(net "PCIE_B2T_B1_TX_DN<11>")
	)
	(via
		(at -371.269999 30.959999)
		(size 0.5588)
		(drill 0.254)
		(layers "F.Cu" "B.Cu")
		(net "PCIE_B2T_B1_TX_DN<11>")
	)
	(segment
		(start -390.6393 21.1201)
		(end -397.0401 21.1201)
		(width 0.127)
		(layer "In5.Cu")
		(net "PCIE_B2T_B1_TX_DN<11>")
	)
	(segment
		(start -399.906048 27.613953)
		(end -400.459999 27.060002)
		(width 0.127)
		(layer "In5.Cu")
		(net "PCIE_B2T_B1_TX_DN<11>")
	)
	(segment
		(start -399.6055 27.50152)
		(end -399.717933 27.613953)
		(width 0.127)
		(layer "In5.Cu")
		(net "PCIE_B2T_B1_TX_DN<11>")
	)
	(segment
		(start -371.269999 30.959999)
		(end -371.758949 31.448949)
		(width 0.127)
		(layer "In5.Cu")
		(net "PCIE_B2T_B1_TX_DN<11>")
	)
	(segment
		(start -371.758949 31.448949)
		(end -372.909818 31.448949)
		(width 0.127)
		(layer "In5.Cu")
		(net "PCIE_B2T_B1_TX_DN<11>")
	)
	(segment
		(start -372.909818 31.448949)
		(end -373.0244 31.334367)
		(width 0.127)
		(layer "In5.Cu")
		(net "PCIE_B2T_B1_TX_DN<11>")
	)
	(segment
		(start -373.0244 31.334367)
		(end -373.0244 30.541887)
		(width 0.127)
		(layer "In5.Cu")
		(net "PCIE_B2T_B1_TX_DN<11>")
	)
	(segment
		(start -399.6055 23.6855)
		(end -399.6055 27.50152)
		(width 0.127)
		(layer "In5.Cu")
		(net "PCIE_B2T_B1_TX_DN<11>")
	)
	(segment
		(start -381.59182 30.16758)
		(end -390.6393 21.1201)
		(width 0.127)
		(layer "In5.Cu")
		(net "PCIE_B2T_B1_TX_DN<11>")
	)
	(segment
		(start -373.0244 30.541887)
		(end -373.398707 30.16758)
		(width 0.127)
		(layer "In5.Cu")
		(net "PCIE_B2T_B1_TX_DN<11>")
	)
	(segment
		(start -399.717933 27.613953)
		(end -399.906048 27.613953)
		(width 0.127)
		(layer "In5.Cu")
		(net "PCIE_B2T_B1_TX_DN<11>")
	)
	(segment
		(start -397.0401 21.1201)
		(end -399.6055 23.6855)
		(width 0.127)
		(layer "In5.Cu")
		(net "PCIE_B2T_B1_TX_DN<11>")
	)
	(segment
		(start -373.398707 30.16758)
		(end -381.59182 30.16758)
		(width 0.127)
		(layer "In5.Cu")
		(net "PCIE_B2T_B1_TX_DN<11>")
	)
	(segment
		(start -371.904999 29.054999)
		(end -372.539999 28.419999)
		(width 0.127)
		(layer "F.Cu")
		(net "PCIE_B2T_B1_TX_DN<10>")
	)
	(via
		(at -372.539999 28.419999)
		(size 0.5588)
		(drill 0.254)
		(layers "F.Cu" "B.Cu")
		(net "PCIE_B2T_B1_TX_DN<10>")
	)
	(segment
		(start -373.028949 28.908949)
		(end -372.539999 28.419999)
		(width 0.127)
		(layer "In5.Cu")
		(net "PCIE_B2T_B1_TX_DN<10>")
	)
	(segment
		(start -374.668707 27.62758)
		(end -374.2944 28.001887)
		(width 0.127)
		(layer "In5.Cu")
		(net "PCIE_B2T_B1_TX_DN<10>")
	)
	(segment
		(start -401.667863 26.313953)
		(end -401.6121 26.25819)
		(width 0.127)
		(layer "In5.Cu")
		(net "PCIE_B2T_B1_TX_DN<10>")
	)
	(segment
		(start -379.01372 27.62758)
		(end -374.668707 27.62758)
		(width 0.127)
		(layer "In5.Cu")
		(net "PCIE_B2T_B1_TX_DN<10>")
	)
	(segment
		(start -401.6121 23.628007)
		(end -398.062793 20.0787)
		(width 0.127)
		(layer "In5.Cu")
		(net "PCIE_B2T_B1_TX_DN<10>")
	)
	(segment
		(start -385.3688 23.285107)
		(end -381.656247 26.99766)
		(width 0.127)
		(layer "In5.Cu")
		(net "PCIE_B2T_B1_TX_DN<10>")
	)
	(segment
		(start -402.46 25.760002)
		(end -401.906049 26.313953)
		(width 0.127)
		(layer "In5.Cu")
		(net "PCIE_B2T_B1_TX_DN<10>")
	)
	(segment
		(start -401.6121 26.25819)
		(end -401.6121 23.628007)
		(width 0.127)
		(layer "In5.Cu")
		(net "PCIE_B2T_B1_TX_DN<10>")
	)
	(segment
		(start -401.906049 26.313953)
		(end -401.667863 26.313953)
		(width 0.127)
		(layer "In5.Cu")
		(net "PCIE_B2T_B1_TX_DN<10>")
	)
	(segment
		(start -381.656247 26.99766)
		(end -379.64364 26.99766)
		(width 0.127)
		(layer "In5.Cu")
		(net "PCIE_B2T_B1_TX_DN<10>")
	)
	(segment
		(start -374.179818 28.908949)
		(end -373.028949 28.908949)
		(width 0.127)
		(layer "In5.Cu")
		(net "PCIE_B2T_B1_TX_DN<10>")
	)
	(segment
		(start -398.062793 20.0787)
		(end -390.1567 20.0787)
		(width 0.127)
		(layer "In5.Cu")
		(net "PCIE_B2T_B1_TX_DN<10>")
	)
	(segment
		(start -390.1567 20.0787)
		(end -386.950293 23.285107)
		(width 0.127)
		(layer "In5.Cu")
		(net "PCIE_B2T_B1_TX_DN<10>")
	)
	(segment
		(start -374.2944 28.794367)
		(end -374.179818 28.908949)
		(width 0.127)
		(layer "In5.Cu")
		(net "PCIE_B2T_B1_TX_DN<10>")
	)
	(segment
		(start -379.64364 26.99766)
		(end -379.01372 27.62758)
		(width 0.127)
		(layer "In5.Cu")
		(net "PCIE_B2T_B1_TX_DN<10>")
	)
	(segment
		(start -374.2944 28.001887)
		(end -374.2944 28.794367)
		(width 0.127)
		(layer "In5.Cu")
		(net "PCIE_B2T_B1_TX_DN<10>")
	)
	(segment
		(start -386.950293 23.285107)
		(end -385.3688 23.285107)
		(width 0.127)
		(layer "In5.Cu")
		(net "PCIE_B2T_B1_TX_DN<10>")
	)
	(segment
		(start -374.444999 23.974999)
		(end -375.079999 23.339999)
		(width 0.127)
		(layer "F.Cu")
		(net "PCIE_B2T_B1_TX_DN<0>")
	)
	(via
		(at -375.079999 23.339999)
		(size 0.5588)
		(drill 0.254)
		(layers "F.Cu" "B.Cu")
		(net "PCIE_B2T_B1_TX_DN<0>")
	)
	(segment
		(start -405.912399 30.507602)
		(end -406.46 29.960001)
		(width 0.127)
		(layer "B.Cu")
		(net "PCIE_B2T_B1_TX_DN<0>")
	)
	(segment
		(start -376.8217 22.9616)
		(end -377.22556 22.55774)
		(width 0.127)
		(layer "B.Cu")
		(net "PCIE_B2T_B1_TX_DN<0>")
	)
	(segment
		(start -376.67438 23.822599)
		(end -376.8217 23.675279)
		(width 0.127)
		(layer "B.Cu")
		(net "PCIE_B2T_B1_TX_DN<0>")
	)
	(segment
		(start -375.562599 23.822599)
		(end -376.67438 23.822599)
		(width 0.127)
		(layer "B.Cu")
		(net "PCIE_B2T_B1_TX_DN<0>")
	)
	(segment
		(start -375.079999 23.339999)
		(end -375.562599 23.822599)
		(width 0.127)
		(layer "B.Cu")
		(net "PCIE_B2T_B1_TX_DN<0>")
	)
	(segment
		(start -380.19228 23.41626)
		(end -381.231887 23.41626)
		(width 0.127)
		(layer "B.Cu")
		(net "PCIE_B2T_B1_TX_DN<0>")
	)
	(segment
		(start -377.22556 22.55774)
		(end -379.33376 22.55774)
		(width 0.127)
		(layer "B.Cu")
		(net "PCIE_B2T_B1_TX_DN<0>")
	)
	(segment
		(start -387.604747 17.0434)
		(end -398.8816 17.0434)
		(width 0.127)
		(layer "B.Cu")
		(net "PCIE_B2T_B1_TX_DN<0>")
	)
	(segment
		(start -405.785399 30.507602)
		(end -405.912399 30.507602)
		(width 0.127)
		(layer "B.Cu")
		(net "PCIE_B2T_B1_TX_DN<0>")
	)
	(segment
		(start -381.231887 23.41626)
		(end -387.604747 17.0434)
		(width 0.127)
		(layer "B.Cu")
		(net "PCIE_B2T_B1_TX_DN<0>")
	)
	(segment
		(start -398.8816 17.0434)
		(end -405.6126 23.7744)
		(width 0.127)
		(layer "B.Cu")
		(net "PCIE_B2T_B1_TX_DN<0>")
	)
	(segment
		(start -405.6126 30.334803)
		(end -405.785399 30.507602)
		(width 0.127)
		(layer "B.Cu")
		(net "PCIE_B2T_B1_TX_DN<0>")
	)
	(segment
		(start -376.8217 23.675279)
		(end -376.8217 22.9616)
		(width 0.127)
		(layer "B.Cu")
		(net "PCIE_B2T_B1_TX_DN<0>")
	)
	(segment
		(start -405.6126 23.7744)
		(end -405.6126 30.334803)
		(width 0.127)
		(layer "B.Cu")
		(net "PCIE_B2T_B1_TX_DN<0>")
	)
	(segment
		(start -379.33376 22.55774)
		(end -380.19228 23.41626)
		(width 0.127)
		(layer "B.Cu")
		(net "PCIE_B2T_B1_TX_DN<0>")
	)
	(segment
		(start -44.005398 13.297002)
		(end -43.9928 13.3096)
		(width 0.3048)
		(layer "F.Cu")
		(net "P3V3_B2_QSFP")
	)
	(segment
		(start -80.736201 7.8486)
		(end -81.8642 7.8486)
		(width 0.381)
		(layer "F.Cu")
		(net "P3V3_B2_QSFP")
	)
	(segment
		(start -61.785401 45.519203)
		(end -61.785401 46.281203)
		(width 0.381)
		(layer "F.Cu")
		(net "P3V3_B2_QSFP")
	)
	(segment
		(start -44.155599 8.75538)
		(end -43.2308 8.75538)
		(width 0.3048)
		(layer "F.Cu")
		(net "P3V3_B2_QSFP")
	)
	(segment
		(start -75.942802 1.130402)
		(end -76.7842 1.130402)
		(width 0.381)
		(layer "F.Cu")
		(net "P3V3_B2_QSFP")
	)
	(segment
		(start -74.711799 10.9982)
		(end -73.787 10.9982)
		(width 0.381)
		(layer "F.Cu")
		(net "P3V3_B2_QSFP")
	)
	(segment
		(start -44.1325 4.191)
		(end -43.2562 4.191)
		(width 0.3048)
		(layer "F.Cu")
		(net "P3V3_B2_QSFP")
	)
	(segment
		(start -76.9112 9.652)
		(end -76.9366 9.6266)
		(width 0.381)
		(layer "F.Cu")
		(net "P3V3_B2_QSFP")
	)
	(segment
		(start -60.388401 45.519203)
		(end -60.388401 46.3042)
		(width 0.381)
		(layer "F.Cu")
		(net "P3V3_B2_QSFP")
	)
	(segment
		(start -111.495601 9.0424)
		(end -112.257601 9.0424)
		(width 0.381)
		(layer "F.Cu")
		(net "P3V3_B2_QSFP")
	)
	(segment
		(start -76.011801 9.652)
		(end -76.9112 9.652)
		(width 0.381)
		(layer "F.Cu")
		(net "P3V3_B2_QSFP")
	)
	(segment
		(start -44.996001 11.979001)
		(end -44.180399 11.979001)
		(width 0.3048)
		(layer "F.Cu")
		(net "P3V3_B2_QSFP")
	)
	(segment
		(start -80.736201 0.381)
		(end -81.752201 0.381)
		(width 0.3048)
		(layer "F.Cu")
		(net "P3V3_B2_QSFP")
	)
	(segment
		(start -111.495601 16.0274)
		(end -112.257601 16.0274)
		(width 0.381)
		(layer "F.Cu")
		(net "P3V3_B2_QSFP")
	)
	(segment
		(start -44.180999 2.54)
		(end -43.307 2.54)
		(width 0.3048)
		(layer "F.Cu")
		(net "P3V3_B2_QSFP")
	)
	(segment
		(start -45.671999 6.1722)
		(end -45.722799 6.223)
		(width 0.3048)
		(layer "F.Cu")
		(net "P3V3_B2_QSFP")
	)
	(segment
		(start -111.495601 18.8214)
		(end -112.257601 18.8214)
		(width 0.381)
		(layer "F.Cu")
		(net "P3V3_B2_QSFP")
	)
	(segment
		(start -45.671999 5.4102)
		(end -45.671999 6.1722)
		(width 0.3048)
		(layer "F.Cu")
		(net "P3V3_B2_QSFP")
	)
	(segment
		(start -80.768802 6.337402)
		(end -81.6102 6.337402)
		(width 0.381)
		(layer "F.Cu")
		(net "P3V3_B2_QSFP")
	)
	(segment
		(start -54.5084 45.6946)
		(end -54.483 45.6692)
		(width 0.3048)
		(layer "F.Cu")
		(net "P3V3_B2_QSFP")
	)
	(segment
		(start -111.495601 13.2334)
		(end -112.257601 13.2334)
		(width 0.381)
		(layer "F.Cu")
		(net "P3V3_B2_QSFP")
	)
	(segment
		(start -45.417999 -1.0922)
		(end -45.468799 -1.143)
		(width 0.3048)
		(layer "F.Cu")
		(net "P3V3_B2_QSFP")
	)
	(segment
		(start -45.417999 -0.254)
		(end -45.417999 -1.0922)
		(width 0.3048)
		(layer "F.Cu")
		(net "P3V3_B2_QSFP")
	)
	(segment
		(start -66.423799 45.72)
		(end -67.322598 45.72)
		(width 0.3048)
		(layer "F.Cu")
		(net "P3V3_B2_QSFP")
	)
	(segment
		(start -73.787 10.9982)
		(end -73.7616 10.9728)
		(width 0.381)
		(layer "F.Cu")
		(net "P3V3_B2_QSFP")
	)
	(segment
		(start -81.8642 7.8486)
		(end -81.8896 7.874)
		(width 0.381)
		(layer "F.Cu")
		(net "P3V3_B2_QSFP")
	)
	(segment
		(start -111.495601 14.6304)
		(end -112.257601 14.6304)
		(width 0.381)
		(layer "F.Cu")
		(net "P3V3_B2_QSFP")
	)
	(segment
		(start -44.981 13.297002)
		(end -44.005398 13.297002)
		(width 0.3048)
		(layer "F.Cu")
		(net "P3V3_B2_QSFP")
	)
	(segment
		(start -74.711799 12.3952)
		(end -74.711799 10.9982)
		(width 0.381)
		(layer "F.Cu")
		(net "P3V3_B2_QSFP")
	)
	(segment
		(start -111.495601 10.4394)
		(end -112.257601 10.4394)
		(width 0.381)
		(layer "F.Cu")
		(net "P3V3_B2_QSFP")
	)
	(segment
		(start -44.180399 11.979001)
		(end -44.1452 12.0142)
		(width 0.3048)
		(layer "F.Cu")
		(net "P3V3_B2_QSFP")
	)
	(segment
		(start -75.942802 6.591402)
		(end -76.7842 6.591402)
		(width 0.381)
		(layer "F.Cu")
		(net "P3V3_B2_QSFP")
	)
	(segment
		(start -74.679198 2.476398)
		(end -73.8378 2.476398)
		(width 0.381)
		(layer "F.Cu")
		(net "P3V3_B2_QSFP")
	)
	(segment
		(start -55.470801 45.6946)
		(end -54.5084 45.6946)
		(width 0.3048)
		(layer "F.Cu")
		(net "P3V3_B2_QSFP")
	)
	(segment
		(start -114.0714 16.215599)
		(end -114.0714 15.453599)
		(width 0.381)
		(layer "F.Cu")
		(net "P3V3_B2_QSFP")
	)
	(segment
		(start -67.322598 45.72)
		(end -67.3608 45.681798)
		(width 0.3048)
		(layer "F.Cu")
		(net "P3V3_B2_QSFP")
	)
	(segment
		(start -80.7488 3.461601)
		(end -81.7118 3.461601)
		(width 0.381)
		(layer "F.Cu")
		(net "P3V3_B2_QSFP")
	)
	(via
		(at -50.0126 44.831)
		(size 0.5588)
		(drill 0.254)
		(layers "F.Cu" "B.Cu")
		(net "P3V3_B2_QSFP")
	)
	(via
		(at -45.671999 5.4102)
		(size 0.5588)
		(drill 0.254)
		(layers "F.Cu" "B.Cu")
		(net "P3V3_B2_QSFP")
	)
	(via
		(at -81.752201 0.381)
		(size 0.5588)
		(drill 0.254)
		(layers "F.Cu" "B.Cu")
		(net "P3V3_B2_QSFP")
	)
	(via
		(at -81.6102 6.337402)
		(size 0.5588)
		(drill 0.254)
		(layers "F.Cu" "B.Cu")
		(net "P3V3_B2_QSFP")
	)
	(via
		(at -112.257601 9.0424)
		(size 0.5588)
		(drill 0.254)
		(layers "F.Cu" "B.Cu")
		(net "P3V3_B2_QSFP")
	)
	(via
		(at -45.468799 -1.143)
		(size 0.5588)
		(drill 0.254)
		(layers "F.Cu" "B.Cu")
		(net "P3V3_B2_QSFP")
	)
	(via
		(at -43.2308 8.75538)
		(size 0.5588)
		(drill 0.254)
		(layers "F.Cu" "B.Cu")
		(net "P3V3_B2_QSFP")
	)
	(via
		(at -81.7118 3.461601)
		(size 0.5588)
		(drill 0.254)
		(layers "F.Cu" "B.Cu")
		(net "P3V3_B2_QSFP")
	)
	(via
		(at -81.8896 7.874)
		(size 0.5588)
		(drill 0.254)
		(layers "F.Cu" "B.Cu")
		(net "P3V3_B2_QSFP")
	)
	(via
		(at -43.2562 4.191)
		(size 0.5588)
		(drill 0.254)
		(layers "F.Cu" "B.Cu")
		(net "P3V3_B2_QSFP")
	)
	(via
		(at -76.9366 9.6266)
		(size 0.5588)
		(drill 0.254)
		(layers "F.Cu" "B.Cu")
		(net "P3V3_B2_QSFP")
	)
	(via
		(at -67.3608 45.681798)
		(size 0.5588)
		(drill 0.254)
		(layers "F.Cu" "B.Cu")
		(net "P3V3_B2_QSFP")
	)
	(via
		(at -43.9928 13.3096)
		(size 0.5588)
		(drill 0.254)
		(layers "F.Cu" "B.Cu")
		(net "P3V3_B2_QSFP")
	)
	(via
		(at -112.257601 14.6304)
		(size 0.5588)
		(drill 0.254)
		(layers "F.Cu" "B.Cu")
		(net "P3V3_B2_QSFP")
	)
	(via
		(at -52.3494 44.8564)
		(size 0.5588)
		(drill 0.254)
		(layers "F.Cu" "B.Cu")
		(net "P3V3_B2_QSFP")
	)
	(via
		(at -51.2064 44.8564)
		(size 0.5588)
		(drill 0.254)
		(layers "F.Cu" "B.Cu")
		(net "P3V3_B2_QSFP")
	)
	(via
		(at -112.257601 13.2334)
		(size 0.5588)
		(drill 0.254)
		(layers "F.Cu" "B.Cu")
		(net "P3V3_B2_QSFP")
	)
	(via
		(at -112.257601 18.8214)
		(size 0.5588)
		(drill 0.254)
		(layers "F.Cu" "B.Cu")
		(net "P3V3_B2_QSFP")
	)
	(via
		(at -76.7842 6.591402)
		(size 0.5588)
		(drill 0.254)
		(layers "F.Cu" "B.Cu")
		(net "P3V3_B2_QSFP")
	)
	(via
		(at -54.483 45.6692)
		(size 0.5588)
		(drill 0.254)
		(layers "F.Cu" "B.Cu")
		(net "P3V3_B2_QSFP")
	)
	(via
		(at -44.1452 12.0142)
		(size 0.5588)
		(drill 0.254)
		(layers "F.Cu" "B.Cu")
		(net "P3V3_B2_QSFP")
	)
	(via
		(at -112.257601 16.0274)
		(size 0.5588)
		(drill 0.254)
		(layers "F.Cu" "B.Cu")
		(net "P3V3_B2_QSFP")
	)
	(via
		(at -60.388401 46.3042)
		(size 0.5588)
		(drill 0.254)
		(layers "F.Cu" "B.Cu")
		(net "P3V3_B2_QSFP")
	)
	(via
		(at -73.8378 2.476398)
		(size 0.5588)
		(drill 0.254)
		(layers "F.Cu" "B.Cu")
		(net "P3V3_B2_QSFP")
	)
	(via
		(at -61.785401 46.281203)
		(size 0.5588)
		(drill 0.254)
		(layers "F.Cu" "B.Cu")
		(net "P3V3_B2_QSFP")
	)
	(via
		(at -43.307 2.54)
		(size 0.5588)
		(drill 0.254)
		(layers "F.Cu" "B.Cu")
		(net "P3V3_B2_QSFP")
	)
	(via
		(at -112.257601 10.4394)
		(size 0.5588)
		(drill 0.254)
		(layers "F.Cu" "B.Cu")
		(net "P3V3_B2_QSFP")
	)
	(via
		(at -73.7616 10.9728)
		(size 0.5588)
		(drill 0.254)
		(layers "F.Cu" "B.Cu")
		(net "P3V3_B2_QSFP")
	)
	(via
		(at -114.0714 15.453599)
		(size 0.5588)
		(drill 0.254)
		(layers "F.Cu" "B.Cu")
		(net "P3V3_B2_QSFP")
	)
	(via
		(at -76.7842 1.130402)
		(size 0.5588)
		(drill 0.254)
		(layers "F.Cu" "B.Cu")
		(net "P3V3_B2_QSFP")
	)
	(segment
		(start -301.589201 7.4676)
		(end -302.7172 7.4676)
		(width 0.381)
		(layer "F.Cu")
		(net "P3V3_B1_QSFP")
	)
	(segment
		(start -282.785401 45.519203)
		(end -282.785401 46.281203)
		(width 0.381)
		(layer "F.Cu")
		(net "P3V3_B1_QSFP")
	)
	(segment
		(start -295.513999 8.382)
		(end -294.6146 8.382)
		(width 0.381)
		(layer "F.Cu")
		(net "P3V3_B1_QSFP")
	)
	(segment
		(start -332.120001 9.0678)
		(end -332.882001 9.0678)
		(width 0.381)
		(layer "F.Cu")
		(net "P3V3_B1_QSFP")
	)
	(segment
		(start -297.700598 1.384402)
		(end -297.7134 1.3716)
		(width 0.381)
		(layer "F.Cu")
		(net "P3V3_B1_QSFP")
	)
	(segment
		(start -301.621802 5.956402)
		(end -302.4632 5.956402)
		(width 0.381)
		(layer "F.Cu")
		(net "P3V3_B1_QSFP")
	)
	(segment
		(start -275.526398 45.6438)
		(end -275.4884 45.681798)
		(width 0.381)
		(layer "F.Cu")
		(net "P3V3_B1_QSFP")
	)
	(segment
		(start -287.365801 45.681798)
		(end -288.183 45.681798)
		(width 0.3048)
		(layer "F.Cu")
		(net "P3V3_B1_QSFP")
	)
	(segment
		(start -295.513999 11.176)
		(end -294.5892 11.176)
		(width 0.381)
		(layer "F.Cu")
		(net "P3V3_B1_QSFP")
	)
	(segment
		(start -264.5156 4.2164)
		(end -264.4902 4.191)
		(width 0.381)
		(layer "F.Cu")
		(net "P3V3_B1_QSFP")
	)
	(segment
		(start -332.120001 14.6558)
		(end -332.882001 14.6558)
		(width 0.381)
		(layer "F.Cu")
		(net "P3V3_B1_QSFP")
	)
	(segment
		(start -294.6146 8.382)
		(end -294.5892 8.4074)
		(width 0.381)
		(layer "F.Cu")
		(net "P3V3_B1_QSFP")
	)
	(segment
		(start -266.931399 6.479799)
		(end -267.0556 6.604)
		(width 0.381)
		(layer "F.Cu")
		(net "P3V3_B1_QSFP")
	)
	(segment
		(start -301.589201 0)
		(end -302.641 0)
		(width 0.381)
		(layer "F.Cu")
		(net "P3V3_B1_QSFP")
	)
	(segment
		(start -301.6018 3.080601)
		(end -302.5648 3.080601)
		(width 0.381)
		(layer "F.Cu")
		(net "P3V3_B1_QSFP")
	)
	(segment
		(start -265.5697 4.2164)
		(end -264.5156 4.2164)
		(width 0.381)
		(layer "F.Cu")
		(net "P3V3_B1_QSFP")
	)
	(segment
		(start -332.120001 13.2588)
		(end -332.882001 13.2588)
		(width 0.381)
		(layer "F.Cu")
		(net "P3V3_B1_QSFP")
	)
	(segment
		(start -265.467998 13.424002)
		(end -265.4554 13.4366)
		(width 0.381)
		(layer "F.Cu")
		(net "P3V3_B1_QSFP")
	)
	(segment
		(start -266.905999 0)
		(end -266.905999 -0.6604)
		(width 0.381)
		(layer "F.Cu")
		(net "P3V3_B1_QSFP")
	)
	(segment
		(start -332.120001 16.0528)
		(end -332.882001 16.0528)
		(width 0.381)
		(layer "F.Cu")
		(net "P3V3_B1_QSFP")
	)
	(segment
		(start -265.541999 9.641601)
		(end -265.5316 9.652)
		(width 0.381)
		(layer "F.Cu")
		(net "P3V3_B1_QSFP")
	)
	(segment
		(start -296.795802 1.384402)
		(end -297.700598 1.384402)
		(width 0.381)
		(layer "F.Cu")
		(net "P3V3_B1_QSFP")
	)
	(segment
		(start -281.388401 45.519203)
		(end -281.388401 46.3042)
		(width 0.381)
		(layer "F.Cu")
		(net "P3V3_B1_QSFP")
	)
	(segment
		(start -294.5892 11.176)
		(end -294.5638 11.1506)
		(width 0.381)
		(layer "F.Cu")
		(net "P3V3_B1_QSFP")
	)
	(segment
		(start -265.541999 2.54)
		(end -264.5156 2.54)
		(width 0.381)
		(layer "F.Cu")
		(net "P3V3_B1_QSFP")
	)
	(segment
		(start -332.120001 18.8468)
		(end -332.882001 18.8468)
		(width 0.381)
		(layer "F.Cu")
		(net "P3V3_B1_QSFP")
	)
	(segment
		(start -266.362 13.424002)
		(end -265.467998 13.424002)
		(width 0.381)
		(layer "F.Cu")
		(net "P3V3_B1_QSFP")
	)
	(segment
		(start -334.6958 17.541001)
		(end -334.6958 18.4658)
		(width 0.381)
		(layer "F.Cu")
		(net "P3V3_B1_QSFP")
	)
	(segment
		(start -264.5156 2.54)
		(end -264.4902 2.5654)
		(width 0.381)
		(layer "F.Cu")
		(net "P3V3_B1_QSFP")
	)
	(segment
		(start -295.513999 12.573)
		(end -295.513999 11.176)
		(width 0.381)
		(layer "F.Cu")
		(net "P3V3_B1_QSFP")
	)
	(segment
		(start -332.120001 10.4648)
		(end -332.882001 10.4648)
		(width 0.381)
		(layer "F.Cu")
		(net "P3V3_B1_QSFP")
	)
	(segment
		(start -266.192 12.093199)
		(end -265.265002 12.093199)
		(width 0.381)
		(layer "F.Cu")
		(net "P3V3_B1_QSFP")
	)
	(segment
		(start -265.265002 12.093199)
		(end -265.2522 12.106001)
		(width 0.381)
		(layer "F.Cu")
		(net "P3V3_B1_QSFP")
	)
	(segment
		(start -296.795802 4.127602)
		(end -297.6372 4.127602)
		(width 0.381)
		(layer "F.Cu")
		(net "P3V3_B1_QSFP")
	)
	(segment
		(start -296.795802 6.845402)
		(end -297.6372 6.845402)
		(width 0.381)
		(layer "F.Cu")
		(net "P3V3_B1_QSFP")
	)
	(segment
		(start -265.541999 8.636)
		(end -265.541999 9.641601)
		(width 0.381)
		(layer "F.Cu")
		(net "P3V3_B1_QSFP")
	)
	(segment
		(start -287.365801 45.681798)
		(end -287.352999 45.6946)
		(width 0.3048)
		(layer "F.Cu")
		(net "P3V3_B1_QSFP")
	)
	(segment
		(start -302.7172 7.4676)
		(end -302.7426 7.493)
		(width 0.381)
		(layer "F.Cu")
		(net "P3V3_B1_QSFP")
	)
	(segment
		(start -276.476201 45.6438)
		(end -275.526398 45.6438)
		(width 0.381)
		(layer "F.Cu")
		(net "P3V3_B1_QSFP")
	)
	(segment
		(start -266.931399 5.842)
		(end -266.931399 6.479799)
		(width 0.381)
		(layer "F.Cu")
		(net "P3V3_B1_QSFP")
	)
	(via
		(at -332.882001 13.2588)
		(size 0.5588)
		(drill 0.254)
		(layers "F.Cu" "B.Cu")
		(net "P3V3_B1_QSFP")
	)
	(via
		(at -332.882001 10.4648)
		(size 0.5588)
		(drill 0.254)
		(layers "F.Cu" "B.Cu")
		(net "P3V3_B1_QSFP")
	)
	(via
		(at -332.882001 18.8468)
		(size 0.5588)
		(drill 0.254)
		(layers "F.Cu" "B.Cu")
		(net "P3V3_B1_QSFP")
	)
	(via
		(at -282.785401 46.281203)
		(size 0.5588)
		(drill 0.254)
		(layers "F.Cu" "B.Cu")
		(net "P3V3_B1_QSFP")
	)
	(via
		(at -266.905999 -0.6604)
		(size 0.5588)
		(drill 0.254)
		(layers "F.Cu" "B.Cu")
		(net "P3V3_B1_QSFP")
	)
	(via
		(at -297.6372 4.127602)
		(size 0.5588)
		(drill 0.254)
		(layers "F.Cu" "B.Cu")
		(net "P3V3_B1_QSFP")
	)
	(via
		(at -265.2522 12.106001)
		(size 0.5588)
		(drill 0.254)
		(layers "F.Cu" "B.Cu")
		(net "P3V3_B1_QSFP")
	)
	(via
		(at -297.7134 1.3716)
		(size 0.5588)
		(drill 0.254)
		(layers "F.Cu" "B.Cu")
		(net "P3V3_B1_QSFP")
	)
	(via
		(at -288.183 45.681798)
		(size 0.5588)
		(drill 0.254)
		(layers "F.Cu" "B.Cu")
		(net "P3V3_B1_QSFP")
	)
	(via
		(at -334.6958 18.4658)
		(size 0.5588)
		(drill 0.254)
		(layers "F.Cu" "B.Cu")
		(net "P3V3_B1_QSFP")
	)
	(via
		(at -294.5892 8.4074)
		(size 0.5588)
		(drill 0.254)
		(layers "F.Cu" "B.Cu")
		(net "P3V3_B1_QSFP")
	)
	(via
		(at -279.2476 22.9108)
		(size 0.5588)
		(drill 0.254)
		(layers "F.Cu" "B.Cu")
		(net "P3V3_B1_QSFP")
	)
	(via
		(at -277.7236 22.9108)
		(size 0.5588)
		(drill 0.254)
		(layers "F.Cu" "B.Cu")
		(net "P3V3_B1_QSFP")
	)
	(via
		(at -302.641 0)
		(size 0.5588)
		(drill 0.254)
		(layers "F.Cu" "B.Cu")
		(net "P3V3_B1_QSFP")
	)
	(via
		(at -264.4902 4.191)
		(size 0.5588)
		(drill 0.254)
		(layers "F.Cu" "B.Cu")
		(net "P3V3_B1_QSFP")
	)
	(via
		(at -332.882001 14.6558)
		(size 0.5588)
		(drill 0.254)
		(layers "F.Cu" "B.Cu")
		(net "P3V3_B1_QSFP")
	)
	(via
		(at -267.0556 6.604)
		(size 0.5588)
		(drill 0.254)
		(layers "F.Cu" "B.Cu")
		(net "P3V3_B1_QSFP")
	)
	(via
		(at -332.882001 9.0678)
		(size 0.5588)
		(drill 0.254)
		(layers "F.Cu" "B.Cu")
		(net "P3V3_B1_QSFP")
	)
	(via
		(at -297.6372 6.845402)
		(size 0.5588)
		(drill 0.254)
		(layers "F.Cu" "B.Cu")
		(net "P3V3_B1_QSFP")
	)
	(via
		(at -265.5316 9.652)
		(size 0.5588)
		(drill 0.254)
		(layers "F.Cu" "B.Cu")
		(net "P3V3_B1_QSFP")
	)
	(via
		(at -302.4632 5.956402)
		(size 0.5588)
		(drill 0.254)
		(layers "F.Cu" "B.Cu")
		(net "P3V3_B1_QSFP")
	)
	(via
		(at -302.7426 7.493)
		(size 0.5588)
		(drill 0.254)
		(layers "F.Cu" "B.Cu")
		(net "P3V3_B1_QSFP")
	)
	(via
		(at -264.4902 2.5654)
		(size 0.5588)
		(drill 0.254)
		(layers "F.Cu" "B.Cu")
		(net "P3V3_B1_QSFP")
	)
	(via
		(at -275.4884 45.681798)
		(size 0.5588)
		(drill 0.254)
		(layers "F.Cu" "B.Cu")
		(net "P3V3_B1_QSFP")
	)
	(via
		(at -332.882001 16.0528)
		(size 0.5588)
		(drill 0.254)
		(layers "F.Cu" "B.Cu")
		(net "P3V3_B1_QSFP")
	)
	(via
		(at -265.4554 13.4366)
		(size 0.5588)
		(drill 0.254)
		(layers "F.Cu" "B.Cu")
		(net "P3V3_B1_QSFP")
	)
	(via
		(at -302.5648 3.080601)
		(size 0.5588)
		(drill 0.254)
		(layers "F.Cu" "B.Cu")
		(net "P3V3_B1_QSFP")
	)
	(via
		(at -294.5638 11.1506)
		(size 0.5588)
		(drill 0.254)
		(layers "F.Cu" "B.Cu")
		(net "P3V3_B1_QSFP")
	)
	(via
		(at -272.542 22.9362)
		(size 0.5588)
		(drill 0.254)
		(layers "F.Cu" "B.Cu")
		(net "P3V3_B1_QSFP")
	)
	(via
		(at -281.388401 46.3042)
		(size 0.5588)
		(drill 0.254)
		(layers "F.Cu" "B.Cu")
		(net "P3V3_B1_QSFP")
	)
	(segment
		(start -95.05 43.840001)
		(end -95.05 45.211601)
		(width 0.3048)
		(layer "F.Cu")
		(net "P3V3_40G_B2_VCC_TX")
	)
	(via
		(at -46.4566 7.5692)
		(size 0.5588)
		(drill 0.254)
		(layers "F.Cu" "B.Cu")
		(net "P3V3_40G_B2_VCC_TX")
	)
	(via
		(at -95.05 45.211601)
		(size 0.5588)
		(drill 0.254)
		(layers "F.Cu" "B.Cu")
		(net "P3V3_40G_B2_VCC_TX")
	)
	(via
		(at -48.3362 7.3406)
		(size 0.5588)
		(drill 0.254)
		(layers "F.Cu" "B.Cu")
		(net "P3V3_40G_B2_VCC_TX")
	)
	(segment
		(start -94.6404 41.8846)
		(end -94.6404 38.55466)
		(width 0.508)
		(layer "In3.Cu")
		(net "P3V3_40G_B2_VCC_TX")
	)
	(segment
		(start -91.84894 35.7632)
		(end -90.34526 35.7632)
		(width 0.508)
		(layer "In3.Cu")
		(net "P3V3_40G_B2_VCC_TX")
	)
	(segment
		(start -82.42046 27.8384)
		(end -75.5396 27.8384)
		(width 0.508)
		(layer "In3.Cu")
		(net "P3V3_40G_B2_VCC_TX")
	)
	(segment
		(start -95.05 45.211601)
		(end -95.05 42.2942)
		(width 0.508)
		(layer "In3.Cu")
		(net "P3V3_40G_B2_VCC_TX")
	)
	(segment
		(start -46.6852 7.3406)
		(end -46.4566 7.5692)
		(width 0.508)
		(layer "In3.Cu")
		(net "P3V3_40G_B2_VCC_TX")
	)
	(segment
		(start -94.6404 38.55466)
		(end -91.84894 35.7632)
		(width 0.508)
		(layer "In3.Cu")
		(net "P3V3_40G_B2_VCC_TX")
	)
	(segment
		(start -60.3377 13.9954)
		(end -53.6829 7.3406)
		(width 0.508)
		(layer "In3.Cu")
		(net "P3V3_40G_B2_VCC_TX")
	)
	(segment
		(start -53.6829 7.3406)
		(end -48.3362 7.3406)
		(width 0.508)
		(layer "In3.Cu")
		(net "P3V3_40G_B2_VCC_TX")
	)
	(segment
		(start -60.9346 13.9954)
		(end -60.3377 13.9954)
		(width 0.508)
		(layer "In3.Cu")
		(net "P3V3_40G_B2_VCC_TX")
	)
	(segment
		(start -67.3862 19.685)
		(end -66.6242 19.685)
		(width 0.508)
		(layer "In3.Cu")
		(net "P3V3_40G_B2_VCC_TX")
	)
	(segment
		(start -75.5396 27.8384)
		(end -67.3862 19.685)
		(width 0.508)
		(layer "In3.Cu")
		(net "P3V3_40G_B2_VCC_TX")
	)
	(segment
		(start -66.6242 19.685)
		(end -60.9346 13.9954)
		(width 0.508)
		(layer "In3.Cu")
		(net "P3V3_40G_B2_VCC_TX")
	)
	(segment
		(start -95.05 42.2942)
		(end -94.6404 41.8846)
		(width 0.508)
		(layer "In3.Cu")
		(net "P3V3_40G_B2_VCC_TX")
	)
	(segment
		(start -48.3362 7.3406)
		(end -46.6852 7.3406)
		(width 0.508)
		(layer "In3.Cu")
		(net "P3V3_40G_B2_VCC_TX")
	)
	(segment
		(start -90.34526 35.7632)
		(end -82.42046 27.8384)
		(width 0.508)
		(layer "In3.Cu")
		(net "P3V3_40G_B2_VCC_TX")
	)
	(segment
		(start -95.45 39.1192)
		(end -95.4532 39.116)
		(width 0.3048)
		(layer "F.Cu")
		(net "P3V3_40G_B2_VCC_RX")
	)
	(segment
		(start -95.45 41.340001)
		(end -95.45 39.1192)
		(width 0.3048)
		(layer "F.Cu")
		(net "P3V3_40G_B2_VCC_RX")
	)
	(via
		(at -48.3362 1.0668)
		(size 0.5588)
		(drill 0.254)
		(layers "F.Cu" "B.Cu")
		(net "P3V3_40G_B2_VCC_RX")
	)
	(via
		(at -95.4532 39.116)
		(size 0.5588)
		(drill 0.254)
		(layers "F.Cu" "B.Cu")
		(net "P3V3_40G_B2_VCC_RX")
	)
	(via
		(at -46.5328 1.1684)
		(size 0.5588)
		(drill 0.254)
		(layers "F.Cu" "B.Cu")
		(net "P3V3_40G_B2_VCC_RX")
	)
	(segment
		(start -66.3448 17.3482)
		(end -66.3448 16.6497)
		(width 0.508)
		(layer "In3.Cu")
		(net "P3V3_40G_B2_VCC_RX")
	)
	(segment
		(start -46.6344 1.0668)
		(end -46.5328 1.1684)
		(width 0.508)
		(layer "In3.Cu")
		(net "P3V3_40G_B2_VCC_RX")
	)
	(segment
		(start -76.1492 26.7462)
		(end -74.295 24.892)
		(width 0.508)
		(layer "In3.Cu")
		(net "P3V3_40G_B2_VCC_RX")
	)
	(segment
		(start -95.4532 39.116)
		(end -95.4532 35.06978)
		(width 0.508)
		(layer "In3.Cu")
		(net "P3V3_40G_B2_VCC_RX")
	)
	(segment
		(start -67.3862 18.3896)
		(end -66.3448 17.3482)
		(width 0.508)
		(layer "In3.Cu")
		(net "P3V3_40G_B2_VCC_RX")
	)
	(segment
		(start -68.5038 18.3896)
		(end -67.3862 18.3896)
		(width 0.508)
		(layer "In3.Cu")
		(net "P3V3_40G_B2_VCC_RX")
	)
	(segment
		(start -74.295 24.1808)
		(end -68.5038 18.3896)
		(width 0.508)
		(layer "In3.Cu")
		(net "P3V3_40G_B2_VCC_RX")
	)
	(segment
		(start -48.3362 1.0668)
		(end -46.6344 1.0668)
		(width 0.508)
		(layer "In3.Cu")
		(net "P3V3_40G_B2_VCC_RX")
	)
	(segment
		(start -87.12962 26.7462)
		(end -76.1492 26.7462)
		(width 0.508)
		(layer "In3.Cu")
		(net "P3V3_40G_B2_VCC_RX")
	)
	(segment
		(start -95.4532 35.06978)
		(end -87.12962 26.7462)
		(width 0.508)
		(layer "In3.Cu")
		(net "P3V3_40G_B2_VCC_RX")
	)
	(segment
		(start -50.73142 3.46202)
		(end -48.3362 1.0668)
		(width 0.508)
		(layer "In3.Cu")
		(net "P3V3_40G_B2_VCC_RX")
	)
	(segment
		(start -53.15712 3.46202)
		(end -50.73142 3.46202)
		(width 0.508)
		(layer "In3.Cu")
		(net "P3V3_40G_B2_VCC_RX")
	)
	(segment
		(start -74.295 24.892)
		(end -74.295 24.1808)
		(width 0.508)
		(layer "In3.Cu")
		(net "P3V3_40G_B2_VCC_RX")
	)
	(segment
		(start -66.3448 16.6497)
		(end -53.15712 3.46202)
		(width 0.508)
		(layer "In3.Cu")
		(net "P3V3_40G_B2_VCC_RX")
	)
	(segment
		(start -94.249999 43.840001)
		(end -94.249999 45.465601)
		(width 0.3048)
		(layer "F.Cu")
		(net "P3V3_40G_B2_VCC1")
	)
	(via
		(at -94.249999 45.465601)
		(size 0.5588)
		(drill 0.254)
		(layers "F.Cu" "B.Cu")
		(net "P3V3_40G_B2_VCC1")
	)
	(via
		(at -47.2186 14.2748)
		(size 0.5588)
		(drill 0.254)
		(layers "F.Cu" "B.Cu")
		(net "P3V3_40G_B2_VCC1")
	)
	(via
		(at -48.514 14.3256)
		(size 0.5588)
		(drill 0.254)
		(layers "F.Cu" "B.Cu")
		(net "P3V3_40G_B2_VCC1")
	)
	(segment
		(start -89.62644 36.56584)
		(end -91.17838 36.56584)
		(width 0.508)
		(layer "In3.Cu")
		(net "P3V3_40G_B2_VCC1")
	)
	(segment
		(start -84.0486 30.988)
		(end -89.62644 36.56584)
		(width 0.508)
		(layer "In3.Cu")
		(net "P3V3_40G_B2_VCC1")
	)
	(segment
		(start -62.9412 22.0218)
		(end -66.9798 26.0604)
		(width 0.508)
		(layer "In3.Cu")
		(net "P3V3_40G_B2_VCC1")
	)
	(segment
		(start -60.7822 18.4912)
		(end -62.9412 20.6502)
		(width 0.508)
		(layer "In3.Cu")
		(net "P3V3_40G_B2_VCC1")
	)
	(segment
		(start -94.249999 44.008799)
		(end -94.249999 45.465601)
		(width 0.508)
		(layer "In3.Cu")
		(net "P3V3_40G_B2_VCC1")
	)
	(segment
		(start -93.82506 43.58386)
		(end -94.249999 44.008799)
		(width 0.508)
		(layer "In3.Cu")
		(net "P3V3_40G_B2_VCC1")
	)
	(segment
		(start -93.82506 39.21252)
		(end -93.82506 43.58386)
		(width 0.508)
		(layer "In3.Cu")
		(net "P3V3_40G_B2_VCC1")
	)
	(segment
		(start -58.05932 18.4912)
		(end -60.7822 18.4912)
		(width 0.508)
		(layer "In3.Cu")
		(net "P3V3_40G_B2_VCC1")
	)
	(segment
		(start -53.89372 14.3256)
		(end -58.05932 18.4912)
		(width 0.508)
		(layer "In3.Cu")
		(net "P3V3_40G_B2_VCC1")
	)
	(segment
		(start -66.9798 26.0604)
		(end -66.9798 29.2862)
		(width 0.508)
		(layer "In3.Cu")
		(net "P3V3_40G_B2_VCC1")
	)
	(segment
		(start -68.6816 30.988)
		(end -84.0486 30.988)
		(width 0.508)
		(layer "In3.Cu")
		(net "P3V3_40G_B2_VCC1")
	)
	(segment
		(start -62.9412 20.6502)
		(end -62.9412 22.0218)
		(width 0.508)
		(layer "In3.Cu")
		(net "P3V3_40G_B2_VCC1")
	)
	(segment
		(start -91.17838 36.56584)
		(end -93.82506 39.21252)
		(width 0.508)
		(layer "In3.Cu")
		(net "P3V3_40G_B2_VCC1")
	)
	(segment
		(start -47.2694 14.3256)
		(end -47.2186 14.2748)
		(width 0.508)
		(layer "In3.Cu")
		(net "P3V3_40G_B2_VCC1")
	)
	(segment
		(start -48.514 14.3256)
		(end -53.89372 14.3256)
		(width 0.508)
		(layer "In3.Cu")
		(net "P3V3_40G_B2_VCC1")
	)
	(segment
		(start -66.9798 29.2862)
		(end -68.6816 30.988)
		(width 0.508)
		(layer "In3.Cu")
		(net "P3V3_40G_B2_VCC1")
	)
	(segment
		(start -48.514 14.3256)
		(end -47.2694 14.3256)
		(width 0.508)
		(layer "In3.Cu")
		(net "P3V3_40G_B2_VCC1")
	)
	(segment
		(start -316.05 43.840001)
		(end -316.05 45.211601)
		(width 0.3048)
		(layer "F.Cu")
		(net "P3V3_40G_B1_VCC_TX")
	)
	(via
		(at -269.748 7.4168)
		(size 0.5588)
		(drill 0.254)
		(layers "F.Cu" "B.Cu")
		(net "P3V3_40G_B1_VCC_TX")
	)
	(via
		(at -267.9446 7.5692)
		(size 0.5588)
		(drill 0.254)
		(layers "F.Cu" "B.Cu")
		(net "P3V3_40G_B1_VCC_TX")
	)
	(via
		(at -316.05 45.211601)
		(size 0.5588)
		(drill 0.254)
		(layers "F.Cu" "B.Cu")
		(net "P3V3_40G_B1_VCC_TX")
	)
	(via
		(at -281.3812 17.3228)
		(size 0.5588)
		(drill 0.254)
		(layers "F.Cu" "B.Cu")
		(net "P3V3_40G_B1_VCC_TX")
	)
	(segment
		(start -271.8816 13.4874)
		(end -271.8816 8.509)
		(width 0.508)
		(layer "In2.Cu")
		(net "P3V3_40G_B1_VCC_TX")
	)
	(segment
		(start -281.3812 17.3228)
		(end -275.717 17.3228)
		(width 0.508)
		(layer "In2.Cu")
		(net "P3V3_40G_B1_VCC_TX")
	)
	(segment
		(start -271.8816 8.509)
		(end -270.7894 7.4168)
		(width 0.508)
		(layer "In2.Cu")
		(net "P3V3_40G_B1_VCC_TX")
	)
	(segment
		(start -270.7894 7.4168)
		(end -269.748 7.4168)
		(width 0.508)
		(layer "In2.Cu")
		(net "P3V3_40G_B1_VCC_TX")
	)
	(segment
		(start -275.717 17.3228)
		(end -271.8816 13.4874)
		(width 0.508)
		(layer "In2.Cu")
		(net "P3V3_40G_B1_VCC_TX")
	)
	(segment
		(start -316.05 43.8636)
		(end -315.722 43.5356)
		(width 0.508)
		(layer "In5.Cu")
		(net "P3V3_40G_B1_VCC_TX")
	)
	(segment
		(start -315.722 43.5356)
		(end -315.722 32.50946)
		(width 0.508)
		(layer "In5.Cu")
		(net "P3V3_40G_B1_VCC_TX")
	)
	(segment
		(start -302.7172 27.559)
		(end -297.2816 27.559)
		(width 0.508)
		(layer "In5.Cu")
		(net "P3V3_40G_B1_VCC_TX")
	)
	(segment
		(start -304.8762 25.4)
		(end -302.7172 27.559)
		(width 0.508)
		(layer "In5.Cu")
		(net "P3V3_40G_B1_VCC_TX")
	)
	(segment
		(start -287.0454 17.3228)
		(end -281.3812 17.3228)
		(width 0.508)
		(layer "In5.Cu")
		(net "P3V3_40G_B1_VCC_TX")
	)
	(segment
		(start -315.722 32.50946)
		(end -308.61254 25.4)
		(width 0.508)
		(layer "In5.Cu")
		(net "P3V3_40G_B1_VCC_TX")
	)
	(segment
		(start -297.2816 27.559)
		(end -287.0454 17.3228)
		(width 0.508)
		(layer "In5.Cu")
		(net "P3V3_40G_B1_VCC_TX")
	)
	(segment
		(start -316.05 45.211601)
		(end -316.05 43.8636)
		(width 0.508)
		(layer "In5.Cu")
		(net "P3V3_40G_B1_VCC_TX")
	)
	(segment
		(start -308.61254 25.4)
		(end -304.8762 25.4)
		(width 0.508)
		(layer "In5.Cu")
		(net "P3V3_40G_B1_VCC_TX")
	)
	(via
		(at -281.3558 16.0274)
		(size 0.5588)
		(drill 0.254)
		(layers "F.Cu" "B.Cu")
		(net "P3V3_40G_B1_VCC_RX")
	)
	(via
		(at -316.58306 38.98646)
		(size 0.5588)
		(drill 0.254)
		(layers "F.Cu" "B.Cu")
		(net "P3V3_40G_B1_VCC_RX")
	)
	(via
		(at -269.7226 1.3208)
		(size 0.5588)
		(drill 0.254)
		(layers "F.Cu" "B.Cu")
		(net "P3V3_40G_B1_VCC_RX")
	)
	(via
		(at -267.8684 1.2954)
		(size 0.5588)
		(drill 0.254)
		(layers "F.Cu" "B.Cu")
		(net "P3V3_40G_B1_VCC_RX")
	)
	(segment
		(start -277.3934 16.0274)
		(end -273.5834 12.2174)
		(width 0.508)
		(layer "In2.Cu")
		(net "P3V3_40G_B1_VCC_RX")
	)
	(segment
		(start -281.3558 16.0274)
		(end -277.3934 16.0274)
		(width 0.508)
		(layer "In2.Cu")
		(net "P3V3_40G_B1_VCC_RX")
	)
	(segment
		(start -273.5834 12.2174)
		(end -273.5834 4.191)
		(width 0.508)
		(layer "In2.Cu")
		(net "P3V3_40G_B1_VCC_RX")
	)
	(segment
		(start -273.5834 4.191)
		(end -270.7132 1.3208)
		(width 0.508)
		(layer "In2.Cu")
		(net "P3V3_40G_B1_VCC_RX")
	)
	(segment
		(start -270.7132 1.3208)
		(end -269.7226 1.3208)
		(width 0.508)
		(layer "In2.Cu")
		(net "P3V3_40G_B1_VCC_RX")
	)
	(segment
		(start -308.991 24.5364)
		(end -304.0634 24.5364)
		(width 0.508)
		(layer "In5.Cu")
		(net "P3V3_40G_B1_VCC_RX")
	)
	(segment
		(start -316.5348 38.9382)
		(end -316.5348 32.0802)
		(width 0.508)
		(layer "In5.Cu")
		(net "P3V3_40G_B1_VCC_RX")
	)
	(segment
		(start -287.4518 16.0274)
		(end -281.3558 16.0274)
		(width 0.508)
		(layer "In5.Cu")
		(net "P3V3_40G_B1_VCC_RX")
	)
	(segment
		(start -304.0634 24.5364)
		(end -301.879 26.7208)
		(width 0.508)
		(layer "In5.Cu")
		(net "P3V3_40G_B1_VCC_RX")
	)
	(segment
		(start -298.1452 26.7208)
		(end -287.4518 16.0274)
		(width 0.508)
		(layer "In5.Cu")
		(net "P3V3_40G_B1_VCC_RX")
	)
	(segment
		(start -316.58306 38.98646)
		(end -316.5348 38.9382)
		(width 0.508)
		(layer "In5.Cu")
		(net "P3V3_40G_B1_VCC_RX")
	)
	(segment
		(start -301.879 26.7208)
		(end -298.1452 26.7208)
		(width 0.508)
		(layer "In5.Cu")
		(net "P3V3_40G_B1_VCC_RX")
	)
	(segment
		(start -316.5348 32.0802)
		(end -308.991 24.5364)
		(width 0.508)
		(layer "In5.Cu")
		(net "P3V3_40G_B1_VCC_RX")
	)
	(segment
		(start -315.249999 43.840001)
		(end -315.249999 45.465601)
		(width 0.3048)
		(layer "F.Cu")
		(net "P3V3_40G_B1_VCC1")
	)
	(via
		(at -270.1544 14.3764)
		(size 0.5588)
		(drill 0.254)
		(layers "F.Cu" "B.Cu")
		(net "P3V3_40G_B1_VCC1")
	)
	(via
		(at -268.4526 14.3002)
		(size 0.5588)
		(drill 0.254)
		(layers "F.Cu" "B.Cu")
		(net "P3V3_40G_B1_VCC1")
	)
	(via
		(at -315.249999 45.465601)
		(size 0.5588)
		(drill 0.254)
		(layers "F.Cu" "B.Cu")
		(net "P3V3_40G_B1_VCC1")
	)
	(via
		(at -281.3558 18.6436)
		(size 0.5588)
		(drill 0.254)
		(layers "F.Cu" "B.Cu")
		(net "P3V3_40G_B1_VCC1")
	)
	(segment
		(start -274.4216 18.6436)
		(end -270.1544 14.3764)
		(width 0.508)
		(layer "In2.Cu")
		(net "P3V3_40G_B1_VCC1")
	)
	(segment
		(start -281.3558 18.6436)
		(end -274.4216 18.6436)
		(width 0.508)
		(layer "In2.Cu")
		(net "P3V3_40G_B1_VCC1")
	)
	(segment
		(start -314.8838 44.6278)
		(end -314.8838 32.84982)
		(width 0.508)
		(layer "In5.Cu")
		(net "P3V3_40G_B1_VCC1")
	)
	(segment
		(start -314.8838 32.84982)
		(end -309.11038 27.0764)
		(width 0.508)
		(layer "In5.Cu")
		(net "P3V3_40G_B1_VCC1")
	)
	(segment
		(start -315.249999 45.465601)
		(end -315.22162 45.437222)
		(width 0.508)
		(layer "In5.Cu")
		(net "P3V3_40G_B1_VCC1")
	)
	(segment
		(start -315.22162 44.96562)
		(end -314.8838 44.6278)
		(width 0.508)
		(layer "In5.Cu")
		(net "P3V3_40G_B1_VCC1")
	)
	(segment
		(start -296.5196 28.448)
		(end -286.7152 18.6436)
		(width 0.508)
		(layer "In5.Cu")
		(net "P3V3_40G_B1_VCC1")
	)
	(segment
		(start -286.7152 18.6436)
		(end -281.3558 18.6436)
		(width 0.508)
		(layer "In5.Cu")
		(net "P3V3_40G_B1_VCC1")
	)
	(segment
		(start -309.11038 27.0764)
		(end -305.9938 27.0764)
		(width 0.508)
		(layer "In5.Cu")
		(net "P3V3_40G_B1_VCC1")
	)
	(segment
		(start -304.6222 28.448)
		(end -296.5196 28.448)
		(width 0.508)
		(layer "In5.Cu")
		(net "P3V3_40G_B1_VCC1")
	)
	(segment
		(start -315.22162 45.437222)
		(end -315.22162 44.96562)
		(width 0.508)
		(layer "In5.Cu")
		(net "P3V3_40G_B1_VCC1")
	)
	(segment
		(start -305.9938 27.0764)
		(end -304.6222 28.448)
		(width 0.508)
		(layer "In5.Cu")
		(net "P3V3_40G_B1_VCC1")
	)
	(via
		(at -61.0362 32.8422)
		(size 0.5588)
		(drill 0.254)
		(layers "F.Cu" "B.Cu")
		(net "P3V3_10G_B2_VCCT")
	)
	(via
		(at -60.1726 43.3578)
		(size 0.5588)
		(drill 0.254)
		(layers "F.Cu" "B.Cu")
		(net "P3V3_10G_B2_VCCT")
	)
	(segment
		(start -60.02274 33.85566)
		(end -57.45004 33.85566)
		(width 0.508)
		(layer "In5.Cu")
		(net "P3V3_10G_B2_VCCT")
	)
	(segment
		(start -55.55012 35.75558)
		(end -55.55012 38.83152)
		(width 0.508)
		(layer "In5.Cu")
		(net "P3V3_10G_B2_VCCT")
	)
	(segment
		(start -55.55012 38.83152)
		(end -56.81504 40.09644)
		(width 0.508)
		(layer "In5.Cu")
		(net "P3V3_10G_B2_VCCT")
	)
	(segment
		(start -60.1726 42.59802)
		(end -60.1726 43.3578)
		(width 0.508)
		(layer "In5.Cu")
		(net "P3V3_10G_B2_VCCT")
	)
	(segment
		(start -61.0362 32.8422)
		(end -60.02274 33.85566)
		(width 0.508)
		(layer "In5.Cu")
		(net "P3V3_10G_B2_VCCT")
	)
	(segment
		(start -57.67102 40.09644)
		(end -60.1726 42.59802)
		(width 0.508)
		(layer "In5.Cu")
		(net "P3V3_10G_B2_VCCT")
	)
	(segment
		(start -56.81504 40.09644)
		(end -57.67102 40.09644)
		(width 0.508)
		(layer "In5.Cu")
		(net "P3V3_10G_B2_VCCT")
	)
	(segment
		(start -57.45004 33.85566)
		(end -55.55012 35.75558)
		(width 0.508)
		(layer "In5.Cu")
		(net "P3V3_10G_B2_VCCT")
	)
	(via
		(at -62.0522 32.8422)
		(size 0.5588)
		(drill 0.254)
		(layers "F.Cu" "B.Cu")
		(net "P3V3_10G_B2_VCCR")
	)
	(via
		(at -62.2046 43.3578)
		(size 0.5588)
		(drill 0.254)
		(layers "F.Cu" "B.Cu")
		(net "P3V3_10G_B2_VCCR")
	)
	(segment
		(start -66.24098 35.99688)
		(end -67.90214 37.65804)
		(width 0.508)
		(layer "In5.Cu")
		(net "P3V3_10G_B2_VCCR")
	)
	(segment
		(start -66.24098 34.5948)
		(end -66.24098 35.99688)
		(width 0.508)
		(layer "In5.Cu")
		(net "P3V3_10G_B2_VCCR")
	)
	(segment
		(start -63.25394 41.87952)
		(end -62.2046 42.92886)
		(width 0.508)
		(layer "In5.Cu")
		(net "P3V3_10G_B2_VCCR")
	)
	(segment
		(start -67.90214 37.65804)
		(end -67.90214 39.09822)
		(width 0.508)
		(layer "In5.Cu")
		(net "P3V3_10G_B2_VCCR")
	)
	(segment
		(start -65.36976 33.72358)
		(end -66.24098 34.5948)
		(width 0.508)
		(layer "In5.Cu")
		(net "P3V3_10G_B2_VCCR")
	)
	(segment
		(start -62.2046 42.92886)
		(end -62.2046 43.3578)
		(width 0.508)
		(layer "In5.Cu")
		(net "P3V3_10G_B2_VCCR")
	)
	(segment
		(start -62.0522 32.8422)
		(end -62.93358 33.72358)
		(width 0.508)
		(layer "In5.Cu")
		(net "P3V3_10G_B2_VCCR")
	)
	(segment
		(start -62.93358 33.72358)
		(end -65.36976 33.72358)
		(width 0.508)
		(layer "In5.Cu")
		(net "P3V3_10G_B2_VCCR")
	)
	(segment
		(start -65.12084 41.87952)
		(end -63.25394 41.87952)
		(width 0.508)
		(layer "In5.Cu")
		(net "P3V3_10G_B2_VCCR")
	)
	(segment
		(start -67.90214 39.09822)
		(end -65.12084 41.87952)
		(width 0.508)
		(layer "In5.Cu")
		(net "P3V3_10G_B2_VCCR")
	)
	(via
		(at -281.1726 43.3578)
		(size 0.5588)
		(drill 0.254)
		(layers "F.Cu" "B.Cu")
		(net "P3V3_10G_B1_VCCT")
	)
	(via
		(at -282.067 32.766)
		(size 0.5588)
		(drill 0.254)
		(layers "F.Cu" "B.Cu")
		(net "P3V3_10G_B1_VCCT")
	)
	(segment
		(start -278.67102 40.09644)
		(end -277.81504 40.09644)
		(width 0.508)
		(layer "In5.Cu")
		(net "P3V3_10G_B1_VCCT")
	)
	(segment
		(start -277.81504 40.09644)
		(end -276.55012 38.83152)
		(width 0.508)
		(layer "In5.Cu")
		(net "P3V3_10G_B1_VCCT")
	)
	(segment
		(start -278.45004 33.85566)
		(end -280.97734 33.85566)
		(width 0.508)
		(layer "In5.Cu")
		(net "P3V3_10G_B1_VCCT")
	)
	(segment
		(start -281.1726 43.3578)
		(end -281.1726 42.59802)
		(width 0.508)
		(layer "In5.Cu")
		(net "P3V3_10G_B1_VCCT")
	)
	(segment
		(start -281.1726 42.59802)
		(end -278.67102 40.09644)
		(width 0.508)
		(layer "In5.Cu")
		(net "P3V3_10G_B1_VCCT")
	)
	(segment
		(start -276.55012 35.75558)
		(end -278.45004 33.85566)
		(width 0.508)
		(layer "In5.Cu")
		(net "P3V3_10G_B1_VCCT")
	)
	(segment
		(start -276.55012 38.83152)
		(end -276.55012 35.75558)
		(width 0.508)
		(layer "In5.Cu")
		(net "P3V3_10G_B1_VCCT")
	)
	(segment
		(start -280.97734 33.85566)
		(end -282.067 32.766)
		(width 0.508)
		(layer "In5.Cu")
		(net "P3V3_10G_B1_VCCT")
	)
	(via
		(at -283.083 32.766)
		(size 0.5588)
		(drill 0.254)
		(layers "F.Cu" "B.Cu")
		(net "P3V3_10G_B1_VCCR")
	)
	(via
		(at -283.2046 43.3578)
		(size 0.5588)
		(drill 0.254)
		(layers "F.Cu" "B.Cu")
		(net "P3V3_10G_B1_VCCR")
	)
	(segment
		(start -283.2046 42.92886)
		(end -283.2046 43.3578)
		(width 0.508)
		(layer "In5.Cu")
		(net "P3V3_10G_B1_VCCR")
	)
	(segment
		(start -288.90214 39.09822)
		(end -286.12084 41.87952)
		(width 0.508)
		(layer "In5.Cu")
		(net "P3V3_10G_B1_VCCR")
	)
	(segment
		(start -286.36976 33.72358)
		(end -287.24098 34.5948)
		(width 0.508)
		(layer "In5.Cu")
		(net "P3V3_10G_B1_VCCR")
	)
	(segment
		(start -288.90214 37.65804)
		(end -288.90214 39.09822)
		(width 0.508)
		(layer "In5.Cu")
		(net "P3V3_10G_B1_VCCR")
	)
	(segment
		(start -287.24098 34.5948)
		(end -287.24098 35.99688)
		(width 0.508)
		(layer "In5.Cu")
		(net "P3V3_10G_B1_VCCR")
	)
	(segment
		(start -283.083 32.766)
		(end -284.04058 33.72358)
		(width 0.508)
		(layer "In5.Cu")
		(net "P3V3_10G_B1_VCCR")
	)
	(segment
		(start -287.24098 35.99688)
		(end -288.90214 37.65804)
		(width 0.508)
		(layer "In5.Cu")
		(net "P3V3_10G_B1_VCCR")
	)
	(segment
		(start -284.25394 41.87952)
		(end -283.2046 42.92886)
		(width 0.508)
		(layer "In5.Cu")
		(net "P3V3_10G_B1_VCCR")
	)
	(segment
		(start -286.12084 41.87952)
		(end -284.25394 41.87952)
		(width 0.508)
		(layer "In5.Cu")
		(net "P3V3_10G_B1_VCCR")
	)
	(segment
		(start -284.04058 33.72358)
		(end -286.36976 33.72358)
		(width 0.508)
		(layer "In5.Cu")
		(net "P3V3_10G_B1_VCCR")
	)
	(segment
		(start -159.16275 20.729956)
		(end -159.095252 20.729956)
		(width 0.3048)
		(layer "F.Cu")
		(net "P12V_MEZZ_B2")
	)
	(segment
		(start -155.984999 18.894999)
		(end -156.619999 18.259999)
		(width 0.3048)
		(layer "F.Cu")
		(net "P12V_MEZZ_B2")
	)
	(segment
		(start -158.524999 20.164999)
		(end -159.159999 19.529999)
		(width 0.3048)
		(layer "F.Cu")
		(net "P12V_MEZZ_B2")
	)
	(segment
		(start -158.524999 18.894999)
		(end -159.159999 18.259999)
		(width 0.3048)
		(layer "F.Cu")
		(net "P12V_MEZZ_B2")
	)
	(segment
		(start -159.095252 20.864746)
		(end -158.524999 21.434999)
		(width 0.3048)
		(layer "F.Cu")
		(net "P12V_MEZZ_B2")
	)
	(segment
		(start -157.254999 18.894999)
		(end -157.889999 18.259999)
		(width 0.3048)
		(layer "F.Cu")
		(net "P12V_MEZZ_B2")
	)
	(segment
		(start -159.095252 20.729956)
		(end -159.095252 20.864746)
		(width 0.3048)
		(layer "F.Cu")
		(net "P12V_MEZZ_B2")
	)
	(via
		(at -157.889999 18.259999)
		(size 0.5588)
		(drill 0.254)
		(layers "F.Cu" "B.Cu")
		(net "P12V_MEZZ_B2")
	)
	(via
		(at -159.159999 19.529999)
		(size 0.5588)
		(drill 0.254)
		(layers "F.Cu" "B.Cu")
		(net "P12V_MEZZ_B2")
	)
	(via
		(at -156.619999 18.259999)
		(size 0.5588)
		(drill 0.254)
		(layers "F.Cu" "B.Cu")
		(net "P12V_MEZZ_B2")
	)
	(via
		(at -159.159999 18.259999)
		(size 0.5588)
		(drill 0.254)
		(layers "F.Cu" "B.Cu")
		(net "P12V_MEZZ_B2")
	)
	(via
		(at -159.16275 20.729956)
		(size 0.5588)
		(drill 0.254)
		(layers "F.Cu" "B.Cu")
		(net "P12V_MEZZ_B2")
	)
	(segment
		(start -379.524999 20.164999)
		(end -380.159999 19.529999)
		(width 0.3048)
		(layer "F.Cu")
		(net "P12V_MEZZ_B1")
	)
	(segment
		(start -379.524999 21.434999)
		(end -379.554801 21.434999)
		(width 0.3048)
		(layer "F.Cu")
		(net "P12V_MEZZ_B1")
	)
	(segment
		(start -379.554801 21.434999)
		(end -380.238 20.7518)
		(width 0.3048)
		(layer "F.Cu")
		(net "P12V_MEZZ_B1")
	)
	(segment
		(start -379.524999 18.894999)
		(end -380.159999 18.259999)
		(width 0.3048)
		(layer "F.Cu")
		(net "P12V_MEZZ_B1")
	)
	(segment
		(start -378.254999 18.894999)
		(end -378.889999 18.259999)
		(width 0.3048)
		(layer "F.Cu")
		(net "P12V_MEZZ_B1")
	)
	(segment
		(start -376.984999 18.894999)
		(end -377.619999 18.259999)
		(width 0.3048)
		(layer "F.Cu")
		(net "P12V_MEZZ_B1")
	)
	(via
		(at -380.238 20.7518)
		(size 0.5588)
		(drill 0.254)
		(layers "F.Cu" "B.Cu")
		(net "P12V_MEZZ_B1")
	)
	(via
		(at -380.159999 19.529999)
		(size 0.5588)
		(drill 0.254)
		(layers "F.Cu" "B.Cu")
		(net "P12V_MEZZ_B1")
	)
	(via
		(at -377.619999 18.259999)
		(size 0.5588)
		(drill 0.254)
		(layers "F.Cu" "B.Cu")
		(net "P12V_MEZZ_B1")
	)
	(via
		(at -378.889999 18.259999)
		(size 0.5588)
		(drill 0.254)
		(layers "F.Cu" "B.Cu")
		(net "P12V_MEZZ_B1")
	)
	(via
		(at -380.159999 18.259999)
		(size 0.5588)
		(drill 0.254)
		(layers "F.Cu" "B.Cu")
		(net "P12V_MEZZ_B1")
	)
	(segment
		(start -115.221601 21.729802)
		(end -115.221601 22.428302)
		(width 0.3048)
		(layer "F.Cu")
		(net "P12V")
	)
	(segment
		(start -131.8768 32.3342)
		(end -130.8608 32.3342)
		(width 0.381)
		(layer "F.Cu")
		(net "P12V")
	)
	(segment
		(start -136.017 32.3469)
		(end -137.1219 32.3469)
		(width 0.381)
		(layer "F.Cu")
		(net "P12V")
	)
	(segment
		(start -334.449001 21.818702)
		(end -334.449001 22.6568)
		(width 0.3048)
		(layer "F.Cu")
		(net "P12V")
	)
	(segment
		(start -130.8608 32.3342)
		(end -130.81 32.385)
		(width 0.381)
		(layer "F.Cu")
		(net "P12V")
	)
	(segment
		(start -137.1219 32.3469)
		(end -137.16 32.385)
		(width 0.381)
		(layer "F.Cu")
		(net "P12V")
	)
	(segment
		(start -113.824601 21.793302)
		(end -113.824601 22.555302)
		(width 0.3048)
		(layer "F.Cu")
		(net "P12V")
	)
	(segment
		(start -335.846001 21.755202)
		(end -335.846001 22.453702)
		(width 0.3048)
		(layer "F.Cu")
		(net "P12V")
	)
	(via
		(at -274.955 -3.683)
		(size 0.5588)
		(drill 0.254)
		(layers "F.Cu" "B.Cu")
		(net "P12V")
	)
	(via
		(at -127.635 16.51)
		(size 0.5588)
		(drill 0.254)
		(layers "F.Cu" "B.Cu")
		(net "P12V")
	)
	(via
		(at -346.075 19.05)
		(size 0.5588)
		(drill 0.254)
		(layers "F.Cu" "B.Cu")
		(net "P12V")
	)
	(via
		(at -111.76 -3.175)
		(size 0.5588)
		(drill 0.254)
		(layers "F.Cu" "B.Cu")
		(net "P12V")
	)
	(via
		(at -362.557545 10.258745)
		(size 0.5588)
		(drill 0.254)
		(layers "F.Cu" "B.Cu")
		(net "P12V")
	)
	(via
		(at -279.4 0.635)
		(size 0.5588)
		(drill 0.254)
		(layers "F.Cu" "B.Cu")
		(net "P12V")
	)
	(via
		(at -394.97 9.525)
		(size 0.5588)
		(drill 0.254)
		(layers "F.Cu" "B.Cu")
		(net "P12V")
	)
	(via
		(at -342.9 15.875)
		(size 0.5588)
		(drill 0.254)
		(layers "F.Cu" "B.Cu")
		(net "P12V")
	)
	(via
		(at -118.11 9.525)
		(size 0.5588)
		(drill 0.254)
		(layers "F.Cu" "B.Cu")
		(net "P12V")
	)
	(via
		(at -186.69 5.08)
		(size 0.5588)
		(drill 0.254)
		(layers "F.Cu" "B.Cu")
		(net "P12V")
	)
	(via
		(at -189.865 1.905)
		(size 0.5588)
		(drill 0.254)
		(layers "F.Cu" "B.Cu")
		(net "P12V")
	)
	(via
		(at -393.7 9.525)
		(size 0.5588)
		(drill 0.254)
		(layers "F.Cu" "B.Cu")
		(net "P12V")
	)
	(via
		(at -368.3 25.4)
		(size 0.5588)
		(drill 0.254)
		(layers "F.Cu" "B.Cu")
		(net "P12V")
	)
	(via
		(at -153.035 0)
		(size 0.5588)
		(drill 0.254)
		(layers "F.Cu" "B.Cu")
		(net "P12V")
	)
	(via
		(at -405.13 8.255)
		(size 0.5588)
		(drill 0.254)
		(layers "F.Cu" "B.Cu")
		(net "P12V")
	)
	(via
		(at -133.985 22.86)
		(size 0.5588)
		(drill 0.254)
		(layers "F.Cu" "B.Cu")
		(net "P12V")
	)
	(via
		(at -368.3 31.75)
		(size 0.5588)
		(drill 0.254)
		(layers "F.Cu" "B.Cu")
		(net "P12V")
	)
	(via
		(at -406.4 9.525)
		(size 0.5588)
		(drill 0.254)
		(layers "F.Cu" "B.Cu")
		(net "P12V")
	)
	(via
		(at -231.14 11.43)
		(size 0.5588)
		(drill 0.254)
		(layers "F.Cu" "B.Cu")
		(net "P12V")
	)
	(via
		(at -227.965 33.655)
		(size 0.5588)
		(drill 0.254)
		(layers "F.Cu" "B.Cu")
		(net "P12V")
	)
	(via
		(at -130.81 9.525)
		(size 0.5588)
		(drill 0.254)
		(layers "F.Cu" "B.Cu")
		(net "P12V")
	)
	(via
		(at -218.44 43.18)
		(size 0.5588)
		(drill 0.254)
		(layers "F.Cu" "B.Cu")
		(net "P12V")
	)
	(via
		(at -339.1916 9.5504)
		(size 0.5588)
		(drill 0.254)
		(layers "F.Cu" "B.Cu")
		(net "P12V")
	)
	(via
		(at -389.89 10.795)
		(size 0.5588)
		(drill 0.254)
		(layers "F.Cu" "B.Cu")
		(net "P12V")
	)
	(via
		(at -130.81 45.085)
		(size 0.5588)
		(drill 0.254)
		(layers "F.Cu" "B.Cu")
		(net "P12V")
	)
	(via
		(at -163.195 3.175)
		(size 0.5588)
		(drill 0.254)
		(layers "F.Cu" "B.Cu")
		(net "P12V")
	)
	(via
		(at -319.405 5.08)
		(size 0.5588)
		(drill 0.254)
		(layers "F.Cu" "B.Cu")
		(net "P12V")
	)
	(via
		(at -394.97 6.985)
		(size 0.5588)
		(drill 0.254)
		(layers "F.Cu" "B.Cu")
		(net "P12V")
	)
	(via
		(at -227.965 20.955)
		(size 0.5588)
		(drill 0.254)
		(layers "F.Cu" "B.Cu")
		(net "P12V")
	)
	(via
		(at -319.405 -3.683)
		(size 0.5588)
		(drill 0.254)
		(layers "F.Cu" "B.Cu")
		(net "P12V")
	)
	(via
		(at -313.055 -3.683)
		(size 0.5588)
		(drill 0.254)
		(layers "F.Cu" "B.Cu")
		(net "P12V")
	)
	(via
		(at -143.51 45.085)
		(size 0.5588)
		(drill 0.254)
		(layers "F.Cu" "B.Cu")
		(net "P12V")
	)
	(via
		(at -127.635 6.35)
		(size 0.5588)
		(drill 0.254)
		(layers "F.Cu" "B.Cu")
		(net "P12V")
	)
	(via
		(at -227.965 14.605)
		(size 0.5588)
		(drill 0.254)
		(layers "F.Cu" "B.Cu")
		(net "P12V")
	)
	(via
		(at -140.335 0)
		(size 0.5588)
		(drill 0.254)
		(layers "F.Cu" "B.Cu")
		(net "P12V")
	)
	(via
		(at -344.805 -3.683)
		(size 0.5588)
		(drill 0.254)
		(layers "F.Cu" "B.Cu")
		(net "P12V")
	)
	(via
		(at -218.44 5.08)
		(size 0.5588)
		(drill 0.254)
		(layers "F.Cu" "B.Cu")
		(net "P12V")
	)
	(via
		(at -362.557545 12.798745)
		(size 0.5588)
		(drill 0.254)
		(layers "F.Cu" "B.Cu")
		(net "P12V")
	)
	(via
		(at -124.46 19.685)
		(size 0.5588)
		(drill 0.254)
		(layers "F.Cu" "B.Cu")
		(net "P12V")
	)
	(via
		(at -234.315 14.605)
		(size 0.5588)
		(drill 0.254)
		(layers "F.Cu" "B.Cu")
		(net "P12V")
	)
	(via
		(at -306.705 -3.683)
		(size 0.5588)
		(drill 0.254)
		(layers "F.Cu" "B.Cu")
		(net "P12V")
	)
	(via
		(at -127.635 22.86)
		(size 0.5588)
		(drill 0.254)
		(layers "F.Cu" "B.Cu")
		(net "P12V")
	)
	(via
		(at -358.775 19.05)
		(size 0.5588)
		(drill 0.254)
		(layers "F.Cu" "B.Cu")
		(net "P12V")
	)
	(via
		(at -407.67 9.525)
		(size 0.5588)
		(drill 0.254)
		(layers "F.Cu" "B.Cu")
		(net "P12V")
	)
	(via
		(at -234.315 40.513)
		(size 0.5588)
		(drill 0.254)
		(layers "F.Cu" "B.Cu")
		(net "P12V")
	)
	(via
		(at -259.08 -3.683)
		(size 0.5588)
		(drill 0.254)
		(layers "F.Cu" "B.Cu")
		(net "P12V")
	)
	(via
		(at -410.21 6.985)
		(size 0.5588)
		(drill 0.254)
		(layers "F.Cu" "B.Cu")
		(net "P12V")
	)
	(via
		(at -231.14 43.18)
		(size 0.5588)
		(drill 0.254)
		(layers "F.Cu" "B.Cu")
		(net "P12V")
	)
	(via
		(at -202.565 -3.683)
		(size 0.5588)
		(drill 0.254)
		(layers "F.Cu" "B.Cu")
		(net "P12V")
	)
	(via
		(at -403.86 10.795)
		(size 0.5588)
		(drill 0.254)
		(layers "F.Cu" "B.Cu")
		(net "P12V")
	)
	(via
		(at -215.265 40.513)
		(size 0.5588)
		(drill 0.254)
		(layers "F.Cu" "B.Cu")
		(net "P12V")
	)
	(via
		(at -143.51 3.175)
		(size 0.5588)
		(drill 0.254)
		(layers "F.Cu" "B.Cu")
		(net "P12V")
	)
	(via
		(at -391.16 8.255)
		(size 0.5588)
		(drill 0.254)
		(layers "F.Cu" "B.Cu")
		(net "P12V")
	)
	(via
		(at -215.392 -3.683)
		(size 0.5588)
		(drill 0.254)
		(layers "F.Cu" "B.Cu")
		(net "P12V")
	)
	(via
		(at -124.46 26.035)
		(size 0.5588)
		(drill 0.254)
		(layers "F.Cu" "B.Cu")
		(net "P12V")
	)
	(via
		(at -361.823 25.4)
		(size 0.5588)
		(drill 0.254)
		(layers "F.Cu" "B.Cu")
		(net "P12V")
	)
	(via
		(at -341.63 -1.778)
		(size 0.5588)
		(drill 0.254)
		(layers "F.Cu" "B.Cu")
		(net "P12V")
	)
	(via
		(at -287.655 -3.683)
		(size 0.5588)
		(drill 0.254)
		(layers "F.Cu" "B.Cu")
		(net "P12V")
	)
	(via
		(at -402.59 9.525)
		(size 0.5588)
		(drill 0.254)
		(layers "F.Cu" "B.Cu")
		(net "P12V")
	)
	(via
		(at -319.405 11.43)
		(size 0.5588)
		(drill 0.254)
		(layers "F.Cu" "B.Cu")
		(net "P12V")
	)
	(via
		(at -193.04 17.78)
		(size 0.5588)
		(drill 0.254)
		(layers "F.Cu" "B.Cu")
		(net "P12V")
	)
	(via
		(at -391.16 9.525)
		(size 0.5588)
		(drill 0.254)
		(layers "F.Cu" "B.Cu")
		(net "P12V")
	)
	(via
		(at -398.78 10.795)
		(size 0.5588)
		(drill 0.254)
		(layers "F.Cu" "B.Cu")
		(net "P12V")
	)
	(via
		(at -352.425 34.925)
		(size 0.5588)
		(drill 0.254)
		(layers "F.Cu" "B.Cu")
		(net "P12V")
	)
	(via
		(at -362.557545 11.528745)
		(size 0.5588)
		(drill 0.254)
		(layers "F.Cu" "B.Cu")
		(net "P12V")
	)
	(via
		(at -212.09 24.13)
		(size 0.5588)
		(drill 0.254)
		(layers "F.Cu" "B.Cu")
		(net "P12V")
	)
	(via
		(at -166.497 6.477)
		(size 0.5588)
		(drill 0.254)
		(layers "F.Cu" "B.Cu")
		(net "P12V")
	)
	(via
		(at -107.823 6.731)
		(size 0.5588)
		(drill 0.254)
		(layers "F.Cu" "B.Cu")
		(net "P12V")
	)
	(via
		(at -130.81 26.035)
		(size 0.5588)
		(drill 0.254)
		(layers "F.Cu" "B.Cu")
		(net "P12V")
	)
	(via
		(at -215.265 20.955)
		(size 0.5588)
		(drill 0.254)
		(layers "F.Cu" "B.Cu")
		(net "P12V")
	)
	(via
		(at -224.79 17.78)
		(size 0.5588)
		(drill 0.254)
		(layers "F.Cu" "B.Cu")
		(net "P12V")
	)
	(via
		(at -344.805 0.127)
		(size 0.5588)
		(drill 0.254)
		(layers "F.Cu" "B.Cu")
		(net "P12V")
	)
	(via
		(at -224.79 24.13)
		(size 0.5588)
		(drill 0.254)
		(layers "F.Cu" "B.Cu")
		(net "P12V")
	)
	(via
		(at -351.127545 12.798745)
		(size 0.5588)
		(drill 0.254)
		(layers "F.Cu" "B.Cu")
		(net "P12V")
	)
	(via
		(at -401.32 6.985)
		(size 0.5588)
		(drill 0.254)
		(layers "F.Cu" "B.Cu")
		(net "P12V")
	)
	(via
		(at -221.615 20.955)
		(size 0.5588)
		(drill 0.254)
		(layers "F.Cu" "B.Cu")
		(net "P12V")
	)
	(via
		(at -149.86 -3.175)
		(size 0.5588)
		(drill 0.254)
		(layers "F.Cu" "B.Cu")
		(net "P12V")
	)
	(via
		(at -212.09 17.78)
		(size 0.5588)
		(drill 0.254)
		(layers "F.Cu" "B.Cu")
		(net "P12V")
	)
	(via
		(at -170.815 -3.683)
		(size 0.5588)
		(drill 0.254)
		(layers "F.Cu" "B.Cu")
		(net "P12V")
	)
	(via
		(at -234.315 1.905)
		(size 0.5588)
		(drill 0.254)
		(layers "F.Cu" "B.Cu")
		(net "P12V")
	)
	(via
		(at -180.34 5.08)
		(size 0.5588)
		(drill 0.254)
		(layers "F.Cu" "B.Cu")
		(net "P12V")
	)
	(via
		(at -224.79 43.18)
		(size 0.5588)
		(drill 0.254)
		(layers "F.Cu" "B.Cu")
		(net "P12V")
	)
	(via
		(at -360.652545 10.258745)
		(size 0.5588)
		(drill 0.254)
		(layers "F.Cu" "B.Cu")
		(net "P12V")
	)
	(via
		(at -389.89 8.255)
		(size 0.5588)
		(drill 0.254)
		(layers "F.Cu" "B.Cu")
		(net "P12V")
	)
	(via
		(at -353.032545 10.258745)
		(size 0.5588)
		(drill 0.254)
		(layers "F.Cu" "B.Cu")
		(net "P12V")
	)
	(via
		(at -407.67 8.255)
		(size 0.5588)
		(drill 0.254)
		(layers "F.Cu" "B.Cu")
		(net "P12V")
	)
	(via
		(at -405.13 9.525)
		(size 0.5588)
		(drill 0.254)
		(layers "F.Cu" "B.Cu")
		(net "P12V")
	)
	(via
		(at -133.985 29.21)
		(size 0.5588)
		(drill 0.254)
		(layers "F.Cu" "B.Cu")
		(net "P12V")
	)
	(via
		(at -231.14 -1.27)
		(size 0.5588)
		(drill 0.254)
		(layers "F.Cu" "B.Cu")
		(net "P12V")
	)
	(via
		(at -218.44 17.78)
		(size 0.5588)
		(drill 0.254)
		(layers "F.Cu" "B.Cu")
		(net "P12V")
	)
	(via
		(at -397.51 9.525)
		(size 0.5588)
		(drill 0.254)
		(layers "F.Cu" "B.Cu")
		(net "P12V")
	)
	(via
		(at -221.615 27.305)
		(size 0.5588)
		(drill 0.254)
		(layers "F.Cu" "B.Cu")
		(net "P12V")
	)
	(via
		(at -294.005 -3.683)
		(size 0.5588)
		(drill 0.254)
		(layers "F.Cu" "B.Cu")
		(net "P12V")
	)
	(via
		(at -221.615 -3.683)
		(size 0.5588)
		(drill 0.254)
		(layers "F.Cu" "B.Cu")
		(net "P12V")
	)
	(via
		(at -215.265 33.655)
		(size 0.5588)
		(drill 0.254)
		(layers "F.Cu" "B.Cu")
		(net "P12V")
	)
	(via
		(at -351.127545 10.258745)
		(size 0.5588)
		(drill 0.254)
		(layers "F.Cu" "B.Cu")
		(net "P12V")
	)
	(via
		(at -351.155 0.127)
		(size 0.5588)
		(drill 0.254)
		(layers "F.Cu" "B.Cu")
		(net "P12V")
	)
	(via
		(at -356.842545 11.528745)
		(size 0.5588)
		(drill 0.254)
		(layers "F.Cu" "B.Cu")
		(net "P12V")
	)
	(via
		(at -146.685 35.56)
		(size 0.5588)
		(drill 0.254)
		(layers "F.Cu" "B.Cu")
		(net "P12V")
	)
	(via
		(at -227.965 40.513)
		(size 0.5588)
		(drill 0.254)
		(layers "F.Cu" "B.Cu")
		(net "P12V")
	)
	(via
		(at -146.685 29.21)
		(size 0.5588)
		(drill 0.254)
		(layers "F.Cu" "B.Cu")
		(net "P12V")
	)
	(via
		(at -240.03 1.905)
		(size 0.5588)
		(drill 0.254)
		(layers "F.Cu" "B.Cu")
		(net "P12V")
	)
	(via
		(at -137.16 26.035)
		(size 0.5588)
		(drill 0.254)
		(layers "F.Cu" "B.Cu")
		(net "P12V")
	)
	(via
		(at -393.7 8.255)
		(size 0.5588)
		(drill 0.254)
		(layers "F.Cu" "B.Cu")
		(net "P12V")
	)
	(via
		(at -286.004 0.635)
		(size 0.5588)
		(drill 0.254)
		(layers "F.Cu" "B.Cu")
		(net "P12V")
	)
	(via
		(at -394.97 12.065)
		(size 0.5588)
		(drill 0.254)
		(layers "F.Cu" "B.Cu")
		(net "P12V")
	)
	(via
		(at -396.24 10.795)
		(size 0.5588)
		(drill 0.254)
		(layers "F.Cu" "B.Cu")
		(net "P12V")
	)
	(via
		(at -133.985 35.56)
		(size 0.5588)
		(drill 0.254)
		(layers "F.Cu" "B.Cu")
		(net "P12V")
	)
	(via
		(at -124.46 3.175)
		(size 0.5588)
		(drill 0.254)
		(layers "F.Cu" "B.Cu")
		(net "P12V")
	)
	(via
		(at -352.425 19.05)
		(size 0.5588)
		(drill 0.254)
		(layers "F.Cu" "B.Cu")
		(net "P12V")
	)
	(via
		(at -361.95 22.225)
		(size 0.5588)
		(drill 0.254)
		(layers "F.Cu" "B.Cu")
		(net "P12V")
	)
	(via
		(at -408.94 8.255)
		(size 0.5588)
		(drill 0.254)
		(layers "F.Cu" "B.Cu")
		(net "P12V")
	)
	(via
		(at -392.43 6.985)
		(size 0.5588)
		(drill 0.254)
		(layers "F.Cu" "B.Cu")
		(net "P12V")
	)
	(via
		(at -339.1916 19.05)
		(size 0.5588)
		(drill 0.254)
		(layers "F.Cu" "B.Cu")
		(net "P12V")
	)
	(via
		(at -215.265 27.305)
		(size 0.5588)
		(drill 0.254)
		(layers "F.Cu" "B.Cu")
		(net "P12V")
	)
	(via
		(at -137.16 -3.175)
		(size 0.5588)
		(drill 0.254)
		(layers "F.Cu" "B.Cu")
		(net "P12V")
	)
	(via
		(at -396.24 6.985)
		(size 0.5588)
		(drill 0.254)
		(layers "F.Cu" "B.Cu")
		(net "P12V")
	)
	(via
		(at -356.842545 8.988745)
		(size 0.5588)
		(drill 0.254)
		(layers "F.Cu" "B.Cu")
		(net "P12V")
	)
	(via
		(at -113.824601 22.555302)
		(size 0.5588)
		(drill 0.254)
		(layers "F.Cu" "B.Cu")
		(net "P12V")
	)
	(via
		(at -401.32 8.255)
		(size 0.5588)
		(drill 0.254)
		(layers "F.Cu" "B.Cu")
		(net "P12V")
	)
	(via
		(at -401.32 10.795)
		(size 0.5588)
		(drill 0.254)
		(layers "F.Cu" "B.Cu")
		(net "P12V")
	)
	(via
		(at -358.747545 10.258745)
		(size 0.5588)
		(drill 0.254)
		(layers "F.Cu" "B.Cu")
		(net "P12V")
	)
	(via
		(at -224.79 11.43)
		(size 0.5588)
		(drill 0.254)
		(layers "F.Cu" "B.Cu")
		(net "P12V")
	)
	(via
		(at -218.44 -1.27)
		(size 0.5588)
		(drill 0.254)
		(layers "F.Cu" "B.Cu")
		(net "P12V")
	)
	(via
		(at -183.515 -3.683)
		(size 0.5588)
		(drill 0.254)
		(layers "F.Cu" "B.Cu")
		(net "P12V")
	)
	(via
		(at -253.365 1.905)
		(size 0.5588)
		(drill 0.254)
		(layers "F.Cu" "B.Cu")
		(net "P12V")
	)
	(via
		(at -146.685 0)
		(size 0.5588)
		(drill 0.254)
		(layers "F.Cu" "B.Cu")
		(net "P12V")
	)
	(via
		(at -389.89 12.065)
		(size 0.5588)
		(drill 0.254)
		(layers "F.Cu" "B.Cu")
		(net "P12V")
	)
	(via
		(at -335.28 -1.778)
		(size 0.5588)
		(drill 0.254)
		(layers "F.Cu" "B.Cu")
		(net "P12V")
	)
	(via
		(at -143.51 -3.175)
		(size 0.5588)
		(drill 0.254)
		(layers "F.Cu" "B.Cu")
		(net "P12V")
	)
	(via
		(at -208.915 20.955)
		(size 0.5588)
		(drill 0.254)
		(layers "F.Cu" "B.Cu")
		(net "P12V")
	)
	(via
		(at -400.05 8.255)
		(size 0.5588)
		(drill 0.254)
		(layers "F.Cu" "B.Cu")
		(net "P12V")
	)
	(via
		(at -212.09 5.08)
		(size 0.5588)
		(drill 0.254)
		(layers "F.Cu" "B.Cu")
		(net "P12V")
	)
	(via
		(at -354.33 2.032)
		(size 0.5588)
		(drill 0.254)
		(layers "F.Cu" "B.Cu")
		(net "P12V")
	)
	(via
		(at -357.378 4.572)
		(size 0.5588)
		(drill 0.254)
		(layers "F.Cu" "B.Cu")
		(net "P12V")
	)
	(via
		(at -133.985 16.51)
		(size 0.5588)
		(drill 0.254)
		(layers "F.Cu" "B.Cu")
		(net "P12V")
	)
	(via
		(at -355.6 44.45)
		(size 0.5588)
		(drill 0.254)
		(layers "F.Cu" "B.Cu")
		(net "P12V")
	)
	(via
		(at -212.09 11.43)
		(size 0.5588)
		(drill 0.254)
		(layers "F.Cu" "B.Cu")
		(net "P12V")
	)
	(via
		(at -358.648 22.098)
		(size 0.5588)
		(drill 0.254)
		(layers "F.Cu" "B.Cu")
		(net "P12V")
	)
	(via
		(at -392.43 12.065)
		(size 0.5588)
		(drill 0.254)
		(layers "F.Cu" "B.Cu")
		(net "P12V")
	)
	(via
		(at -130.81 32.385)
		(size 0.5588)
		(drill 0.254)
		(layers "F.Cu" "B.Cu")
		(net "P12V")
	)
	(via
		(at -355.727 22.098)
		(size 0.5588)
		(drill 0.254)
		(layers "F.Cu" "B.Cu")
		(net "P12V")
	)
	(via
		(at -361.95 15.875)
		(size 0.5588)
		(drill 0.254)
		(layers "F.Cu" "B.Cu")
		(net "P12V")
	)
	(via
		(at -160.02 9.525)
		(size 0.5588)
		(drill 0.254)
		(layers "F.Cu" "B.Cu")
		(net "P12V")
	)
	(via
		(at -218.44 11.43)
		(size 0.5588)
		(drill 0.254)
		(layers "F.Cu" "B.Cu")
		(net "P12V")
	)
	(via
		(at -347.98 -1.778)
		(size 0.5588)
		(drill 0.254)
		(layers "F.Cu" "B.Cu")
		(net "P12V")
	)
	(via
		(at -338.455 0.127)
		(size 0.5588)
		(drill 0.254)
		(layers "F.Cu" "B.Cu")
		(net "P12V")
	)
	(via
		(at -393.7 6.985)
		(size 0.5588)
		(drill 0.254)
		(layers "F.Cu" "B.Cu")
		(net "P12V")
	)
	(via
		(at -313.055 5.08)
		(size 0.5588)
		(drill 0.254)
		(layers "F.Cu" "B.Cu")
		(net "P12V")
	)
	(via
		(at -401.32 9.525)
		(size 0.5588)
		(drill 0.254)
		(layers "F.Cu" "B.Cu")
		(net "P12V")
	)
	(via
		(at -361.95 44.45)
		(size 0.5588)
		(drill 0.254)
		(layers "F.Cu" "B.Cu")
		(net "P12V")
	)
	(via
		(at -391.16 12.065)
		(size 0.5588)
		(drill 0.254)
		(layers "F.Cu" "B.Cu")
		(net "P12V")
	)
	(via
		(at -193.04 11.43)
		(size 0.5588)
		(drill 0.254)
		(layers "F.Cu" "B.Cu")
		(net "P12V")
	)
	(via
		(at -246.38 -3.683)
		(size 0.5588)
		(drill 0.254)
		(layers "F.Cu" "B.Cu")
		(net "P12V")
	)
	(via
		(at -288.925 3.81)
		(size 0.5588)
		(drill 0.254)
		(layers "F.Cu" "B.Cu")
		(net "P12V")
	)
	(via
		(at -398.78 12.065)
		(size 0.5588)
		(drill 0.254)
		(layers "F.Cu" "B.Cu")
		(net "P12V")
	)
	(via
		(at -180.34 11.43)
		(size 0.5588)
		(drill 0.254)
		(layers "F.Cu" "B.Cu")
		(net "P12V")
	)
	(via
		(at -360.652545 11.528745)
		(size 0.5588)
		(drill 0.254)
		(layers "F.Cu" "B.Cu")
		(net "P12V")
	)
	(via
		(at -180.34 -1.27)
		(size 0.5588)
		(drill 0.254)
		(layers "F.Cu" "B.Cu")
		(net "P12V")
	)
	(via
		(at -189.865 -3.683)
		(size 0.5588)
		(drill 0.254)
		(layers "F.Cu" "B.Cu")
		(net "P12V")
	)
	(via
		(at -140.335 6.35)
		(size 0.5588)
		(drill 0.254)
		(layers "F.Cu" "B.Cu")
		(net "P12V")
	)
	(via
		(at -127.635 0)
		(size 0.5588)
		(drill 0.254)
		(layers "F.Cu" "B.Cu")
		(net "P12V")
	)
	(via
		(at -231.14 5.08)
		(size 0.5588)
		(drill 0.254)
		(layers "F.Cu" "B.Cu")
		(net "P12V")
	)
	(via
		(at -402.59 12.065)
		(size 0.5588)
		(drill 0.254)
		(layers "F.Cu" "B.Cu")
		(net "P12V")
	)
	(via
		(at -252.73 -3.683)
		(size 0.5588)
		(drill 0.254)
		(layers "F.Cu" "B.Cu")
		(net "P12V")
	)
	(via
		(at -143.51 9.525)
		(size 0.5588)
		(drill 0.254)
		(layers "F.Cu" "B.Cu")
		(net "P12V")
	)
	(via
		(at -205.74 5.08)
		(size 0.5588)
		(drill 0.254)
		(layers "F.Cu" "B.Cu")
		(net "P12V")
	)
	(via
		(at -221.615 14.605)
		(size 0.5588)
		(drill 0.254)
		(layers "F.Cu" "B.Cu")
		(net "P12V")
	)
	(via
		(at -130.81 38.735)
		(size 0.5588)
		(drill 0.254)
		(layers "F.Cu" "B.Cu")
		(net "P12V")
	)
	(via
		(at -403.86 8.255)
		(size 0.5588)
		(drill 0.254)
		(layers "F.Cu" "B.Cu")
		(net "P12V")
	)
	(via
		(at -193.04 30.48)
		(size 0.5588)
		(drill 0.254)
		(layers "F.Cu" "B.Cu")
		(net "P12V")
	)
	(via
		(at -352.425 41.275)
		(size 0.5588)
		(drill 0.254)
		(layers "F.Cu" "B.Cu")
		(net "P12V")
	)
	(via
		(at -402.59 6.985)
		(size 0.5588)
		(drill 0.254)
		(layers "F.Cu" "B.Cu")
		(net "P12V")
	)
	(via
		(at -133.985 0)
		(size 0.5588)
		(drill 0.254)
		(layers "F.Cu" "B.Cu")
		(net "P12V")
	)
	(via
		(at -163.195 9.525)
		(size 0.5588)
		(drill 0.254)
		(layers "F.Cu" "B.Cu")
		(net "P12V")
	)
	(via
		(at -137.16 19.685)
		(size 0.5588)
		(drill 0.254)
		(layers "F.Cu" "B.Cu")
		(net "P12V")
	)
	(via
		(at -396.24 8.255)
		(size 0.5588)
		(drill 0.254)
		(layers "F.Cu" "B.Cu")
		(net "P12V")
	)
	(via
		(at -199.39 -1.27)
		(size 0.5588)
		(drill 0.254)
		(layers "F.Cu" "B.Cu")
		(net "P12V")
	)
	(via
		(at -196.215 -3.683)
		(size 0.5588)
		(drill 0.254)
		(layers "F.Cu" "B.Cu")
		(net "P12V")
	)
	(via
		(at -177.165 1.905)
		(size 0.5588)
		(drill 0.254)
		(layers "F.Cu" "B.Cu")
		(net "P12V")
	)
	(via
		(at -173.99 11.43)
		(size 0.5588)
		(drill 0.254)
		(layers "F.Cu" "B.Cu")
		(net "P12V")
	)
	(via
		(at -341.63 2.032)
		(size 0.5588)
		(drill 0.254)
		(layers "F.Cu" "B.Cu")
		(net "P12V")
	)
	(via
		(at -368.3 38.1)
		(size 0.5588)
		(drill 0.254)
		(layers "F.Cu" "B.Cu")
		(net "P12V")
	)
	(via
		(at -401.32 12.065)
		(size 0.5588)
		(drill 0.254)
		(layers "F.Cu" "B.Cu")
		(net "P12V")
	)
	(via
		(at -353.032545 8.988745)
		(size 0.5588)
		(drill 0.254)
		(layers "F.Cu" "B.Cu")
		(net "P12V")
	)
	(via
		(at -114.046 -1.651)
		(size 0.5588)
		(drill 0.254)
		(layers "F.Cu" "B.Cu")
		(net "P12V")
	)
	(via
		(at -146.685 6.35)
		(size 0.5588)
		(drill 0.254)
		(layers "F.Cu" "B.Cu")
		(net "P12V")
	)
	(via
		(at -405.13 6.985)
		(size 0.5588)
		(drill 0.254)
		(layers "F.Cu" "B.Cu")
		(net "P12V")
	)
	(via
		(at -193.04 -1.27)
		(size 0.5588)
		(drill 0.254)
		(layers "F.Cu" "B.Cu")
		(net "P12V")
	)
	(via
		(at -227.965 27.305)
		(size 0.5588)
		(drill 0.254)
		(layers "F.Cu" "B.Cu")
		(net "P12V")
	)
	(via
		(at -271.78 -3.683)
		(size 0.5588)
		(drill 0.254)
		(layers "F.Cu" "B.Cu")
		(net "P12V")
	)
	(via
		(at -121.285 6.35)
		(size 0.5588)
		(drill 0.254)
		(layers "F.Cu" "B.Cu")
		(net "P12V")
	)
	(via
		(at -221.615 1.905)
		(size 0.5588)
		(drill 0.254)
		(layers "F.Cu" "B.Cu")
		(net "P12V")
	)
	(via
		(at -353.314 24.511)
		(size 0.5588)
		(drill 0.254)
		(layers "F.Cu" "B.Cu")
		(net "P12V")
	)
	(via
		(at -130.81 -3.175)
		(size 0.5588)
		(drill 0.254)
		(layers "F.Cu" "B.Cu")
		(net "P12V")
	)
	(via
		(at -137.16 3.175)
		(size 0.5588)
		(drill 0.254)
		(layers "F.Cu" "B.Cu")
		(net "P12V")
	)
	(via
		(at -221.615 33.655)
		(size 0.5588)
		(drill 0.254)
		(layers "F.Cu" "B.Cu")
		(net "P12V")
	)
	(via
		(at -234.315 20.955)
		(size 0.5588)
		(drill 0.254)
		(layers "F.Cu" "B.Cu")
		(net "P12V")
	)
	(via
		(at -393.7 12.065)
		(size 0.5588)
		(drill 0.254)
		(layers "F.Cu" "B.Cu")
		(net "P12V")
	)
	(via
		(at -397.51 6.985)
		(size 0.5588)
		(drill 0.254)
		(layers "F.Cu" "B.Cu")
		(net "P12V")
	)
	(via
		(at -398.78 9.525)
		(size 0.5588)
		(drill 0.254)
		(layers "F.Cu" "B.Cu")
		(net "P12V")
	)
	(via
		(at -400.05 9.525)
		(size 0.5588)
		(drill 0.254)
		(layers "F.Cu" "B.Cu")
		(net "P12V")
	)
	(via
		(at -338.455 -3.683)
		(size 0.5588)
		(drill 0.254)
		(layers "F.Cu" "B.Cu")
		(net "P12V")
	)
	(via
		(at -202.565 1.905)
		(size 0.5588)
		(drill 0.254)
		(layers "F.Cu" "B.Cu")
		(net "P12V")
	)
	(via
		(at -393.7 10.795)
		(size 0.5588)
		(drill 0.254)
		(layers "F.Cu" "B.Cu")
		(net "P12V")
	)
	(via
		(at -398.78 8.255)
		(size 0.5588)
		(drill 0.254)
		(layers "F.Cu" "B.Cu")
		(net "P12V")
	)
	(via
		(at -186.69 -1.27)
		(size 0.5588)
		(drill 0.254)
		(layers "F.Cu" "B.Cu")
		(net "P12V")
	)
	(via
		(at -408.94 9.525)
		(size 0.5588)
		(drill 0.254)
		(layers "F.Cu" "B.Cu")
		(net "P12V")
	)
	(via
		(at -193.04 5.08)
		(size 0.5588)
		(drill 0.254)
		(layers "F.Cu" "B.Cu")
		(net "P12V")
	)
	(via
		(at -196.215 27.305)
		(size 0.5588)
		(drill 0.254)
		(layers "F.Cu" "B.Cu")
		(net "P12V")
	)
	(via
		(at -394.97 8.255)
		(size 0.5588)
		(drill 0.254)
		(layers "F.Cu" "B.Cu")
		(net "P12V")
	)
	(via
		(at -199.39 5.08)
		(size 0.5588)
		(drill 0.254)
		(layers "F.Cu" "B.Cu")
		(net "P12V")
	)
	(via
		(at -146.685 16.51)
		(size 0.5588)
		(drill 0.254)
		(layers "F.Cu" "B.Cu")
		(net "P12V")
	)
	(via
		(at -183.515 14.605)
		(size 0.5588)
		(drill 0.254)
		(layers "F.Cu" "B.Cu")
		(net "P12V")
	)
	(via
		(at -362.557545 8.988745)
		(size 0.5588)
		(drill 0.254)
		(layers "F.Cu" "B.Cu")
		(net "P12V")
	)
	(via
		(at -140.335 35.56)
		(size 0.5588)
		(drill 0.254)
		(layers "F.Cu" "B.Cu")
		(net "P12V")
	)
	(via
		(at -354.937545 8.988745)
		(size 0.5588)
		(drill 0.254)
		(layers "F.Cu" "B.Cu")
		(net "P12V")
	)
	(via
		(at -115.221601 22.428302)
		(size 0.5588)
		(drill 0.254)
		(layers "F.Cu" "B.Cu")
		(net "P12V")
	)
	(via
		(at -246.38 1.905)
		(size 0.5588)
		(drill 0.254)
		(layers "F.Cu" "B.Cu")
		(net "P12V")
	)
	(via
		(at -355.6 15.875)
		(size 0.5588)
		(drill 0.254)
		(layers "F.Cu" "B.Cu")
		(net "P12V")
	)
	(via
		(at -356.842545 12.798745)
		(size 0.5588)
		(drill 0.254)
		(layers "F.Cu" "B.Cu")
		(net "P12V")
	)
	(via
		(at -357.505 -3.683)
		(size 0.5588)
		(drill 0.254)
		(layers "F.Cu" "B.Cu")
		(net "P12V")
	)
	(via
		(at -406.4 6.985)
		(size 0.5588)
		(drill 0.254)
		(layers "F.Cu" "B.Cu")
		(net "P12V")
	)
	(via
		(at -281.305 -3.683)
		(size 0.5588)
		(drill 0.254)
		(layers "F.Cu" "B.Cu")
		(net "P12V")
	)
	(via
		(at -396.24 9.525)
		(size 0.5588)
		(drill 0.254)
		(layers "F.Cu" "B.Cu")
		(net "P12V")
	)
	(via
		(at -137.16 38.735)
		(size 0.5588)
		(drill 0.254)
		(layers "F.Cu" "B.Cu")
		(net "P12V")
	)
	(via
		(at -118.11 -3.175)
		(size 0.5588)
		(drill 0.254)
		(layers "F.Cu" "B.Cu")
		(net "P12V")
	)
	(via
		(at -170.815 1.905)
		(size 0.5588)
		(drill 0.254)
		(layers "F.Cu" "B.Cu")
		(net "P12V")
	)
	(via
		(at -173.99 -1.27)
		(size 0.5588)
		(drill 0.254)
		(layers "F.Cu" "B.Cu")
		(net "P12V")
	)
	(via
		(at -402.59 8.255)
		(size 0.5588)
		(drill 0.254)
		(layers "F.Cu" "B.Cu")
		(net "P12V")
	)
	(via
		(at -332.105 -3.683)
		(size 0.5588)
		(drill 0.254)
		(layers "F.Cu" "B.Cu")
		(net "P12V")
	)
	(via
		(at -193.04 24.13)
		(size 0.5588)
		(drill 0.254)
		(layers "F.Cu" "B.Cu")
		(net "P12V")
	)
	(via
		(at -149.86 9.525)
		(size 0.5588)
		(drill 0.254)
		(layers "F.Cu" "B.Cu")
		(net "P12V")
	)
	(via
		(at -153.035 6.35)
		(size 0.5588)
		(drill 0.254)
		(layers "F.Cu" "B.Cu")
		(net "P12V")
	)
	(via
		(at -227.965 -3.683)
		(size 0.5588)
		(drill 0.254)
		(layers "F.Cu" "B.Cu")
		(net "P12V")
	)
	(via
		(at -234.315 27.305)
		(size 0.5588)
		(drill 0.254)
		(layers "F.Cu" "B.Cu")
		(net "P12V")
	)
	(via
		(at -397.51 10.795)
		(size 0.5588)
		(drill 0.254)
		(layers "F.Cu" "B.Cu")
		(net "P12V")
	)
	(via
		(at -208.915 33.655)
		(size 0.5588)
		(drill 0.254)
		(layers "F.Cu" "B.Cu")
		(net "P12V")
	)
	(via
		(at -183.515 1.905)
		(size 0.5588)
		(drill 0.254)
		(layers "F.Cu" "B.Cu")
		(net "P12V")
	)
	(via
		(at -394.97 10.795)
		(size 0.5588)
		(drill 0.254)
		(layers "F.Cu" "B.Cu")
		(net "P12V")
	)
	(via
		(at -163.195 6.477)
		(size 0.5588)
		(drill 0.254)
		(layers "F.Cu" "B.Cu")
		(net "P12V")
	)
	(via
		(at -358.747545 12.798745)
		(size 0.5588)
		(drill 0.254)
		(layers "F.Cu" "B.Cu")
		(net "P12V")
	)
	(via
		(at -349.25 15.875)
		(size 0.5588)
		(drill 0.254)
		(layers "F.Cu" "B.Cu")
		(net "P12V")
	)
	(via
		(at -358.747545 11.528745)
		(size 0.5588)
		(drill 0.254)
		(layers "F.Cu" "B.Cu")
		(net "P12V")
	)
	(via
		(at -133.985 41.91)
		(size 0.5588)
		(drill 0.254)
		(layers "F.Cu" "B.Cu")
		(net "P12V")
	)
	(via
		(at -351.127545 8.988745)
		(size 0.5588)
		(drill 0.254)
		(layers "F.Cu" "B.Cu")
		(net "P12V")
	)
	(via
		(at -208.915 40.513)
		(size 0.5588)
		(drill 0.254)
		(layers "F.Cu" "B.Cu")
		(net "P12V")
	)
	(via
		(at -392.43 10.795)
		(size 0.5588)
		(drill 0.254)
		(layers "F.Cu" "B.Cu")
		(net "P12V")
	)
	(via
		(at -196.215 14.605)
		(size 0.5588)
		(drill 0.254)
		(layers "F.Cu" "B.Cu")
		(net "P12V")
	)
	(via
		(at -354.937545 10.258745)
		(size 0.5588)
		(drill 0.254)
		(layers "F.Cu" "B.Cu")
		(net "P12V")
	)
	(via
		(at -355.6 31.75)
		(size 0.5588)
		(drill 0.254)
		(layers "F.Cu" "B.Cu")
		(net "P12V")
	)
	(via
		(at -234.315 33.655)
		(size 0.5588)
		(drill 0.254)
		(layers "F.Cu" "B.Cu")
		(net "P12V")
	)
	(via
		(at -400.05 6.985)
		(size 0.5588)
		(drill 0.254)
		(layers "F.Cu" "B.Cu")
		(net "P12V")
	)
	(via
		(at -353.032545 12.798745)
		(size 0.5588)
		(drill 0.254)
		(layers "F.Cu" "B.Cu")
		(net "P12V")
	)
	(via
		(at -352.425 28.575)
		(size 0.5588)
		(drill 0.254)
		(layers "F.Cu" "B.Cu")
		(net "P12V")
	)
	(via
		(at -163.83 -3.683)
		(size 0.5588)
		(drill 0.254)
		(layers "F.Cu" "B.Cu")
		(net "P12V")
	)
	(via
		(at -292.481 3.81)
		(size 0.5588)
		(drill 0.254)
		(layers "F.Cu" "B.Cu")
		(net "P12V")
	)
	(via
		(at -366.649 23.876)
		(size 0.5588)
		(drill 0.254)
		(layers "F.Cu" "B.Cu")
		(net "P12V")
	)
	(via
		(at -410.21 9.525)
		(size 0.5588)
		(drill 0.254)
		(layers "F.Cu" "B.Cu")
		(net "P12V")
	)
	(via
		(at -218.44 24.13)
		(size 0.5588)
		(drill 0.254)
		(layers "F.Cu" "B.Cu")
		(net "P12V")
	)
	(via
		(at -149.86 3.175)
		(size 0.5588)
		(drill 0.254)
		(layers "F.Cu" "B.Cu")
		(net "P12V")
	)
	(via
		(at -328.549 20.32)
		(size 0.5588)
		(drill 0.254)
		(layers "F.Cu" "B.Cu")
		(net "P12V")
	)
	(via
		(at -189.865 14.605)
		(size 0.5588)
		(drill 0.254)
		(layers "F.Cu" "B.Cu")
		(net "P12V")
	)
	(via
		(at -397.51 12.065)
		(size 0.5588)
		(drill 0.254)
		(layers "F.Cu" "B.Cu")
		(net "P12V")
	)
	(via
		(at -224.79 5.08)
		(size 0.5588)
		(drill 0.254)
		(layers "F.Cu" "B.Cu")
		(net "P12V")
	)
	(via
		(at -208.915 -3.683)
		(size 0.5588)
		(drill 0.254)
		(layers "F.Cu" "B.Cu")
		(net "P12V")
	)
	(via
		(at -400.05 10.795)
		(size 0.5588)
		(drill 0.254)
		(layers "F.Cu" "B.Cu")
		(net "P12V")
	)
	(via
		(at -177.165 -3.683)
		(size 0.5588)
		(drill 0.254)
		(layers "F.Cu" "B.Cu")
		(net "P12V")
	)
	(via
		(at -137.16 45.085)
		(size 0.5588)
		(drill 0.254)
		(layers "F.Cu" "B.Cu")
		(net "P12V")
	)
	(via
		(at -355.6 38.1)
		(size 0.5588)
		(drill 0.254)
		(layers "F.Cu" "B.Cu")
		(net "P12V")
	)
	(via
		(at -347.98 2.032)
		(size 0.5588)
		(drill 0.254)
		(layers "F.Cu" "B.Cu")
		(net "P12V")
	)
	(via
		(at -402.59 10.795)
		(size 0.5588)
		(drill 0.254)
		(layers "F.Cu" "B.Cu")
		(net "P12V")
	)
	(via
		(at -360.652545 8.988745)
		(size 0.5588)
		(drill 0.254)
		(layers "F.Cu" "B.Cu")
		(net "P12V")
	)
	(via
		(at -221.615 40.513)
		(size 0.5588)
		(drill 0.254)
		(layers "F.Cu" "B.Cu")
		(net "P12V")
	)
	(via
		(at -368.3 44.45)
		(size 0.5588)
		(drill 0.254)
		(layers "F.Cu" "B.Cu")
		(net "P12V")
	)
	(via
		(at -208.915 1.905)
		(size 0.5588)
		(drill 0.254)
		(layers "F.Cu" "B.Cu")
		(net "P12V")
	)
	(via
		(at -396.24 12.065)
		(size 0.5588)
		(drill 0.254)
		(layers "F.Cu" "B.Cu")
		(net "P12V")
	)
	(via
		(at -354.937545 11.528745)
		(size 0.5588)
		(drill 0.254)
		(layers "F.Cu" "B.Cu")
		(net "P12V")
	)
	(via
		(at -351.155 -3.683)
		(size 0.5588)
		(drill 0.254)
		(layers "F.Cu" "B.Cu")
		(net "P12V")
	)
	(via
		(at -186.69 11.43)
		(size 0.5588)
		(drill 0.254)
		(layers "F.Cu" "B.Cu")
		(net "P12V")
	)
	(via
		(at -205.74 -1.27)
		(size 0.5588)
		(drill 0.254)
		(layers "F.Cu" "B.Cu")
		(net "P12V")
	)
	(via
		(at -304.673 0.762)
		(size 0.5588)
		(drill 0.254)
		(layers "F.Cu" "B.Cu")
		(net "P12V")
	)
	(via
		(at -397.51 8.255)
		(size 0.5588)
		(drill 0.254)
		(layers "F.Cu" "B.Cu")
		(net "P12V")
	)
	(via
		(at -140.335 16.51)
		(size 0.5588)
		(drill 0.254)
		(layers "F.Cu" "B.Cu")
		(net "P12V")
	)
	(via
		(at -358.747545 8.988745)
		(size 0.5588)
		(drill 0.254)
		(layers "F.Cu" "B.Cu")
		(net "P12V")
	)
	(via
		(at -391.16 10.795)
		(size 0.5588)
		(drill 0.254)
		(layers "F.Cu" "B.Cu")
		(net "P12V")
	)
	(via
		(at -130.81 19.685)
		(size 0.5588)
		(drill 0.254)
		(layers "F.Cu" "B.Cu")
		(net "P12V")
	)
	(via
		(at -196.215 33.655)
		(size 0.5588)
		(drill 0.254)
		(layers "F.Cu" "B.Cu")
		(net "P12V")
	)
	(via
		(at -354.937545 12.798745)
		(size 0.5588)
		(drill 0.254)
		(layers "F.Cu" "B.Cu")
		(net "P12V")
	)
	(via
		(at -406.4 8.255)
		(size 0.5588)
		(drill 0.254)
		(layers "F.Cu" "B.Cu")
		(net "P12V")
	)
	(via
		(at -137.16 32.385)
		(size 0.5588)
		(drill 0.254)
		(layers "F.Cu" "B.Cu")
		(net "P12V")
	)
	(via
		(at -193.04 36.83)
		(size 0.5588)
		(drill 0.254)
		(layers "F.Cu" "B.Cu")
		(net "P12V")
	)
	(via
		(at -173.99 5.08)
		(size 0.5588)
		(drill 0.254)
		(layers "F.Cu" "B.Cu")
		(net "P12V")
	)
	(via
		(at -215.265 1.905)
		(size 0.5588)
		(drill 0.254)
		(layers "F.Cu" "B.Cu")
		(net "P12V")
	)
	(via
		(at -356.842545 10.258745)
		(size 0.5588)
		(drill 0.254)
		(layers "F.Cu" "B.Cu")
		(net "P12V")
	)
	(via
		(at -208.915 14.605)
		(size 0.5588)
		(drill 0.254)
		(layers "F.Cu" "B.Cu")
		(net "P12V")
	)
	(via
		(at -124.46 9.525)
		(size 0.5588)
		(drill 0.254)
		(layers "F.Cu" "B.Cu")
		(net "P12V")
	)
	(via
		(at -407.67 6.985)
		(size 0.5588)
		(drill 0.254)
		(layers "F.Cu" "B.Cu")
		(net "P12V")
	)
	(via
		(at -325.755 -3.683)
		(size 0.5588)
		(drill 0.254)
		(layers "F.Cu" "B.Cu")
		(net "P12V")
	)
	(via
		(at -392.43 9.525)
		(size 0.5588)
		(drill 0.254)
		(layers "F.Cu" "B.Cu")
		(net "P12V")
	)
	(via
		(at -227.965 1.905)
		(size 0.5588)
		(drill 0.254)
		(layers "F.Cu" "B.Cu")
		(net "P12V")
	)
	(via
		(at -334.449001 22.6568)
		(size 0.5588)
		(drill 0.254)
		(layers "F.Cu" "B.Cu")
		(net "P12V")
	)
	(via
		(at -265.43 -3.683)
		(size 0.5588)
		(drill 0.254)
		(layers "F.Cu" "B.Cu")
		(net "P12V")
	)
	(via
		(at -365.125 41.275)
		(size 0.5588)
		(drill 0.254)
		(layers "F.Cu" "B.Cu")
		(net "P12V")
	)
	(via
		(at -364.462545 11.528745)
		(size 0.5588)
		(drill 0.254)
		(layers "F.Cu" "B.Cu")
		(net "P12V")
	)
	(via
		(at -143.51 38.735)
		(size 0.5588)
		(drill 0.254)
		(layers "F.Cu" "B.Cu")
		(net "P12V")
	)
	(via
		(at -156.464 6.477)
		(size 0.5588)
		(drill 0.254)
		(layers "F.Cu" "B.Cu")
		(net "P12V")
	)
	(via
		(at -363.728 4.572)
		(size 0.5588)
		(drill 0.254)
		(layers "F.Cu" "B.Cu")
		(net "P12V")
	)
	(via
		(at -389.89 9.525)
		(size 0.5588)
		(drill 0.254)
		(layers "F.Cu" "B.Cu")
		(net "P12V")
	)
	(via
		(at -208.915 27.305)
		(size 0.5588)
		(drill 0.254)
		(layers "F.Cu" "B.Cu")
		(net "P12V")
	)
	(via
		(at -392.43 8.255)
		(size 0.5588)
		(drill 0.254)
		(layers "F.Cu" "B.Cu")
		(net "P12V")
	)
	(via
		(at -196.215 1.905)
		(size 0.5588)
		(drill 0.254)
		(layers "F.Cu" "B.Cu")
		(net "P12V")
	)
	(via
		(at -109.474 -1.651)
		(size 0.5588)
		(drill 0.254)
		(layers "F.Cu" "B.Cu")
		(net "P12V")
	)
	(via
		(at -121.285 0)
		(size 0.5588)
		(drill 0.254)
		(layers "F.Cu" "B.Cu")
		(net "P12V")
	)
	(via
		(at -117.348 18.669)
		(size 0.5588)
		(drill 0.254)
		(layers "F.Cu" "B.Cu")
		(net "P12V")
	)
	(via
		(at -353.032545 11.528745)
		(size 0.5588)
		(drill 0.254)
		(layers "F.Cu" "B.Cu")
		(net "P12V")
	)
	(via
		(at -364.462545 12.798745)
		(size 0.5588)
		(drill 0.254)
		(layers "F.Cu" "B.Cu")
		(net "P12V")
	)
	(via
		(at -403.86 9.525)
		(size 0.5588)
		(drill 0.254)
		(layers "F.Cu" "B.Cu")
		(net "P12V")
	)
	(via
		(at -124.46 -3.175)
		(size 0.5588)
		(drill 0.254)
		(layers "F.Cu" "B.Cu")
		(net "P12V")
	)
	(via
		(at -408.94 6.985)
		(size 0.5588)
		(drill 0.254)
		(layers "F.Cu" "B.Cu")
		(net "P12V")
	)
	(via
		(at -212.09 30.48)
		(size 0.5588)
		(drill 0.254)
		(layers "F.Cu" "B.Cu")
		(net "P12V")
	)
	(via
		(at -282.321 3.81)
		(size 0.5588)
		(drill 0.254)
		(layers "F.Cu" "B.Cu")
		(net "P12V")
	)
	(via
		(at -364.462545 8.988745)
		(size 0.5588)
		(drill 0.254)
		(layers "F.Cu" "B.Cu")
		(net "P12V")
	)
	(via
		(at -231.14 24.13)
		(size 0.5588)
		(drill 0.254)
		(layers "F.Cu" "B.Cu")
		(net "P12V")
	)
	(via
		(at -240.03 -3.683)
		(size 0.5588)
		(drill 0.254)
		(layers "F.Cu" "B.Cu")
		(net "P12V")
	)
	(via
		(at -224.79 -1.27)
		(size 0.5588)
		(drill 0.254)
		(layers "F.Cu" "B.Cu")
		(net "P12V")
	)
	(via
		(at -137.16 9.525)
		(size 0.5588)
		(drill 0.254)
		(layers "F.Cu" "B.Cu")
		(net "P12V")
	)
	(via
		(at -351.127545 11.528745)
		(size 0.5588)
		(drill 0.254)
		(layers "F.Cu" "B.Cu")
		(net "P12V")
	)
	(via
		(at -358.775 41.275)
		(size 0.5588)
		(drill 0.254)
		(layers "F.Cu" "B.Cu")
		(net "P12V")
	)
	(via
		(at -234.188 -3.683)
		(size 0.5588)
		(drill 0.254)
		(layers "F.Cu" "B.Cu")
		(net "P12V")
	)
	(via
		(at -335.846001 22.453702)
		(size 0.5588)
		(drill 0.254)
		(layers "F.Cu" "B.Cu")
		(net "P12V")
	)
	(via
		(at -215.265 14.605)
		(size 0.5588)
		(drill 0.254)
		(layers "F.Cu" "B.Cu")
		(net "P12V")
	)
	(via
		(at -410.21 8.255)
		(size 0.5588)
		(drill 0.254)
		(layers "F.Cu" "B.Cu")
		(net "P12V")
	)
	(via
		(at -400.05 12.065)
		(size 0.5588)
		(drill 0.254)
		(layers "F.Cu" "B.Cu")
		(net "P12V")
	)
	(via
		(at -300.355 -3.683)
		(size 0.5588)
		(drill 0.254)
		(layers "F.Cu" "B.Cu")
		(net "P12V")
	)
	(via
		(at -133.985 6.35)
		(size 0.5588)
		(drill 0.254)
		(layers "F.Cu" "B.Cu")
		(net "P12V")
	)
	(via
		(at -360.652545 12.798745)
		(size 0.5588)
		(drill 0.254)
		(layers "F.Cu" "B.Cu")
		(net "P12V")
	)
	(via
		(at -196.215 20.955)
		(size 0.5588)
		(drill 0.254)
		(layers "F.Cu" "B.Cu")
		(net "P12V")
	)
	(via
		(at -140.335 41.91)
		(size 0.5588)
		(drill 0.254)
		(layers "F.Cu" "B.Cu")
		(net "P12V")
	)
	(via
		(at -146.685 41.91)
		(size 0.5588)
		(drill 0.254)
		(layers "F.Cu" "B.Cu")
		(net "P12V")
	)
	(via
		(at -351.155 4.572)
		(size 0.5588)
		(drill 0.254)
		(layers "F.Cu" "B.Cu")
		(net "P12V")
	)
	(via
		(at -130.81 3.175)
		(size 0.5588)
		(drill 0.254)
		(layers "F.Cu" "B.Cu")
		(net "P12V")
	)
	(via
		(at -398.78 6.985)
		(size 0.5588)
		(drill 0.254)
		(layers "F.Cu" "B.Cu")
		(net "P12V")
	)
	(via
		(at -403.86 6.985)
		(size 0.5588)
		(drill 0.254)
		(layers "F.Cu" "B.Cu")
		(net "P12V")
	)
	(via
		(at -403.86 12.065)
		(size 0.5588)
		(drill 0.254)
		(layers "F.Cu" "B.Cu")
		(net "P12V")
	)
	(via
		(at -364.462545 10.258745)
		(size 0.5588)
		(drill 0.254)
		(layers "F.Cu" "B.Cu")
		(net "P12V")
	)
	(via
		(at -231.14 17.78)
		(size 0.5588)
		(drill 0.254)
		(layers "F.Cu" "B.Cu")
		(net "P12V")
	)
	(segment
		(start -205.93825 22.10485)
		(end -204.940799 21.1074)
		(width 0.381)
		(layer "B.Cu")
		(net "P12V")
	)
	(segment
		(start -200.761605 19.786595)
		(end -199.4408 21.1074)
		(width 0.381)
		(layer "B.Cu")
		(net "P12V")
	)
	(segment
		(start -200.761605 22.428205)
		(end -199.4408 21.1074)
		(width 0.381)
		(layer "B.Cu")
		(net "P12V")
	)
	(segment
		(start -199.4408 21.1074)
		(end -198.119995 19.786595)
		(width 0.381)
		(layer "B.Cu")
		(net "P12V")
	)
	(segment
		(start -204.940799 21.1074)
		(end -203.943349 22.10485)
		(width 0.381)
		(layer "B.Cu")
		(net "P12V")
	)
	(segment
		(start -205.93825 20.10995)
		(end -204.940799 21.1074)
		(width 0.381)
		(layer "B.Cu")
		(net "P12V")
	)
	(segment
		(start -204.940799 21.1074)
		(end -203.943349 20.10995)
		(width 0.381)
		(layer "B.Cu")
		(net "P12V")
	)
	(segment
		(start -199.4408 21.1074)
		(end -198.119995 22.428205)
		(width 0.381)
		(layer "B.Cu")
		(net "P12V")
	)
	(segment
		(start -200.43825 22.10485)
		(end -199.4408 21.1074)
		(width 0.381)
		(layer "In3.Cu")
		(net "P12V")
	)
	(segment
		(start -199.4408 21.1074)
		(end -198.44335 20.10995)
		(width 0.381)
		(layer "In3.Cu")
		(net "P12V")
	)
	(segment
		(start -205.93825 22.10485)
		(end -204.940799 21.1074)
		(width 0.381)
		(layer "In3.Cu")
		(net "P12V")
	)
	(segment
		(start -205.93825 20.10995)
		(end -204.940799 21.1074)
		(width 0.381)
		(layer "In3.Cu")
		(net "P12V")
	)
	(segment
		(start -204.940799 21.1074)
		(end -203.943349 20.10995)
		(width 0.381)
		(layer "In3.Cu")
		(net "P12V")
	)
	(segment
		(start -199.4408 21.1074)
		(end -198.44335 22.10485)
		(width 0.381)
		(layer "In3.Cu")
		(net "P12V")
	)
	(segment
		(start -200.43825 20.10995)
		(end -199.4408 21.1074)
		(width 0.381)
		(layer "In3.Cu")
		(net "P12V")
	)
	(segment
		(start -204.940799 21.1074)
		(end -203.943349 22.10485)
		(width 0.381)
		(layer "In3.Cu")
		(net "P12V")
	)
	(segment
		(start -199.4408 21.1074)
		(end -198.44335 22.10485)
		(width 0.381)
		(layer "In4.Cu")
		(net "P12V")
	)
	(segment
		(start -199.4408 21.1074)
		(end -198.44335 20.10995)
		(width 0.381)
		(layer "In4.Cu")
		(net "P12V")
	)
	(segment
		(start -200.43825 20.10995)
		(end -199.4408 21.1074)
		(width 0.381)
		(layer "In4.Cu")
		(net "P12V")
	)
	(segment
		(start -204.940799 21.1074)
		(end -203.943349 20.10995)
		(width 0.381)
		(layer "In4.Cu")
		(net "P12V")
	)
	(segment
		(start -204.940799 21.1074)
		(end -203.943349 22.10485)
		(width 0.381)
		(layer "In4.Cu")
		(net "P12V")
	)
	(segment
		(start -200.43825 22.10485)
		(end -199.4408 21.1074)
		(width 0.381)
		(layer "In4.Cu")
		(net "P12V")
	)
	(segment
		(start -205.93825 22.10485)
		(end -204.940799 21.1074)
		(width 0.381)
		(layer "In4.Cu")
		(net "P12V")
	)
	(segment
		(start -205.93825 20.10995)
		(end -204.940799 21.1074)
		(width 0.381)
		(layer "In4.Cu")
		(net "P12V")
	)
	(segment
		(start -199.4408 21.1074)
		(end -198.44335 22.10485)
		(width 0.381)
		(layer "In5.Cu")
		(net "P12V")
	)
	(segment
		(start -200.43825 20.10995)
		(end -199.4408 21.1074)
		(width 0.381)
		(layer "In5.Cu")
		(net "P12V")
	)
	(segment
		(start -204.940799 21.1074)
		(end -203.943349 20.10995)
		(width 0.381)
		(layer "In5.Cu")
		(net "P12V")
	)
	(segment
		(start -200.43825 22.10485)
		(end -199.4408 21.1074)
		(width 0.381)
		(layer "In5.Cu")
		(net "P12V")
	)
	(segment
		(start -199.4408 21.1074)
		(end -198.44335 20.10995)
		(width 0.381)
		(layer "In5.Cu")
		(net "P12V")
	)
	(segment
		(start -205.93825 20.10995)
		(end -204.940799 21.1074)
		(width 0.381)
		(layer "In5.Cu")
		(net "P12V")
	)
	(segment
		(start -205.93825 22.10485)
		(end -204.940799 21.1074)
		(width 0.381)
		(layer "In5.Cu")
		(net "P12V")
	)
	(segment
		(start -204.940799 21.1074)
		(end -203.943349 22.10485)
		(width 0.381)
		(layer "In5.Cu")
		(net "P12V")
	)
	(segment
		(start -252.867201 32.524913)
		(end -252.84176 32.550354)
		(width 0.1016)
		(layer "F.Cu")
		(net "SERIAL_B1_TX1")
	)
	(segment
		(start -411.8864 15.1638)
		(end -411.8864 15.5194)
		(width 0.1016)
		(layer "F.Cu")
		(net "SERIAL_B1_TX1")
	)
	(segment
		(start -252.84176 44.25188)
		(end -251.733639 45.360001)
		(width 0.1016)
		(layer "F.Cu")
		(net "SERIAL_B1_TX1")
	)
	(segment
		(start -259.62356 31.23184)
		(end -259.0927 31.7627)
		(width 0.1016)
		(layer "F.Cu")
		(net "SERIAL_B1_TX1")
	)
	(segment
		(start -252.84176 32.550354)
		(end -252.84176 44.25188)
		(width 0.1016)
		(layer "F.Cu")
		(net "SERIAL_B1_TX1")
	)
	(segment
		(start -253.344914 32.0472)
		(end -253.343291 32.0472)
		(width 0.1016)
		(layer "F.Cu")
		(net "SERIAL_B1_TX1")
	)
	(segment
		(start -413.89 4.8798)
		(end -411.56128 7.20852)
		(width 0.1016)
		(layer "F.Cu")
		(net "SERIAL_B1_TX1")
	)
	(segment
		(start -411.56128 7.20852)
		(end -411.56128 14.83868)
		(width 0.1016)
		(layer "F.Cu")
		(net "SERIAL_B1_TX1")
	)
	(segment
		(start -298.6532 34.946801)
		(end -298.040001 35.56)
		(width 0.1016)
		(layer "F.Cu")
		(net "SERIAL_B1_TX1")
	)
	(segment
		(start -411.56128 14.83868)
		(end -411.8864 15.1638)
		(width 0.1016)
		(layer "F.Cu")
		(net "SERIAL_B1_TX1")
	)
	(segment
		(start -413.89 -1.840001)
		(end -413.89 4.8798)
		(width 0.1016)
		(layer "F.Cu")
		(net "SERIAL_B1_TX1")
	)
	(segment
		(start -298.6532 32.9438)
		(end -298.6532 34.946801)
		(width 0.1016)
		(layer "F.Cu")
		(net "SERIAL_B1_TX1")
	)
	(segment
		(start -253.629414 31.7627)
		(end -253.344914 32.0472)
		(width 0.1016)
		(layer "F.Cu")
		(net "SERIAL_B1_TX1")
	)
	(segment
		(start -251.733639 45.360001)
		(end -251.68 45.360001)
		(width 0.1016)
		(layer "F.Cu")
		(net "SERIAL_B1_TX1")
	)
	(segment
		(start -253.343291 32.0472)
		(end -252.867201 32.52329)
		(width 0.1016)
		(layer "F.Cu")
		(net "SERIAL_B1_TX1")
	)
	(segment
		(start -294.64 29.2354)
		(end -294.9448 29.2354)
		(width 0.1016)
		(layer "F.Cu")
		(net "SERIAL_B1_TX1")
	)
	(segment
		(start -294.9448 29.2354)
		(end -298.6532 32.9438)
		(width 0.1016)
		(layer "F.Cu")
		(net "SERIAL_B1_TX1")
	)
	(segment
		(start -252.867201 32.52329)
		(end -252.867201 32.524913)
		(width 0.1016)
		(layer "F.Cu")
		(net "SERIAL_B1_TX1")
	)
	(segment
		(start -259.0927 31.7627)
		(end -253.629414 31.7627)
		(width 0.1016)
		(layer "F.Cu")
		(net "SERIAL_B1_TX1")
	)
	(via
		(at -259.62356 31.23184)
		(size 0.5588)
		(drill 0.254)
		(layers "F.Cu" "B.Cu")
		(net "SERIAL_B1_TX1")
	)
	(via
		(at -294.64 29.2354)
		(size 0.5588)
		(drill 0.254)
		(layers "F.Cu" "B.Cu")
		(net "SERIAL_B1_TX1")
	)
	(via
		(at -411.8864 15.5194)
		(size 0.5588)
		(drill 0.254)
		(layers "F.Cu" "B.Cu")
		(net "SERIAL_B1_TX1")
	)
	(via
		(at -368.0714 18.2372)
		(size 0.5588)
		(drill 0.254)
		(layers "F.Cu" "B.Cu")
		(net "SERIAL_B1_TX1")
	)
	(segment
		(start -293.624 28.2194)
		(end -293.0652 28.2194)
		(width 0.1016)
		(layer "B.Cu")
		(net "SERIAL_B1_TX1")
	)
	(segment
		(start -265.303 26.924)
		(end -263.155712 29.071288)
		(width 0.1016)
		(layer "B.Cu")
		(net "SERIAL_B1_TX1")
	)
	(segment
		(start -327.64476 22.987)
		(end -332.613 22.987)
		(width 0.1016)
		(layer "B.Cu")
		(net "SERIAL_B1_TX1")
	)
	(segment
		(start -295.70934 28.16606)
		(end -302.18634 28.16606)
		(width 0.1016)
		(layer "B.Cu")
		(net "SERIAL_B1_TX1")
	)
	(segment
		(start -263.155712 29.071288)
		(end -263.155712 32.777908)
		(width 0.1016)
		(layer "B.Cu")
		(net "SERIAL_B1_TX1")
	)
	(segment
		(start -262.636 33.297619)
		(end -261.689339 33.297619)
		(width 0.1016)
		(layer "B.Cu")
		(net "SERIAL_B1_TX1")
	)
	(segment
		(start -366.0902 16.9672)
		(end -367.3602 18.2372)
		(width 0.1016)
		(layer "B.Cu")
		(net "SERIAL_B1_TX1")
	)
	(segment
		(start -342.1634 16.9672)
		(end -366.0902 16.9672)
		(width 0.1016)
		(layer "B.Cu")
		(net "SERIAL_B1_TX1")
	)
	(segment
		(start -261.689339 33.297619)
		(end -259.62356 31.23184)
		(width 0.1016)
		(layer "B.Cu")
		(net "SERIAL_B1_TX1")
	)
	(segment
		(start -332.74 23.114)
		(end -336.0166 23.114)
		(width 0.1016)
		(layer "B.Cu")
		(net "SERIAL_B1_TX1")
	)
	(segment
		(start -286.4358 24.638)
		(end -278.6126 24.638)
		(width 0.1016)
		(layer "B.Cu")
		(net "SERIAL_B1_TX1")
	)
	(segment
		(start -276.3266 26.924)
		(end -265.303 26.924)
		(width 0.1016)
		(layer "B.Cu")
		(net "SERIAL_B1_TX1")
	)
	(segment
		(start -294.64 29.2354)
		(end -295.70934 28.16606)
		(width 0.1016)
		(layer "B.Cu")
		(net "SERIAL_B1_TX1")
	)
	(segment
		(start -320.9798 24.3332)
		(end -322.69684 22.61616)
		(width 0.1016)
		(layer "B.Cu")
		(net "SERIAL_B1_TX1")
	)
	(segment
		(start -327.27392 22.61616)
		(end -327.64476 22.987)
		(width 0.1016)
		(layer "B.Cu")
		(net "SERIAL_B1_TX1")
	)
	(segment
		(start -302.18634 28.16606)
		(end -306.0192 24.3332)
		(width 0.1016)
		(layer "B.Cu")
		(net "SERIAL_B1_TX1")
	)
	(segment
		(start -294.64 29.2354)
		(end -293.624 28.2194)
		(width 0.1016)
		(layer "B.Cu")
		(net "SERIAL_B1_TX1")
	)
	(segment
		(start -367.3602 18.2372)
		(end -368.0714 18.2372)
		(width 0.1016)
		(layer "B.Cu")
		(net "SERIAL_B1_TX1")
	)
	(segment
		(start -290.7792 22.3774)
		(end -288.6964 22.3774)
		(width 0.1016)
		(layer "B.Cu")
		(net "SERIAL_B1_TX1")
	)
	(segment
		(start -293.0652 28.2194)
		(end -292.1 27.2542)
		(width 0.1016)
		(layer "B.Cu")
		(net "SERIAL_B1_TX1")
	)
	(segment
		(start -278.6126 24.638)
		(end -276.3266 26.924)
		(width 0.1016)
		(layer "B.Cu")
		(net "SERIAL_B1_TX1")
	)
	(segment
		(start -322.69684 22.61616)
		(end -327.27392 22.61616)
		(width 0.1016)
		(layer "B.Cu")
		(net "SERIAL_B1_TX1")
	)
	(segment
		(start -336.0166 23.114)
		(end -342.1634 16.9672)
		(width 0.1016)
		(layer "B.Cu")
		(net "SERIAL_B1_TX1")
	)
	(segment
		(start -332.613 22.987)
		(end -332.74 23.114)
		(width 0.1016)
		(layer "B.Cu")
		(net "SERIAL_B1_TX1")
	)
	(segment
		(start -292.1 23.6982)
		(end -290.7792 22.3774)
		(width 0.1016)
		(layer "B.Cu")
		(net "SERIAL_B1_TX1")
	)
	(segment
		(start -306.0192 24.3332)
		(end -320.9798 24.3332)
		(width 0.1016)
		(layer "B.Cu")
		(net "SERIAL_B1_TX1")
	)
	(segment
		(start -263.155712 32.777908)
		(end -262.636 33.297619)
		(width 0.1016)
		(layer "B.Cu")
		(net "SERIAL_B1_TX1")
	)
	(segment
		(start -288.6964 22.3774)
		(end -286.4358 24.638)
		(width 0.1016)
		(layer "B.Cu")
		(net "SERIAL_B1_TX1")
	)
	(segment
		(start -292.1 27.2542)
		(end -292.1 23.6982)
		(width 0.1016)
		(layer "B.Cu")
		(net "SERIAL_B1_TX1")
	)
	(segment
		(start -409.6512 15.5194)
		(end -408.95524 14.82344)
		(width 0.12954)
		(layer "In2.Cu")
		(net "SERIAL_B1_TX1")
	)
	(segment
		(start -369.1382 18.2372)
		(end -368.0714 18.2372)
		(width 0.12954)
		(layer "In2.Cu")
		(net "SERIAL_B1_TX1")
	)
	(segment
		(start -411.8864 15.5194)
		(end -409.6512 15.5194)
		(width 0.12954)
		(layer "In2.Cu")
		(net "SERIAL_B1_TX1")
	)
	(segment
		(start -372.55196 14.82344)
		(end -369.1382 18.2372)
		(width 0.12954)
		(layer "In2.Cu")
		(net "SERIAL_B1_TX1")
	)
	(segment
		(start -408.95524 14.82344)
		(end -372.55196 14.82344)
		(width 0.12954)
		(layer "In2.Cu")
		(net "SERIAL_B1_TX1")
	)
	(segment
		(start -252.528832 32.387286)
		(end -252.528832 43.111169)
		(width 0.1016)
		(layer "F.Cu")
		(net "SERIAL_B1_RX1")
	)
	(segment
		(start -412.16834 16.0274)
		(end -412.39948 15.79626)
		(width 0.1016)
		(layer "F.Cu")
		(net "SERIAL_B1_RX1")
	)
	(segment
		(start -411.85846 7.54634)
		(end -415.16 4.2448)
		(width 0.1016)
		(layer "F.Cu")
		(net "SERIAL_B1_RX1")
	)
	(segment
		(start -412.39948 15.27302)
		(end -411.85846 14.732)
		(width 0.1016)
		(layer "F.Cu")
		(net "SERIAL_B1_RX1")
	)
	(segment
		(start -412.39948 15.79626)
		(end -412.39948 15.27302)
		(width 0.1016)
		(layer "F.Cu")
		(net "SERIAL_B1_RX1")
	)
	(segment
		(start -258.32308 31.1404)
		(end -253.775718 31.1404)
		(width 0.1016)
		(layer "F.Cu")
		(net "SERIAL_B1_RX1")
	)
	(segment
		(start -411.0482 16.0274)
		(end -412.16834 16.0274)
		(width 0.1016)
		(layer "F.Cu")
		(net "SERIAL_B1_RX1")
	)
	(segment
		(start -252.528832 43.111169)
		(end -251.68 43.960001)
		(width 0.1016)
		(layer "F.Cu")
		(net "SERIAL_B1_RX1")
	)
	(segment
		(start -415.16 4.2448)
		(end -415.16 -1.840001)
		(width 0.1016)
		(layer "F.Cu")
		(net "SERIAL_B1_RX1")
	)
	(segment
		(start -253.775718 31.1404)
		(end -252.528832 32.387286)
		(width 0.1016)
		(layer "F.Cu")
		(net "SERIAL_B1_RX1")
	)
	(segment
		(start -258.48818 31.3055)
		(end -258.32308 31.1404)
		(width 0.1016)
		(layer "F.Cu")
		(net "SERIAL_B1_RX1")
	)
	(segment
		(start -411.85846 14.732)
		(end -411.85846 7.54634)
		(width 0.1016)
		(layer "F.Cu")
		(net "SERIAL_B1_RX1")
	)
	(via
		(at -411.0482 16.0274)
		(size 0.5588)
		(drill 0.254)
		(layers "F.Cu" "B.Cu")
		(net "SERIAL_B1_RX1")
	)
	(via
		(at -258.48818 31.3055)
		(size 0.5588)
		(drill 0.254)
		(layers "F.Cu" "B.Cu")
		(net "SERIAL_B1_RX1")
	)
	(via
		(at -368.808 18.796)
		(size 0.5588)
		(drill 0.254)
		(layers "F.Cu" "B.Cu")
		(net "SERIAL_B1_RX1")
	)
	(segment
		(start -342.2142 17.2974)
		(end -336.1436 23.368)
		(width 0.1016)
		(layer "B.Cu")
		(net "SERIAL_B1_RX1")
	)
	(segment
		(start -368.808 18.796)
		(end -367.4872 18.796)
		(width 0.1016)
		(layer "B.Cu")
		(net "SERIAL_B1_RX1")
	)
	(segment
		(start -322.232 23.4874)
		(end -321.1322 24.5872)
		(width 0.1016)
		(layer "B.Cu")
		(net "SERIAL_B1_RX1")
	)
	(segment
		(start -302.336164 28.4226)
		(end -296.7228 28.4226)
		(width 0.1016)
		(layer "B.Cu")
		(net "SERIAL_B1_RX1")
	)
	(segment
		(start -276.4536 27.305)
		(end -278.7396 25.019)
		(width 0.1016)
		(layer "B.Cu")
		(net "SERIAL_B1_RX1")
	)
	(segment
		(start -263.525 29.21)
		(end -265.43 27.305)
		(width 0.1016)
		(layer "B.Cu")
		(net "SERIAL_B1_RX1")
	)
	(segment
		(start -291.719 27.3812)
		(end -294.1574 29.8196)
		(width 0.1016)
		(layer "B.Cu")
		(net "SERIAL_B1_RX1")
	)
	(segment
		(start -322.843248 22.87524)
		(end -322.232 23.486488)
		(width 0.1016)
		(layer "B.Cu")
		(net "SERIAL_B1_RX1")
	)
	(segment
		(start -326.88784 22.87524)
		(end -322.843248 22.87524)
		(width 0.1016)
		(layer "B.Cu")
		(net "SERIAL_B1_RX1")
	)
	(segment
		(start -294.1574 29.8196)
		(end -296.0624 29.8196)
		(width 0.1016)
		(layer "B.Cu")
		(net "SERIAL_B1_RX1")
	)
	(segment
		(start -290.6776 22.7076)
		(end -291.719 23.749)
		(width 0.1016)
		(layer "B.Cu")
		(net "SERIAL_B1_RX1")
	)
	(segment
		(start -327.3806 23.368)
		(end -326.88784 22.87524)
		(width 0.1016)
		(layer "B.Cu")
		(net "SERIAL_B1_RX1")
	)
	(segment
		(start -297.1292 36.049199)
		(end -298.040001 36.96)
		(width 0.1016)
		(layer "B.Cu")
		(net "SERIAL_B1_RX1")
	)
	(segment
		(start -296.0624 29.083)
		(end -296.0624 29.8196)
		(width 0.1016)
		(layer "B.Cu")
		(net "SERIAL_B1_RX1")
	)
	(segment
		(start -296.0624 29.8196)
		(end -297.4594 31.2166)
		(width 0.1016)
		(layer "B.Cu")
		(net "SERIAL_B1_RX1")
	)
	(segment
		(start -258.48818 31.3055)
		(end -260.79958 33.6169)
		(width 0.1016)
		(layer "B.Cu")
		(net "SERIAL_B1_RX1")
	)
	(segment
		(start -367.4872 18.796)
		(end -365.9886 17.2974)
		(width 0.1016)
		(layer "B.Cu")
		(net "SERIAL_B1_RX1")
	)
	(segment
		(start -289.0012 22.7076)
		(end -290.6776 22.7076)
		(width 0.1016)
		(layer "B.Cu")
		(net "SERIAL_B1_RX1")
	)
	(segment
		(start -297.4594 31.2166)
		(end -297.4594 33.3502)
		(width 0.1016)
		(layer "B.Cu")
		(net "SERIAL_B1_RX1")
	)
	(segment
		(start -365.9886 17.2974)
		(end -342.2142 17.2974)
		(width 0.1016)
		(layer "B.Cu")
		(net "SERIAL_B1_RX1")
	)
	(segment
		(start -296.7228 28.4226)
		(end -296.0624 29.083)
		(width 0.1016)
		(layer "B.Cu")
		(net "SERIAL_B1_RX1")
	)
	(segment
		(start -286.6898 25.019)
		(end -289.0012 22.7076)
		(width 0.1016)
		(layer "B.Cu")
		(net "SERIAL_B1_RX1")
	)
	(segment
		(start -263.525 32.798057)
		(end -263.525 29.21)
		(width 0.1016)
		(layer "B.Cu")
		(net "SERIAL_B1_RX1")
	)
	(segment
		(start -262.706157 33.6169)
		(end -263.525 32.798057)
		(width 0.1016)
		(layer "B.Cu")
		(net "SERIAL_B1_RX1")
	)
	(segment
		(start -336.1436 23.368)
		(end -327.3806 23.368)
		(width 0.1016)
		(layer "B.Cu")
		(net "SERIAL_B1_RX1")
	)
	(segment
		(start -265.43 27.305)
		(end -276.4536 27.305)
		(width 0.1016)
		(layer "B.Cu")
		(net "SERIAL_B1_RX1")
	)
	(segment
		(start -278.7396 25.019)
		(end -286.6898 25.019)
		(width 0.1016)
		(layer "B.Cu")
		(net "SERIAL_B1_RX1")
	)
	(segment
		(start -306.171564 24.5872)
		(end -302.336164 28.4226)
		(width 0.1016)
		(layer "B.Cu")
		(net "SERIAL_B1_RX1")
	)
	(segment
		(start -297.1292 33.6804)
		(end -297.1292 36.049199)
		(width 0.1016)
		(layer "B.Cu")
		(net "SERIAL_B1_RX1")
	)
	(segment
		(start -321.1322 24.5872)
		(end -306.171564 24.5872)
		(width 0.1016)
		(layer "B.Cu")
		(net "SERIAL_B1_RX1")
	)
	(segment
		(start -260.79958 33.6169)
		(end -262.706157 33.6169)
		(width 0.1016)
		(layer "B.Cu")
		(net "SERIAL_B1_RX1")
	)
	(segment
		(start -322.232 23.486488)
		(end -322.232 23.4874)
		(width 0.1016)
		(layer "B.Cu")
		(net "SERIAL_B1_RX1")
	)
	(segment
		(start -297.4594 33.3502)
		(end -297.1292 33.6804)
		(width 0.1016)
		(layer "B.Cu")
		(net "SERIAL_B1_RX1")
	)
	(segment
		(start -291.719 23.749)
		(end -291.719 27.3812)
		(width 0.1016)
		(layer "B.Cu")
		(net "SERIAL_B1_RX1")
	)
	(segment
		(start -369.2144 18.796)
		(end -368.808 18.796)
		(width 0.12954)
		(layer "In2.Cu")
		(net "SERIAL_B1_RX1")
	)
	(segment
		(start -372.90502 15.10538)
		(end -369.2144 18.796)
		(width 0.12954)
		(layer "In2.Cu")
		(net "SERIAL_B1_RX1")
	)
	(segment
		(start -411.0482 16.0274)
		(end -409.6004 16.0274)
		(width 0.12954)
		(layer "In2.Cu")
		(net "SERIAL_B1_RX1")
	)
	(segment
		(start -409.6004 16.0274)
		(end -408.67838 15.10538)
		(width 0.12954)
		(layer "In2.Cu")
		(net "SERIAL_B1_RX1")
	)
	(segment
		(start -408.67838 15.10538)
		(end -372.90502 15.10538)
		(width 0.12954)
		(layer "In2.Cu")
		(net "SERIAL_B1_RX1")
	)
	(segment
		(start -149.634999 18.894999)
		(end -150.269999 18.259999)
		(width 0.127)
		(layer "F.Cu")
		(net "MEZZ_PRESENT_B2_N")
	)
	(via
		(at -150.269999 18.259999)
		(size 0.5588)
		(drill 0.254)
		(layers "F.Cu" "B.Cu")
		(net "MEZZ_PRESENT_B2_N")
	)
	(segment
		(start -182.479 24.13)
		(end -179.1516 20.8026)
		(width 0.12954)
		(layer "In3.Cu")
		(net "MEZZ_PRESENT_B2_N")
	)
	(segment
		(start -182.479 34.544)
		(end -182.479 24.13)
		(width 0.12954)
		(layer "In3.Cu")
		(net "MEZZ_PRESENT_B2_N")
	)
	(segment
		(start -181.46 35.56)
		(end -181.463 35.56)
		(width 0.12954)
		(layer "In3.Cu")
		(net "MEZZ_PRESENT_B2_N")
	)
	(segment
		(start -163.5306 20.8026)
		(end -159.5936 16.8656)
		(width 0.12954)
		(layer "In3.Cu")
		(net "MEZZ_PRESENT_B2_N")
	)
	(segment
		(start -159.5936 16.8656)
		(end -155.4026 16.8656)
		(width 0.12954)
		(layer "In3.Cu")
		(net "MEZZ_PRESENT_B2_N")
	)
	(segment
		(start -150.876998 17.653)
		(end -150.269999 18.259999)
		(width 0.12954)
		(layer "In3.Cu")
		(net "MEZZ_PRESENT_B2_N")
	)
	(segment
		(start -179.1516 20.8026)
		(end -163.5306 20.8026)
		(width 0.12954)
		(layer "In3.Cu")
		(net "MEZZ_PRESENT_B2_N")
	)
	(segment
		(start -154.6152 17.653)
		(end -150.876998 17.653)
		(width 0.12954)
		(layer "In3.Cu")
		(net "MEZZ_PRESENT_B2_N")
	)
	(segment
		(start -181.463 35.56)
		(end -182.479 34.544)
		(width 0.12954)
		(layer "In3.Cu")
		(net "MEZZ_PRESENT_B2_N")
	)
	(segment
		(start -155.4026 16.8656)
		(end -154.6152 17.653)
		(width 0.12954)
		(layer "In3.Cu")
		(net "MEZZ_PRESENT_B2_N")
	)
	(segment
		(start -370.634999 18.894999)
		(end -371.269999 18.259999)
		(width 0.127)
		(layer "F.Cu")
		(net "MEZZ_PRESENT_B1_N")
	)
	(via
		(at -371.269999 18.259999)
		(size 0.5588)
		(drill 0.254)
		(layers "F.Cu" "B.Cu")
		(net "MEZZ_PRESENT_B1_N")
	)
	(segment
		(start -375.6152 17.653)
		(end -371.876998 17.653)
		(width 0.12954)
		(layer "In3.Cu")
		(net "MEZZ_PRESENT_B1_N")
	)
	(segment
		(start -402.463 35.56)
		(end -403.479 34.544)
		(width 0.12954)
		(layer "In3.Cu")
		(net "MEZZ_PRESENT_B1_N")
	)
	(segment
		(start -403.479 24.13)
		(end -400.1516 20.8026)
		(width 0.12954)
		(layer "In3.Cu")
		(net "MEZZ_PRESENT_B1_N")
	)
	(segment
		(start -371.876998 17.653)
		(end -371.269999 18.259999)
		(width 0.12954)
		(layer "In3.Cu")
		(net "MEZZ_PRESENT_B1_N")
	)
	(segment
		(start -403.479 34.544)
		(end -403.479 24.13)
		(width 0.12954)
		(layer "In3.Cu")
		(net "MEZZ_PRESENT_B1_N")
	)
	(segment
		(start -400.1516 20.8026)
		(end -384.5306 20.8026)
		(width 0.12954)
		(layer "In3.Cu")
		(net "MEZZ_PRESENT_B1_N")
	)
	(segment
		(start -402.46 35.56)
		(end -402.463 35.56)
		(width 0.12954)
		(layer "In3.Cu")
		(net "MEZZ_PRESENT_B1_N")
	)
	(segment
		(start -380.5936 16.8656)
		(end -376.4026 16.8656)
		(width 0.12954)
		(layer "In3.Cu")
		(net "MEZZ_PRESENT_B1_N")
	)
	(segment
		(start -384.5306 20.8026)
		(end -380.5936 16.8656)
		(width 0.12954)
		(layer "In3.Cu")
		(net "MEZZ_PRESENT_B1_N")
	)
	(segment
		(start -376.4026 16.8656)
		(end -375.6152 17.653)
		(width 0.12954)
		(layer "In3.Cu")
		(net "MEZZ_PRESENT_B1_N")
	)
	(segment
		(start -152.174999 18.894999)
		(end -152.809999 18.259999)
		(width 0.127)
		(layer "F.Cu")
		(net "MEZZ_B2_SDA")
	)
	(via
		(at -152.809999 18.259999)
		(size 0.5588)
		(drill 0.254)
		(layers "F.Cu" "B.Cu")
		(net "MEZZ_B2_SDA")
	)
	(segment
		(start -176.5608 33.2608)
		(end -176.5608 23.6728)
		(width 0.12954)
		(layer "In3.Cu")
		(net "MEZZ_B2_SDA")
	)
	(segment
		(start -177.460001 34.16)
		(end -176.5608 33.2608)
		(width 0.12954)
		(layer "In3.Cu")
		(net "MEZZ_B2_SDA")
	)
	(segment
		(start -157.58446 20.13966)
		(end -157.2314 19.7866)
		(width 0.12954)
		(layer "In3.Cu")
		(net "MEZZ_B2_SDA")
	)
	(segment
		(start -157.2314 19.3294)
		(end -156.66498 18.76298)
		(width 0.12954)
		(layer "In3.Cu")
		(net "MEZZ_B2_SDA")
	)
	(segment
		(start -162.17424 22.16658)
		(end -160.14732 20.13966)
		(width 0.12954)
		(layer "In3.Cu")
		(net "MEZZ_B2_SDA")
	)
	(segment
		(start -156.66498 18.76298)
		(end -153.36298 18.76298)
		(width 0.12954)
		(layer "In3.Cu")
		(net "MEZZ_B2_SDA")
	)
	(segment
		(start -157.2314 19.7866)
		(end -157.2314 19.3294)
		(width 0.12954)
		(layer "In3.Cu")
		(net "MEZZ_B2_SDA")
	)
	(segment
		(start -176.5608 23.6728)
		(end -175.05458 22.16658)
		(width 0.12954)
		(layer "In3.Cu")
		(net "MEZZ_B2_SDA")
	)
	(segment
		(start -175.05458 22.16658)
		(end -162.17424 22.16658)
		(width 0.12954)
		(layer "In3.Cu")
		(net "MEZZ_B2_SDA")
	)
	(segment
		(start -160.14732 20.13966)
		(end -157.58446 20.13966)
		(width 0.12954)
		(layer "In3.Cu")
		(net "MEZZ_B2_SDA")
	)
	(segment
		(start -152.859999 18.259999)
		(end -152.809999 18.259999)
		(width 0.12954)
		(layer "In3.Cu")
		(net "MEZZ_B2_SDA")
	)
	(segment
		(start -153.36298 18.76298)
		(end -152.859999 18.259999)
		(width 0.12954)
		(layer "In3.Cu")
		(net "MEZZ_B2_SDA")
	)
	(segment
		(start -154.714999 18.894999)
		(end -155.349999 18.259999)
		(width 0.127)
		(layer "F.Cu")
		(net "MEZZ_B2_SCL")
	)
	(via
		(at -155.349999 18.259999)
		(size 0.5588)
		(drill 0.254)
		(layers "F.Cu" "B.Cu")
		(net "MEZZ_B2_SCL")
	)
	(segment
		(start -157.3584 18.6309)
		(end -157.3584 17.9324)
		(width 0.12954)
		(layer "In3.Cu")
		(net "MEZZ_B2_SCL")
	)
	(segment
		(start -156.083998 17.526)
		(end -155.349999 18.259999)
		(width 0.12954)
		(layer "In3.Cu")
		(net "MEZZ_B2_SCL")
	)
	(segment
		(start -178.3134 23.9776)
		(end -176.167131 21.83133)
		(width 0.12954)
		(layer "In3.Cu")
		(net "MEZZ_B2_SCL")
	)
	(segment
		(start -176.167131 21.83133)
		(end -162.959131 21.83133)
		(width 0.12954)
		(layer "In3.Cu")
		(net "MEZZ_B2_SCL")
	)
	(segment
		(start -157.63526 18.90776)
		(end -157.3584 18.6309)
		(width 0.12954)
		(layer "In3.Cu")
		(net "MEZZ_B2_SCL")
	)
	(segment
		(start -156.952 17.526)
		(end -156.083998 17.526)
		(width 0.12954)
		(layer "In3.Cu")
		(net "MEZZ_B2_SCL")
	)
	(segment
		(start -160.03556 18.90776)
		(end -157.63526 18.90776)
		(width 0.12954)
		(layer "In3.Cu")
		(net "MEZZ_B2_SCL")
	)
	(segment
		(start -178.3134 35.687)
		(end -178.3134 23.9776)
		(width 0.12954)
		(layer "In3.Cu")
		(net "MEZZ_B2_SCL")
	)
	(segment
		(start -179.459999 36.86)
		(end -179.459999 36.833599)
		(width 0.12954)
		(layer "In3.Cu")
		(net "MEZZ_B2_SCL")
	)
	(segment
		(start -157.3584 17.9324)
		(end -156.952 17.526)
		(width 0.12954)
		(layer "In3.Cu")
		(net "MEZZ_B2_SCL")
	)
	(segment
		(start -179.459999 36.833599)
		(end -178.3134 35.687)
		(width 0.12954)
		(layer "In3.Cu")
		(net "MEZZ_B2_SCL")
	)
	(segment
		(start -162.959131 21.83133)
		(end -160.03556 18.90776)
		(width 0.12954)
		(layer "In3.Cu")
		(net "MEZZ_B2_SCL")
	)
	(segment
		(start -153.444999 18.894999)
		(end -154.079999 18.259999)
		(width 0.127)
		(layer "F.Cu")
		(net "MEZZ_B2_EN")
	)
	(via
		(at -154.079999 18.259999)
		(size 0.5588)
		(drill 0.254)
		(layers "F.Cu" "B.Cu")
		(net "MEZZ_B2_EN")
	)
	(segment
		(start -154.567001 18.259999)
		(end -155.6058 17.2212)
		(width 0.12954)
		(layer "In3.Cu")
		(net "MEZZ_B2_EN")
	)
	(segment
		(start -159.238 17.2212)
		(end -163.302132 21.285332)
		(width 0.12954)
		(layer "In3.Cu")
		(net "MEZZ_B2_EN")
	)
	(segment
		(start -163.302132 21.285332)
		(end -176.713332 21.285332)
		(width 0.12954)
		(layer "In3.Cu")
		(net "MEZZ_B2_EN")
	)
	(segment
		(start -154.079999 18.259999)
		(end -154.567001 18.259999)
		(width 0.12954)
		(layer "In3.Cu")
		(net "MEZZ_B2_EN")
	)
	(segment
		(start -176.713332 21.285332)
		(end -178.5674 23.1394)
		(width 0.12954)
		(layer "In3.Cu")
		(net "MEZZ_B2_EN")
	)
	(segment
		(start -178.5674 34.567401)
		(end -179.459999 35.46)
		(width 0.12954)
		(layer "In3.Cu")
		(net "MEZZ_B2_EN")
	)
	(segment
		(start -155.6058 17.2212)
		(end -159.238 17.2212)
		(width 0.12954)
		(layer "In3.Cu")
		(net "MEZZ_B2_EN")
	)
	(segment
		(start -178.5674 23.1394)
		(end -178.5674 34.567401)
		(width 0.12954)
		(layer "In3.Cu")
		(net "MEZZ_B2_EN")
	)
	(segment
		(start -373.174999 18.894999)
		(end -373.809999 18.259999)
		(width 0.127)
		(layer "F.Cu")
		(net "MEZZ_B1_SDA")
	)
	(via
		(at -373.809999 18.259999)
		(size 0.5588)
		(drill 0.254)
		(layers "F.Cu" "B.Cu")
		(net "MEZZ_B1_SDA")
	)
	(segment
		(start -397.5608 33.2608)
		(end -397.5608 23.6728)
		(width 0.12954)
		(layer "In3.Cu")
		(net "MEZZ_B1_SDA")
	)
	(segment
		(start -374.36806 18.76806)
		(end -373.859999 18.259999)
		(width 0.12954)
		(layer "In3.Cu")
		(net "MEZZ_B1_SDA")
	)
	(segment
		(start -373.859999 18.259999)
		(end -373.809999 18.259999)
		(width 0.12954)
		(layer "In3.Cu")
		(net "MEZZ_B1_SDA")
	)
	(segment
		(start -378.58446 20.13966)
		(end -378.2314 19.7866)
		(width 0.12954)
		(layer "In3.Cu")
		(net "MEZZ_B1_SDA")
	)
	(segment
		(start -378.2314 19.3294)
		(end -377.67006 18.76806)
		(width 0.12954)
		(layer "In3.Cu")
		(net "MEZZ_B1_SDA")
	)
	(segment
		(start -398.460001 34.16)
		(end -397.5608 33.2608)
		(width 0.12954)
		(layer "In3.Cu")
		(net "MEZZ_B1_SDA")
	)
	(segment
		(start -397.5608 23.6728)
		(end -396.05458 22.16658)
		(width 0.12954)
		(layer "In3.Cu")
		(net "MEZZ_B1_SDA")
	)
	(segment
		(start -396.05458 22.16658)
		(end -383.17424 22.16658)
		(width 0.12954)
		(layer "In3.Cu")
		(net "MEZZ_B1_SDA")
	)
	(segment
		(start -381.14732 20.13966)
		(end -378.58446 20.13966)
		(width 0.12954)
		(layer "In3.Cu")
		(net "MEZZ_B1_SDA")
	)
	(segment
		(start -377.67006 18.76806)
		(end -374.36806 18.76806)
		(width 0.12954)
		(layer "In3.Cu")
		(net "MEZZ_B1_SDA")
	)
	(segment
		(start -378.2314 19.7866)
		(end -378.2314 19.3294)
		(width 0.12954)
		(layer "In3.Cu")
		(net "MEZZ_B1_SDA")
	)
	(segment
		(start -383.17424 22.16658)
		(end -381.14732 20.13966)
		(width 0.12954)
		(layer "In3.Cu")
		(net "MEZZ_B1_SDA")
	)
	(segment
		(start -375.714999 18.894999)
		(end -376.349999 18.259999)
		(width 0.127)
		(layer "F.Cu")
		(net "MEZZ_B1_SCL")
	)
	(via
		(at -376.349999 18.259999)
		(size 0.5588)
		(drill 0.254)
		(layers "F.Cu" "B.Cu")
		(net "MEZZ_B1_SCL")
	)
	(segment
		(start -400.459999 36.833599)
		(end -399.3134 35.687)
		(width 0.12954)
		(layer "In3.Cu")
		(net "MEZZ_B1_SCL")
	)
	(segment
		(start -378.3584 17.9324)
		(end -377.952 17.526)
		(width 0.12954)
		(layer "In3.Cu")
		(net "MEZZ_B1_SCL")
	)
	(segment
		(start -399.3134 23.9776)
		(end -397.16713 21.83133)
		(width 0.12954)
		(layer "In3.Cu")
		(net "MEZZ_B1_SCL")
	)
	(segment
		(start -378.63526 18.90776)
		(end -378.3584 18.6309)
		(width 0.12954)
		(layer "In3.Cu")
		(net "MEZZ_B1_SCL")
	)
	(segment
		(start -383.95913 21.83133)
		(end -381.03556 18.90776)
		(width 0.12954)
		(layer "In3.Cu")
		(net "MEZZ_B1_SCL")
	)
	(segment
		(start -399.3134 35.687)
		(end -399.3134 23.9776)
		(width 0.12954)
		(layer "In3.Cu")
		(net "MEZZ_B1_SCL")
	)
	(segment
		(start -400.459999 36.86)
		(end -400.459999 36.833599)
		(width 0.12954)
		(layer "In3.Cu")
		(net "MEZZ_B1_SCL")
	)
	(segment
		(start -377.083998 17.526)
		(end -376.349999 18.259999)
		(width 0.12954)
		(layer "In3.Cu")
		(net "MEZZ_B1_SCL")
	)
	(segment
		(start -397.16713 21.83133)
		(end -383.95913 21.83133)
		(width 0.12954)
		(layer "In3.Cu")
		(net "MEZZ_B1_SCL")
	)
	(segment
		(start -381.03556 18.90776)
		(end -378.63526 18.90776)
		(width 0.12954)
		(layer "In3.Cu")
		(net "MEZZ_B1_SCL")
	)
	(segment
		(start -378.3584 18.6309)
		(end -378.3584 17.9324)
		(width 0.12954)
		(layer "In3.Cu")
		(net "MEZZ_B1_SCL")
	)
	(segment
		(start -377.952 17.526)
		(end -377.083998 17.526)
		(width 0.12954)
		(layer "In3.Cu")
		(net "MEZZ_B1_SCL")
	)
	(segment
		(start -374.444999 18.894999)
		(end -375.079999 18.259999)
		(width 0.127)
		(layer "F.Cu")
		(net "MEZZ_B1_EN")
	)
	(via
		(at -375.079999 18.259999)
		(size 0.5588)
		(drill 0.254)
		(layers "F.Cu" "B.Cu")
		(net "MEZZ_B1_EN")
	)
	(segment
		(start -380.238 17.2212)
		(end -384.302132 21.285332)
		(width 0.12954)
		(layer "In3.Cu")
		(net "MEZZ_B1_EN")
	)
	(segment
		(start -399.5674 23.1394)
		(end -399.5674 34.567401)
		(width 0.12954)
		(layer "In3.Cu")
		(net "MEZZ_B1_EN")
	)
	(segment
		(start -399.5674 34.567401)
		(end -400.459999 35.46)
		(width 0.12954)
		(layer "In3.Cu")
		(net "MEZZ_B1_EN")
	)
	(segment
		(start -384.302132 21.285332)
		(end -397.713332 21.285332)
		(width 0.12954)
		(layer "In3.Cu")
		(net "MEZZ_B1_EN")
	)
	(segment
		(start -397.713332 21.285332)
		(end -399.5674 23.1394)
		(width 0.12954)
		(layer "In3.Cu")
		(net "MEZZ_B1_EN")
	)
	(segment
		(start -375.567001 18.259999)
		(end -376.6058 17.2212)
		(width 0.12954)
		(layer "In3.Cu")
		(net "MEZZ_B1_EN")
	)
	(segment
		(start -375.079999 18.259999)
		(end -375.567001 18.259999)
		(width 0.12954)
		(layer "In3.Cu")
		(net "MEZZ_B1_EN")
	)
	(segment
		(start -376.6058 17.2212)
		(end -380.238 17.2212)
		(width 0.12954)
		(layer "In3.Cu")
		(net "MEZZ_B1_EN")
	)
	(segment
		(start -31.0134 46.4185)
		(end -31.857 45.5749)
		(width 0.1016)
		(layer "F.Cu")
		(net "JBOD_B2_MATED_N")
	)
	(segment
		(start -31.857 45.5749)
		(end -31.857 44.8945)
		(width 0.1016)
		(layer "F.Cu")
		(net "JBOD_B2_MATED_N")
	)
	(segment
		(start -31.865131 44.874871)
		(end -32.680001 44.060001)
		(width 0.1016)
		(layer "F.Cu")
		(net "JBOD_B2_MATED_N")
	)
	(segment
		(start -24.899701 44.846001)
		(end -25.654 45.6003)
		(width 0.1016)
		(layer "F.Cu")
		(net "JBOD_B2_MATED_N")
	)
	(segment
		(start -25.654 46.0629)
		(end -26.0096 46.4185)
		(width 0.1016)
		(layer "F.Cu")
		(net "JBOD_B2_MATED_N")
	)
	(segment
		(start -19.9136 44.846001)
		(end -24.899701 44.846001)
		(width 0.1016)
		(layer "F.Cu")
		(net "JBOD_B2_MATED_N")
	)
	(segment
		(start -25.654 45.6003)
		(end -25.654 46.0629)
		(width 0.1016)
		(layer "F.Cu")
		(net "JBOD_B2_MATED_N")
	)
	(segment
		(start -26.0096 46.4185)
		(end -31.0134 46.4185)
		(width 0.1016)
		(layer "F.Cu")
		(net "JBOD_B2_MATED_N")
	)
	(segment
		(start -31.857 44.8945)
		(end -31.865131 44.874871)
		(width 0.1016)
		(layer "F.Cu")
		(net "JBOD_B2_MATED_N")
	)
	(segment
		(start -246.5578 46.4312)
		(end -251.7648 46.4312)
		(width 0.1016)
		(layer "F.Cu")
		(net "JBOD_B1_MATED_N")
	)
	(segment
		(start -244.718601 44.592001)
		(end -246.5578 46.4312)
		(width 0.1016)
		(layer "F.Cu")
		(net "JBOD_B1_MATED_N")
	)
	(segment
		(start -240.919 44.592001)
		(end -244.718601 44.592001)
		(width 0.1016)
		(layer "F.Cu")
		(net "JBOD_B1_MATED_N")
	)
	(segment
		(start -251.7648 46.4312)
		(end -252.857 45.339)
		(width 0.1016)
		(layer "F.Cu")
		(net "JBOD_B1_MATED_N")
	)
	(segment
		(start -252.857 44.883001)
		(end -253.680001 44.060001)
		(width 0.1016)
		(layer "F.Cu")
		(net "JBOD_B1_MATED_N")
	)
	(segment
		(start -252.857 45.339)
		(end -252.857 44.883001)
		(width 0.1016)
		(layer "F.Cu")
		(net "JBOD_B1_MATED_N")
	)
	(segment
		(start -150.904999 26.514999)
		(end -151.539999 25.879999)
		(width 0.3048)
		(layer "F.Cu")
		(net "GND")
	)
	(segment
		(start -201.607001 35.110001)
		(end -200.834056 35.882946)
		(width 0.381)
		(layer "F.Cu")
		(net "GND")
	)
	(segment
		(start -149.634999 34.134999)
		(end -150.269999 33.499999)
		(width 0.3048)
		(layer "F.Cu")
		(net "GND")
	)
	(segment
		(start -150.904999 27.784999)
		(end -151.539999 27.149999)
		(width 0.3048)
		(layer "F.Cu")
		(net "GND")
	)
	(segment
		(start -152.174999 40.484999)
		(end -152.809999 39.849999)
		(width 0.3048)
		(layer "F.Cu")
		(net "GND")
	)
	(segment
		(start -373.174999 35.404999)
		(end -373.809999 34.769999)
		(width 0.3048)
		(layer "F.Cu")
		(net "GND")
	)
	(segment
		(start -308.85 43.840001)
		(end -308.85 45.211601)
		(width 0.3048)
		(layer "F.Cu")
		(net "GND")
	)
	(segment
		(start -376.984999 26.514999)
		(end -377.619999 25.879999)
		(width 0.3048)
		(layer "F.Cu")
		(net "GND")
	)
	(segment
		(start -314.049999 39.941581)
		(end -314.050081 39.9669)
		(width 0.3048)
		(layer "F.Cu")
		(net "GND")
	)
	(segment
		(start -370.634999 29.054999)
		(end -371.269999 28.419999)
		(width 0.3048)
		(layer "F.Cu")
		(net "GND")
	)
	(segment
		(start -279.35 26.663858)
		(end -279.148601 26.462459)
		(width 0.3048)
		(layer "F.Cu")
		(net "GND")
	)
	(segment
		(start -283.750001 37.61486)
		(end -283.750001 36.159999)
		(width 0.3048)
		(layer "F.Cu")
		(net "GND")
	)
	(segment
		(start -371.904999 37.944999)
		(end -372.539999 37.309999)
		(width 0.3048)
		(layer "F.Cu")
		(net "GND")
	)
	(segment
		(start -374.444999 31.594999)
		(end -375.079999 30.959999)
		(width 0.3048)
		(layer "F.Cu")
		(net "GND")
	)
	(segment
		(start -154.714999 29.054999)
		(end -155.349999 28.419999)
		(width 0.3048)
		(layer "F.Cu")
		(net "GND")
	)
	(segment
		(start -371.904999 22.704999)
		(end -372.539999 22.069999)
		(width 0.3048)
		(layer "F.Cu")
		(net "GND")
	)
	(segment
		(start -155.984999 27.784999)
		(end -156.619999 27.149999)
		(width 0.3048)
		(layer "F.Cu")
		(net "GND")
	)
	(segment
		(start -378.254999 20.164999)
		(end -378.889999 19.529999)
		(width 0.3048)
		(layer "F.Cu")
		(net "GND")
	)
	(segment
		(start -158.542987 27.784999)
		(end -158.5654 27.807412)
		(width 0.3048)
		(layer "F.Cu")
		(net "GND")
	)
	(segment
		(start -375.714999 35.404999)
		(end -376.349999 34.769999)
		(width 0.3048)
		(layer "F.Cu")
		(net "GND")
	)
	(segment
		(start -371.904999 31.594999)
		(end -372.539999 30.959999)
		(width 0.3048)
		(layer "F.Cu")
		(net "GND")
	)
	(segment
		(start -87.85 43.840001)
		(end -87.85 45.211601)
		(width 0.3048)
		(layer "F.Cu")
		(net "GND")
	)
	(segment
		(start -90.25 43.840001)
		(end -90.25 45.211601)
		(width 0.3048)
		(layer "F.Cu")
		(net "GND")
	)
	(segment
		(start -296.795802 5.524602)
		(end -297.561 5.524602)
		(width 0.3048)
		(layer "F.Cu")
		(net "GND")
	)
	(segment
		(start -112.88776 20.50034)
		(end -112.890198 20.497902)
		(width 0.3048)
		(layer "F.Cu")
		(net "GND")
	)
	(segment
		(start -158.524999 27.784999)
		(end -158.542987 27.784999)
		(width 0.3048)
		(layer "F.Cu")
		(net "GND")
	)
	(segment
		(start -158.524999 36.597801)
		(end -159.2326 35.8902)
		(width 0.3048)
		(layer "F.Cu")
		(net "GND")
	)
	(segment
		(start -375.714999 23.974999)
		(end -376.349999 23.339999)
		(width 0.3048)
		(layer "F.Cu")
		(net "GND")
	)
	(segment
		(start -336.491682 20.840802)
		(end -335.846001 20.840802)
		(width 0.3048)
		(layer "F.Cu")
		(net "GND")
	)
	(segment
		(start -158.5654 27.807412)
		(end -159.011508 27.807412)
		(width 0.3048)
		(layer "F.Cu")
		(net "GND")
	)
	(segment
		(start -378.254999 23.974999)
		(end -378.889999 23.339999)
		(width 0.3048)
		(layer "F.Cu")
		(net "GND")
	)
	(segment
		(start -112.26292 7.493)
		(end -111.495601 7.493)
		(width 0.3048)
		(layer "F.Cu")
		(net "GND")
	)
	(segment
		(start -155.984999 22.704999)
		(end -156.619999 22.069999)
		(width 0.3048)
		(layer "F.Cu")
		(net "GND")
	)
	(segment
		(start -157.254999 34.134999)
		(end -157.889999 33.499999)
		(width 0.3048)
		(layer "F.Cu")
		(net "GND")
	)
	(segment
		(start -159.033921 27.784999)
		(end -159.248899 27.784999)
		(width 0.3048)
		(layer "F.Cu")
		(net "GND")
	)
	(segment
		(start -278.950001 36.159999)
		(end -278.950001 37.61486)
		(width 0.3048)
		(layer "F.Cu")
		(net "GND")
	)
	(segment
		(start -374.444999 22.704999)
		(end -375.079999 22.069999)
		(width 0.3048)
		(layer "F.Cu")
		(net "GND")
	)
	(segment
		(start -374.444999 36.674999)
		(end -375.079999 36.039999)
		(width 0.3048)
		(layer "F.Cu")
		(net "GND")
	)
	(segment
		(start -353.3902 33.8328)
		(end -352.3742 33.8328)
		(width 0.3048)
		(layer "F.Cu")
		(net "GND")
	)
	(segment
		(start -311.649999 41.340001)
		(end -311.649999 39.941581)
		(width 0.3048)
		(layer "F.Cu")
		(net "GND")
	)
	(segment
		(start -205.93825 26.30485)
		(end -204.940799 25.307399)
		(width 0.381)
		(layer "F.Cu")
		(net "GND")
	)
	(segment
		(start -88.25008 39.9669)
		(end -88.249999 39.941581)
		(width 0.3048)
		(layer "F.Cu")
		(net "GND")
	)
	(segment
		(start -374.444999 32.864999)
		(end -375.079999 32.229999)
		(width 0.3048)
		(layer "F.Cu")
		(net "GND")
	)
	(segment
		(start -286.550001 27.96)
		(end -286.550001 26.62714)
		(width 0.3048)
		(layer "F.Cu")
		(net "GND")
	)
	(segment
		(start -93.049999 39.941581)
		(end -93.050081 39.9669)
		(width 0.3048)
		(layer "F.Cu")
		(net "GND")
	)
	(segment
		(start -281.350001 34.72942)
		(end -281.350001 36.159999)
		(width 0.3048)
		(layer "F.Cu")
		(net "GND")
	)
	(segment
		(start -158.524999 37.944999)
		(end -158.823599 37.944999)
		(width 0.3048)
		(layer "F.Cu")
		(net "GND")
	)
	(segment
		(start -102.250001 43.840001)
		(end -102.250001 45.211601)
		(width 0.3048)
		(layer "F.Cu")
		(net "GND")
	)
	(segment
		(start -199.4408 25.307399)
		(end -198.44335 26.30485)
		(width 0.381)
		(layer "F.Cu")
		(net "GND")
	)
	(segment
		(start -285.020601 44.488202)
		(end -285.719101 44.488202)
		(width 0.3048)
		(layer "F.Cu")
		(net "GND")
	)
	(segment
		(start -379.524999 41.754999)
		(end -380.248899 41.754999)
		(width 0.3048)
		(layer "F.Cu")
		(net "GND")
	)
	(segment
		(start -150.904999 41.754999)
		(end -151.539999 41.119999)
		(width 0.3048)
		(layer "F.Cu")
		(net "GND")
	)
	(segment
		(start -301.621802 4.635602)
		(end -302.514 4.635602)
		(width 0.3048)
		(layer "F.Cu")
		(net "GND")
	)
	(segment
		(start -318.850081 39.9669)
		(end -318.85 39.941581)
		(width 0.3048)
		(layer "F.Cu")
		(net "GND")
	)
	(segment
		(start -115.423 5.577601)
		(end -115.423 6.847601)
		(width 0.3048)
		(layer "F.Cu")
		(net "GND")
	)
	(segment
		(start -152.174999 25.244999)
		(end -152.809999 24.609999)
		(width 0.3048)
		(layer "F.Cu")
		(net "GND")
	)
	(segment
		(start -60.350001 37.61486)
		(end -60.350001 36.159999)
		(width 0.3048)
		(layer "F.Cu")
		(net "GND")
	)
	(segment
		(start -336.423 5.577601)
		(end -336.423 6.847601)
		(width 0.3048)
		(layer "F.Cu")
		(net "GND")
	)
	(segment
		(start -370.634999 39.214999)
		(end -371.269999 38.579999)
		(width 0.3048)
		(layer "F.Cu")
		(net "GND")
	)
	(segment
		(start -155.984999 43.024999)
		(end -156.619999 42.389999)
		(width 0.3048)
		(layer "F.Cu")
		(net "GND")
	)
	(segment
		(start -154.714999 25.244999)
		(end -155.349999 24.609999)
		(width 0.3048)
		(layer "F.Cu")
		(net "GND")
	)
	(segment
		(start -376.984999 22.704999)
		(end -377.619999 22.069999)
		(width 0.3048)
		(layer "F.Cu")
		(net "GND")
	)
	(segment
		(start -153.444999 43.024999)
		(end -154.079999 42.389999)
		(width 0.3048)
		(layer "F.Cu")
		(net "GND")
	)
	(segment
		(start -200.43825 24.309949)
		(end -199.4408 25.307399)
		(width 0.381)
		(layer "F.Cu")
		(net "GND")
	)
	(segment
		(start -205.93825 24.309949)
		(end -204.940799 25.307399)
		(width 0.381)
		(layer "F.Cu")
		(net "GND")
	)
	(segment
		(start -153.444999 36.674999)
		(end -154.079999 36.039999)
		(width 0.3048)
		(layer "F.Cu")
		(net "GND")
	)
	(segment
		(start -102.65 41.340001)
		(end -102.65 39.941581)
		(width 0.3048)
		(layer "F.Cu")
		(net "GND")
	)
	(segment
		(start -374.444999 41.754999)
		(end -375.079999 41.119999)
		(width 0.3048)
		(layer "F.Cu")
		(net "GND")
	)
	(segment
		(start -380.011508 27.807412)
		(end -380.033921 27.784999)
		(width 0.3048)
		(layer "F.Cu")
		(net "GND")
	)
	(segment
		(start -158.524999 22.704999)
		(end -159.248899 22.704999)
		(width 0.3048)
		(layer "F.Cu")
		(net "GND")
	)
	(segment
		(start -157.254999 35.404999)
		(end -157.889999 34.769999)
		(width 0.3048)
		(layer "F.Cu")
		(net "GND")
	)
	(segment
		(start -379.524999 31.594999)
		(end -380.248899 31.594999)
		(width 0.3048)
		(layer "F.Cu")
		(net "GND")
	)
	(segment
		(start -90.649999 41.340001)
		(end -90.649999 39.941581)
		(width 0.3048)
		(layer "F.Cu")
		(net "GND")
	)
	(segment
		(start -157.889999 38.579999)
		(end -157.889999 38.569613)
		(width 0.3048)
		(layer "F.Cu")
		(net "GND")
	)
	(segment
		(start -373.174999 23.974999)
		(end -373.809999 23.339999)
		(width 0.3048)
		(layer "F.Cu")
		(net "GND")
	)
	(segment
		(start -149.634999 40.484999)
		(end -150.269999 39.849999)
		(width 0.3048)
		(layer "F.Cu")
		(net "GND")
	)
	(segment
		(start -149.634999 35.404999)
		(end -150.269999 34.769999)
		(width 0.3048)
		(layer "F.Cu")
		(net "GND")
	)
	(segment
		(start -153.444999 31.594999)
		(end -154.079999 30.959999)
		(width 0.3048)
		(layer "F.Cu")
		(net "GND")
	)
	(segment
		(start -65.150002 34.72942)
		(end -65.150002 36.159999)
		(width 0.3048)
		(layer "F.Cu")
		(net "GND")
	)
	(segment
		(start -123.551 5.374401)
		(end -123.551 6.644401)
		(width 0.3048)
		(layer "F.Cu")
		(net "GND")
	)
	(segment
		(start -58.35 26.663858)
		(end -58.148601 26.462459)
		(width 0.3048)
		(layer "F.Cu")
		(net "GND")
	)
	(segment
		(start -158.524999 41.754999)
		(end -159.248899 41.754999)
		(width 0.3048)
		(layer "F.Cu")
		(net "GND")
	)
	(segment
		(start -371.904999 32.864999)
		(end -372.539999 32.229999)
		(width 0.3048)
		(layer "F.Cu")
		(net "GND")
	)
	(segment
		(start -370.634999 34.134999)
		(end -371.269999 33.499999)
		(width 0.3048)
		(layer "F.Cu")
		(net "GND")
	)
	(segment
		(start -155.984999 32.864999)
		(end -156.619999 32.229999)
		(width 0.3048)
		(layer "F.Cu")
		(net "GND")
	)
	(segment
		(start -378.254999 30.324999)
		(end -378.889999 29.689999)
		(width 0.3048)
		(layer "F.Cu")
		(net "GND")
	)
	(segment
		(start -100.25 39.941581)
		(end -100.250081 39.9669)
		(width 0.3048)
		(layer "F.Cu")
		(net "GND")
	)
	(segment
		(start -375.714999 29.054999)
		(end -376.349999 28.419999)
		(width 0.3048)
		(layer "F.Cu")
		(net "GND")
	)
	(segment
		(start -19.045001 43.545999)
		(end -19.9136 43.545999)
		(width 0.3048)
		(layer "F.Cu")
		(net "GND")
	)
	(segment
		(start -376.984999 37.944999)
		(end -377.619999 37.309999)
		(width 0.3048)
		(layer "F.Cu")
		(net "GND")
	)
	(segment
		(start -376.984999 36.674999)
		(end -377.619999 36.039999)
		(width 0.3048)
		(layer "F.Cu")
		(net "GND")
	)
	(segment
		(start -154.714999 30.324999)
		(end -155.349999 29.689999)
		(width 0.3048)
		(layer "F.Cu")
		(net "GND")
	)
	(segment
		(start -159.509399 32.864999)
		(end -158.524999 32.864999)
		(width 0.3048)
		(layer "F.Cu")
		(net "GND")
	)
	(segment
		(start -313.65 43.840001)
		(end -313.65 45.211601)
		(width 0.3048)
		(layer "F.Cu")
		(net "GND")
	)
	(segment
		(start -65.550001 26.62714)
		(end -65.550001 27.96)
		(width 0.3048)
		(layer "F.Cu")
		(net "GND")
	)
	(segment
		(start -379.524999 26.514999)
		(end -380.248899 26.514999)
		(width 0.3048)
		(layer "F.Cu")
		(net "GND")
	)
	(segment
		(start -314.049999 41.340001)
		(end -314.049999 39.941581)
		(width 0.3048)
		(layer "F.Cu")
		(net "GND")
	)
	(segment
		(start -157.254999 39.214999)
		(end -157.889999 38.579999)
		(width 0.3048)
		(layer "F.Cu")
		(net "GND")
	)
	(segment
		(start -296.795802 2.730602)
		(end -297.688 2.730602)
		(width 0.3048)
		(layer "F.Cu")
		(net "GND")
	)
	(segment
		(start -158.823599 37.944999)
		(end -159.3088 38.4302)
		(width 0.3048)
		(layer "F.Cu")
		(net "GND")
	)
	(segment
		(start -57.950001 36.159999)
		(end -57.950001 34.72942)
		(width 0.3048)
		(layer "F.Cu")
		(net "GND")
	)
	(segment
		(start -373.174999 40.484999)
		(end -373.809999 39.849999)
		(width 0.3048)
		(layer "F.Cu")
		(net "GND")
	)
	(segment
		(start -97.85 39.941581)
		(end -97.85 41.340001)
		(width 0.3048)
		(layer "F.Cu")
		(net "GND")
	)
	(segment
		(start -378.254999 29.054999)
		(end -378.889999 28.419999)
		(width 0.3048)
		(layer "F.Cu")
		(net "GND")
	)
	(segment
		(start -373.174999 34.134999)
		(end -373.809999 33.499999)
		(width 0.3048)
		(layer "F.Cu")
		(net "GND")
	)
	(segment
		(start -318.450001 43.840001)
		(end -318.450001 45.211601)
		(width 0.3048)
		(layer "F.Cu")
		(net "GND")
	)
	(segment
		(start -158.524999 43.024999)
		(end -159.248899 43.024999)
		(width 0.3048)
		(layer "F.Cu")
		(net "GND")
	)
	(segment
		(start -344.551 6.4516)
		(end -344.6018 6.5024)
		(width 0.3048)
		(layer "F.Cu")
		(net "GND")
	)
	(segment
		(start -157.254999 23.974999)
		(end -157.889999 23.339999)
		(width 0.3048)
		(layer "F.Cu")
		(net "GND")
	)
	(segment
		(start -154.714999 40.484999)
		(end -155.349999 39.849999)
		(width 0.3048)
		(layer "F.Cu")
		(net "GND")
	)
	(segment
		(start -370.634999 35.404999)
		(end -371.269999 34.769999)
		(width 0.3048)
		(layer "F.Cu")
		(net "GND")
	)
	(segment
		(start -64.020601 44.488202)
		(end -64.719101 44.488202)
		(width 0.3048)
		(layer "F.Cu")
		(net "GND")
	)
	(segment
		(start -311.25 43.840001)
		(end -311.25 45.211601)
		(width 0.3048)
		(layer "F.Cu")
		(net "GND")
	)
	(segment
		(start -204.940799 25.307399)
		(end -203.943349 26.30485)
		(width 0.381)
		(layer "F.Cu")
		(net "GND")
	)
	(segment
		(start -376.984999 32.864999)
		(end -377.619999 32.229999)
		(width 0.3048)
		(layer "F.Cu")
		(net "GND")
	)
	(segment
		(start -286.550001 26.62714)
		(end -286.717801 26.45934)
		(width 0.3048)
		(layer "F.Cu")
		(net "GND")
	)
	(segment
		(start -152.174999 30.324999)
		(end -152.809999 29.689999)
		(width 0.3048)
		(layer "F.Cu")
		(net "GND")
	)
	(segment
		(start -154.714999 35.404999)
		(end -155.349999 34.769999)
		(width 0.3048)
		(layer "F.Cu")
		(net "GND")
	)
	(segment
		(start -157.889999 38.569613)
		(end -157.879613 38.569613)
		(width 0.3048)
		(layer "F.Cu")
		(net "GND")
	)
	(segment
		(start -376.984999 41.754999)
		(end -377.619999 41.119999)
		(width 0.3048)
		(layer "F.Cu")
		(net "GND")
	)
	(segment
		(start -57.4348 44.488202)
		(end -58.153201 44.488202)
		(width 0.3048)
		(layer "F.Cu")
		(net "GND")
	)
	(segment
		(start -302.4124 8.8646)
		(end -302.641 8.636)
		(width 0.3048)
		(layer "F.Cu")
		(net "GND")
	)
	(segment
		(start -374.444999 27.784999)
		(end -375.079999 27.149999)
		(width 0.3048)
		(layer "F.Cu")
		(net "GND")
	)
	(segment
		(start -149.634999 29.054999)
		(end -150.269999 28.419999)
		(width 0.3048)
		(layer "F.Cu")
		(net "GND")
	)
	(segment
		(start -323.250001 43.840001)
		(end -323.250001 45.211601)
		(width 0.3048)
		(layer "F.Cu")
		(net "GND")
	)
	(segment
		(start -149.634999 39.214999)
		(end -150.269999 38.579999)
		(width 0.3048)
		(layer "F.Cu")
		(net "GND")
	)
	(segment
		(start -376.984999 20.164999)
		(end -377.619999 19.529999)
		(width 0.3048)
		(layer "F.Cu")
		(net "GND")
	)
	(segment
		(start -379.542987 27.784999)
		(end -379.5654 27.807412)
		(width 0.3048)
		(layer "F.Cu")
		(net "GND")
	)
	(segment
		(start -202.379946 35.882946)
		(end -201.607001 35.110001)
		(width 0.381)
		(layer "F.Cu")
		(net "GND")
	)
	(segment
		(start -373.174999 29.054999)
		(end -373.809999 28.419999)
		(width 0.3048)
		(layer "F.Cu")
		(net "GND")
	)
	(segment
		(start -149.634999 23.974999)
		(end -150.269999 23.339999)
		(width 0.3048)
		(layer "F.Cu")
		(net "GND")
	)
	(segment
		(start -281.350001 36.159999)
		(end -281.350001 37.61486)
		(width 0.3048)
		(layer "F.Cu")
		(net "GND")
	)
	(segment
		(start -371.904999 41.754999)
		(end -372.539999 41.119999)
		(width 0.3048)
		(layer "F.Cu")
		(net "GND")
	)
	(segment
		(start -300.339999 10.287)
		(end -299.466 10.287)
		(width 0.3048)
		(layer "F.Cu")
		(net "GND")
	)
	(segment
		(start -152.174999 29.054999)
		(end -152.809999 28.419999)
		(width 0.3048)
		(layer "F.Cu")
		(net "GND")
	)
	(segment
		(start -149.634999 30.324999)
		(end -150.269999 29.689999)
		(width 0.3048)
		(layer "F.Cu")
		(net "GND")
	)
	(segment
		(start -92.65 43.840001)
		(end -92.65 45.211601)
		(width 0.3048)
		(layer "F.Cu")
		(net "GND")
	)
	(segment
		(start -374.444999 26.514999)
		(end -375.079999 25.879999)
		(width 0.3048)
		(layer "F.Cu")
		(net "GND")
	)
	(segment
		(start -378.254999 40.484999)
		(end -378.889999 39.849999)
		(width 0.3048)
		(layer "F.Cu")
		(net "GND")
	)
	(segment
		(start -152.174999 39.214999)
		(end -152.809999 38.579999)
		(width 0.3048)
		(layer "F.Cu")
		(net "GND")
	)
	(segment
		(start -58.35 27.96)
		(end -58.35 26.663858)
		(width 0.3048)
		(layer "F.Cu")
		(net "GND")
	)
	(segment
		(start -376.984999 27.784999)
		(end -377.619999 27.149999)
		(width 0.3048)
		(layer "F.Cu")
		(net "GND")
	)
	(segment
		(start -150.904999 32.864999)
		(end -151.539999 32.229999)
		(width 0.3048)
		(layer "F.Cu")
		(net "GND")
	)
	(segment
		(start -65.150002 36.159999)
		(end -65.150002 37.58946)
		(width 0.3048)
		(layer "F.Cu")
		(net "GND")
	)
	(segment
		(start -379.524999 36.674999)
		(end -380.248899 36.674999)
		(width 0.3048)
		(layer "F.Cu")
		(net "GND")
	)
	(segment
		(start -375.714999 25.244999)
		(end -376.349999 24.609999)
		(width 0.3048)
		(layer "F.Cu")
		(net "GND")
	)
	(segment
		(start -278.4348 44.488202)
		(end -279.153201 44.488202)
		(width 0.3048)
		(layer "F.Cu")
		(net "GND")
	)
	(segment
		(start -153.444999 27.784999)
		(end -154.079999 27.149999)
		(width 0.3048)
		(layer "F.Cu")
		(net "GND")
	)
	(segment
		(start -150.904999 31.594999)
		(end -151.539999 30.959999)
		(width 0.3048)
		(layer "F.Cu")
		(net "GND")
	)
	(segment
		(start -200.43825 26.30485)
		(end -199.4408 25.307399)
		(width 0.381)
		(layer "F.Cu")
		(net "GND")
	)
	(segment
		(start -102.65 39.941581)
		(end -102.650082 39.9669)
		(width 0.3048)
		(layer "F.Cu")
		(net "GND")
	)
	(segment
		(start -373.174999 30.324999)
		(end -373.809999 29.689999)
		(width 0.3048)
		(layer "F.Cu")
		(net "GND")
	)
	(segment
		(start -374.444999 21.434999)
		(end -375.079999 20.799999)
		(width 0.3048)
		(layer "F.Cu")
		(net "GND")
	)
	(segment
		(start -321.25 41.340001)
		(end -321.25 39.941581)
		(width 0.3048)
		(layer "F.Cu")
		(net "GND")
	)
	(segment
		(start -371.904999 36.674999)
		(end -372.539999 36.039999)
		(width 0.3048)
		(layer "F.Cu")
		(net "GND")
	)
	(segment
		(start -163.510199 31.841201)
		(end -163.4998 31.8516)
		(width 0.3048)
		(layer "F.Cu")
		(net "GND")
	)
	(segment
		(start -158.524999 36.674999)
		(end -158.524999 36.597801)
		(width 0.3048)
		(layer "F.Cu")
		(net "GND")
	)
	(segment
		(start -295.513999 9.779)
		(end -294.64 9.779)
		(width 0.3048)
		(layer "F.Cu")
		(net "GND")
	)
	(segment
		(start -199.4408 25.307399)
		(end -198.44335 24.309949)
		(width 0.381)
		(layer "F.Cu")
		(net "GND")
	)
	(segment
		(start -157.254999 25.244999)
		(end -157.889999 24.609999)
		(width 0.3048)
		(layer "F.Cu")
		(net "GND")
	)
	(segment
		(start -158.524999 31.594999)
		(end -157.889999 30.959999)
		(width 0.3048)
		(layer "F.Cu")
		(net "GND")
	)
	(segment
		(start -371.904999 43.024999)
		(end -372.539999 42.389999)
		(width 0.3048)
		(layer "F.Cu")
		(net "GND")
	)
	(segment
		(start -370.634999 40.484999)
		(end -371.269999 39.849999)
		(width 0.3048)
		(layer "F.Cu")
		(net "GND")
	)
	(segment
		(start -373.174999 25.244999)
		(end -373.809999 24.609999)
		(width 0.3048)
		(layer "F.Cu")
		(net "GND")
	)
	(segment
		(start -332.8924 11.85926)
		(end -332.88986 11.8618)
		(width 0.3048)
		(layer "F.Cu")
		(net "GND")
	)
	(segment
		(start -374.444999 37.944999)
		(end -375.079999 37.309999)
		(width 0.3048)
		(layer "F.Cu")
		(net "GND")
	)
	(segment
		(start -376.984999 21.434999)
		(end -377.619999 20.799999)
		(width 0.3048)
		(layer "F.Cu")
		(net "GND")
	)
	(segment
		(start -370.634999 25.244999)
		(end -371.269999 24.609999)
		(width 0.3048)
		(layer "F.Cu")
		(net "GND")
	)
	(segment
		(start -100.25 41.340001)
		(end -100.25 39.941581)
		(width 0.3048)
		(layer "F.Cu")
		(net "GND")
	)
	(segment
		(start -155.984999 31.594999)
		(end -156.619999 30.959999)
		(width 0.3048)
		(layer "F.Cu")
		(net "GND")
	)
	(segment
		(start -115.221601 20.815402)
		(end -115.867282 20.815402)
		(width 0.3048)
		(layer "F.Cu")
		(net "GND")
	)
	(segment
		(start -155.984999 41.754999)
		(end -156.619999 41.119999)
		(width 0.3048)
		(layer "F.Cu")
		(net "GND")
	)
	(segment
		(start -378.254999 35.404999)
		(end -378.889999 34.769999)
		(width 0.3048)
		(layer "F.Cu")
		(net "GND")
	)
	(segment
		(start -58.153201 43.345202)
		(end -57.454701 43.345202)
		(width 0.3048)
		(layer "F.Cu")
		(net "GND")
	)
	(segment
		(start -376.984999 31.594999)
		(end -377.619999 30.959999)
		(width 0.3048)
		(layer "F.Cu")
		(net "GND")
	)
	(segment
		(start -279.35 27.96)
		(end -279.35 26.663858)
		(width 0.3048)
		(layer "F.Cu")
		(net "GND")
	)
	(segment
		(start -150.904999 36.674999)
		(end -151.539999 36.039999)
		(width 0.3048)
		(layer "F.Cu")
		(net "GND")
	)
	(segment
		(start -375.714999 39.214999)
		(end -376.349999 38.579999)
		(width 0.3048)
		(layer "F.Cu")
		(net "GND")
	)
	(segment
		(start -320.850001 43.840001)
		(end -320.850001 45.211601)
		(width 0.3048)
		(layer "F.Cu")
		(net "GND")
	)
	(segment
		(start -112.890198 20.497902)
		(end -113.824601 20.497902)
		(width 0.3048)
		(layer "F.Cu")
		(net "GND")
	)
	(segment
		(start -323.65 41.340001)
		(end -323.65 39.941581)
		(width 0.3048)
		(layer "F.Cu")
		(net "GND")
	)
	(segment
		(start -286.150002 34.72942)
		(end -286.150002 36.159999)
		(width 0.3048)
		(layer "F.Cu")
		(net "GND")
	)
	(segment
		(start -152.174999 23.974999)
		(end -152.809999 23.339999)
		(width 0.3048)
		(layer "F.Cu")
		(net "GND")
	)
	(segment
		(start -286.150002 36.159999)
		(end -286.150002 37.58946)
		(width 0.3048)
		(layer "F.Cu")
		(net "GND")
	)
	(segment
		(start -62.750002 36.159999)
		(end -62.750002 37.61486)
		(width 0.3048)
		(layer "F.Cu")
		(net "GND")
	)
	(segment
		(start -154.714999 23.974999)
		(end -155.349999 23.339999)
		(width 0.3048)
		(layer "F.Cu")
		(net "GND")
	)
	(segment
		(start -385.826 31.841201)
		(end -387.187201 31.841201)
		(width 0.3048)
		(layer "F.Cu")
		(net "GND")
	)
	(segment
		(start -379.524999 43.024999)
		(end -380.248899 43.024999)
		(width 0.3048)
		(layer "F.Cu")
		(net "GND")
	)
	(segment
		(start -165.0238 31.841201)
		(end -163.510199 31.841201)
		(width 0.3048)
		(layer "F.Cu")
		(net "GND")
	)
	(segment
		(start -88.249999 39.941581)
		(end -88.249999 41.340001)
		(width 0.3048)
		(layer "F.Cu")
		(net "GND")
	)
	(segment
		(start -334.449001 20.523302)
		(end -333.514598 20.523302)
		(width 0.3048)
		(layer "F.Cu")
		(net "GND")
	)
	(segment
		(start -157.254999 40.484999)
		(end -157.889999 39.849999)
		(width 0.3048)
		(layer "F.Cu")
		(net "GND")
	)
	(segment
		(start -378.254999 34.134999)
		(end -378.889999 33.499999)
		(width 0.3048)
		(layer "F.Cu")
		(net "GND")
	)
	(segment
		(start -150.904999 37.944999)
		(end -151.539999 37.309999)
		(width 0.3048)
		(layer "F.Cu")
		(net "GND")
	)
	(segment
		(start -333.514598 20.523302)
		(end -333.51216 20.52574)
		(width 0.3048)
		(layer "F.Cu")
		(net "GND")
	)
	(segment
		(start -149.634999 25.244999)
		(end -150.269999 24.609999)
		(width 0.3048)
		(layer "F.Cu")
		(net "GND")
	)
	(segment
		(start -115.867282 20.815402)
		(end -115.88496 20.83308)
		(width 0.3048)
		(layer "F.Cu")
		(net "GND")
	)
	(segment
		(start -379.524999 37.944999)
		(end -380.248899 37.944999)
		(width 0.3048)
		(layer "F.Cu")
		(net "GND")
	)
	(segment
		(start -155.984999 36.674999)
		(end -156.619999 36.039999)
		(width 0.3048)
		(layer "F.Cu")
		(net "GND")
	)
	(segment
		(start -332.88986 11.8618)
		(end -332.120001 11.8618)
		(width 0.3048)
		(layer "F.Cu")
		(net "GND")
	)
	(segment
		(start -57.950001 37.61486)
		(end -57.950001 36.159999)
		(width 0.3048)
		(layer "F.Cu")
		(net "GND")
	)
	(segment
		(start -323.65 39.941581)
		(end -323.650082 39.9669)
		(width 0.3048)
		(layer "F.Cu")
		(net "GND")
	)
	(segment
		(start -279.153201 43.345202)
		(end -278.454701 43.345202)
		(width 0.3048)
		(layer "F.Cu")
		(net "GND")
	)
	(segment
		(start -375.714999 40.484999)
		(end -376.349999 39.849999)
		(width 0.3048)
		(layer "F.Cu")
		(net "GND")
	)
	(segment
		(start -309.25008 39.9669)
		(end -309.249999 39.941581)
		(width 0.3048)
		(layer "F.Cu")
		(net "GND")
	)
	(segment
		(start -379.524999 22.704999)
		(end -380.248899 22.704999)
		(width 0.3048)
		(layer "F.Cu")
		(net "GND")
	)
	(segment
		(start -155.984999 37.944999)
		(end -156.619999 37.309999)
		(width 0.3048)
		(layer "F.Cu")
		(net "GND")
	)
	(segment
		(start -373.174999 39.214999)
		(end -373.809999 38.579999)
		(width 0.3048)
		(layer "F.Cu")
		(net "GND")
	)
	(segment
		(start -204.940799 25.307399)
		(end -203.943349 24.309949)
		(width 0.381)
		(layer "F.Cu")
		(net "GND")
	)
	(segment
		(start -152.174999 35.404999)
		(end -152.809999 34.769999)
		(width 0.3048)
		(layer "F.Cu")
		(net "GND")
	)
	(segment
		(start -153.444999 22.704999)
		(end -154.079999 22.069999)
		(width 0.3048)
		(layer "F.Cu")
		(net "GND")
	)
	(segment
		(start -370.634999 30.324999)
		(end -371.269999 29.689999)
		(width 0.3048)
		(layer "F.Cu")
		(net "GND")
	)
	(segment
		(start -378.889999 38.579999)
		(end -378.889999 38.569613)
		(width 0.3048)
		(layer "F.Cu")
		(net "GND")
	)
	(segment
		(start -155.984999 20.164999)
		(end -156.619999 19.529999)
		(width 0.3048)
		(layer "F.Cu")
		(net "GND")
	)
	(segment
		(start -153.444999 32.864999)
		(end -154.079999 32.229999)
		(width 0.3048)
		(layer "F.Cu")
		(net "GND")
	)
	(segment
		(start -155.984999 21.434999)
		(end -156.619999 20.799999)
		(width 0.3048)
		(layer "F.Cu")
		(net "GND")
	)
	(segment
		(start -153.444999 26.514999)
		(end -154.079999 25.879999)
		(width 0.3048)
		(layer "F.Cu")
		(net "GND")
	)
	(segment
		(start -93.049999 41.340001)
		(end -93.049999 39.941581)
		(width 0.3048)
		(layer "F.Cu")
		(net "GND")
	)
	(segment
		(start -301.589201 8.8646)
		(end -302.4124 8.8646)
		(width 0.3048)
		(layer "F.Cu")
		(net "GND")
	)
	(segment
		(start -19.03 43.561)
		(end -19.045001 43.545999)
		(width 0.3048)
		(layer "F.Cu")
		(net "GND")
	)
	(segment
		(start -97.850081 39.9669)
		(end -97.85 39.941581)
		(width 0.3048)
		(layer "F.Cu")
		(net "GND")
	)
	(segment
		(start -155.984999 26.514999)
		(end -156.619999 25.879999)
		(width 0.3048)
		(layer "F.Cu")
		(net "GND")
	)
	(segment
		(start -159.011508 27.807412)
		(end -159.033921 27.784999)
		(width 0.3048)
		(layer "F.Cu")
		(net "GND")
	)
	(segment
		(start -159.6898 33.0454)
		(end -159.509399 32.864999)
		(width 0.3048)
		(layer "F.Cu")
		(net "GND")
	)
	(segment
		(start -371.904999 26.514999)
		(end -372.539999 25.879999)
		(width 0.3048)
		(layer "F.Cu")
		(net "GND")
	)
	(segment
		(start -283.750001 36.159999)
		(end -283.750001 34.72942)
		(width 0.3048)
		(layer "F.Cu")
		(net "GND")
	)
	(segment
		(start -354.6094 33.4137)
		(end -355.6254 33.4137)
		(width 0.3048)
		(layer "F.Cu")
		(net "GND")
	)
	(segment
		(start -311.649999 39.941581)
		(end -311.65008 39.9669)
		(width 0.3048)
		(layer "F.Cu")
		(net "GND")
	)
	(segment
		(start -374.444999 43.024999)
		(end -375.079999 42.389999)
		(width 0.3048)
		(layer "F.Cu")
		(net "GND")
	)
	(segment
		(start -62.750002 34.72942)
		(end -62.750002 36.159999)
		(width 0.3048)
		(layer "F.Cu")
		(net "GND")
	)
	(segment
		(start -154.714999 34.134999)
		(end -155.349999 33.499999)
		(width 0.3048)
		(layer "F.Cu")
		(net "GND")
	)
	(segment
		(start -378.889999 38.569613)
		(end -378.879613 38.569613)
		(width 0.3048)
		(layer "F.Cu")
		(net "GND")
	)
	(segment
		(start -330.819999 7.6708)
		(end -329.8952 7.6708)
		(width 0.3048)
		(layer "F.Cu")
		(net "GND")
	)
	(segment
		(start -65.717801 26.45934)
		(end -65.550001 26.62714)
		(width 0.3048)
		(layer "F.Cu")
		(net "GND")
	)
	(segment
		(start -150.904999 43.024999)
		(end -151.539999 42.389999)
		(width 0.3048)
		(layer "F.Cu")
		(net "GND")
	)
	(segment
		(start -158.524999 26.514999)
		(end -159.248899 26.514999)
		(width 0.3048)
		(layer "F.Cu")
		(net "GND")
	)
	(segment
		(start -379.524999 32.864999)
		(end -380.248899 32.864999)
		(width 0.3048)
		(layer "F.Cu")
		(net "GND")
	)
	(segment
		(start -112.268 7.48792)
		(end -112.26292 7.493)
		(width 0.3048)
		(layer "F.Cu")
		(net "GND")
	)
	(segment
		(start -150.904999 22.704999)
		(end -151.539999 22.069999)
		(width 0.3048)
		(layer "F.Cu")
		(net "GND")
	)
	(segment
		(start -318.85 39.941581)
		(end -318.85 41.340001)
		(width 0.3048)
		(layer "F.Cu")
		(net "GND")
	)
	(segment
		(start -370.634999 23.974999)
		(end -371.269999 23.339999)
		(width 0.3048)
		(layer "F.Cu")
		(net "GND")
	)
	(segment
		(start -321.25 39.941581)
		(end -321.250081 39.9669)
		(width 0.3048)
		(layer "F.Cu")
		(net "GND")
	)
	(segment
		(start -371.904999 27.784999)
		(end -372.539999 27.149999)
		(width 0.3048)
		(layer "F.Cu")
		(net "GND")
	)
	(segment
		(start -202.379946 34.337056)
		(end -201.607001 35.110001)
		(width 0.381)
		(layer "F.Cu")
		(net "GND")
	)
	(segment
		(start -201.607001 35.110001)
		(end -200.834056 34.337056)
		(width 0.381)
		(layer "F.Cu")
		(net "GND")
	)
	(segment
		(start -97.450001 43.840001)
		(end -97.450001 45.211601)
		(width 0.3048)
		(layer "F.Cu")
		(net "GND")
	)
	(segment
		(start -90.649999 39.941581)
		(end -90.65008 39.9669)
		(width 0.3048)
		(layer "F.Cu")
		(net "GND")
	)
	(segment
		(start -153.444999 37.944999)
		(end -154.079999 37.309999)
		(width 0.3048)
		(layer "F.Cu")
		(net "GND")
	)
	(segment
		(start -154.714999 39.214999)
		(end -155.349999 38.579999)
		(width 0.3048)
		(layer "F.Cu")
		(net "GND")
	)
	(segment
		(start -60.350001 36.159999)
		(end -60.350001 34.72942)
		(width 0.3048)
		(layer "F.Cu")
		(net "GND")
	)
	(segment
		(start -379.5654 27.807412)
		(end -380.011508 27.807412)
		(width 0.3048)
		(layer "F.Cu")
		(net "GND")
	)
	(segment
		(start -99.850001 43.840001)
		(end -99.850001 45.211601)
		(width 0.3048)
		(layer "F.Cu")
		(net "GND")
	)
	(segment
		(start -153.444999 41.754999)
		(end -154.079999 41.119999)
		(width 0.3048)
		(layer "F.Cu")
		(net "GND")
	)
	(segment
		(start -285.020601 43.345202)
		(end -285.7246 43.345202)
		(width 0.3048)
		(layer "F.Cu")
		(net "GND")
	)
	(segment
		(start -376.984999 43.024999)
		(end -377.619999 42.389999)
		(width 0.3048)
		(layer "F.Cu")
		(net "GND")
	)
	(segment
		(start -309.249999 39.941581)
		(end -309.249999 41.340001)
		(width 0.3048)
		(layer "F.Cu")
		(net "GND")
	)
	(segment
		(start -278.950001 34.72942)
		(end -278.950001 36.159999)
		(width 0.3048)
		(layer "F.Cu")
		(net "GND")
	)
	(segment
		(start -152.174999 34.134999)
		(end -152.809999 33.499999)
		(width 0.3048)
		(layer "F.Cu")
		(net "GND")
	)
	(segment
		(start -153.444999 21.434999)
		(end -154.079999 20.799999)
		(width 0.3048)
		(layer "F.Cu")
		(net "GND")
	)
	(segment
		(start -378.254999 25.244999)
		(end -378.889999 24.609999)
		(width 0.3048)
		(layer "F.Cu")
		(net "GND")
	)
	(segment
		(start -64.020601 43.345202)
		(end -64.7192 43.345202)
		(width 0.3048)
		(layer "F.Cu")
		(net "GND")
	)
	(segment
		(start -157.254999 30.324999)
		(end -157.889999 29.689999)
		(width 0.3048)
		(layer "F.Cu")
		(net "GND")
	)
	(segment
		(start -380.033921 27.784999)
		(end -380.248899 27.784999)
		(width 0.3048)
		(layer "F.Cu")
		(net "GND")
	)
	(segment
		(start -378.254999 39.214999)
		(end -378.889999 38.579999)
		(width 0.3048)
		(layer "F.Cu")
		(net "GND")
	)
	(segment
		(start -157.254999 20.164999)
		(end -157.889999 19.529999)
		(width 0.3048)
		(layer "F.Cu")
		(net "GND")
	)
	(segment
		(start -375.714999 30.324999)
		(end -376.349999 29.689999)
		(width 0.3048)
		(layer "F.Cu")
		(net "GND")
	)
	(segment
		(start -157.254999 29.054999)
		(end -157.889999 28.419999)
		(width 0.3048)
		(layer "F.Cu")
		(net "GND")
	)
	(segment
		(start -375.714999 34.134999)
		(end -376.349999 33.499999)
		(width 0.3048)
		(layer "F.Cu")
		(net "GND")
	)
	(segment
		(start -379.524999 27.784999)
		(end -379.542987 27.784999)
		(width 0.3048)
		(layer "F.Cu")
		(net "GND")
	)
	(segment
		(start -344.551 5.374401)
		(end -344.551 6.4516)
		(width 0.3048)
		(layer "F.Cu")
		(net "GND")
	)
	(segment
		(start -336.50936 20.85848)
		(end -336.491682 20.840802)
		(width 0.3048)
		(layer "F.Cu")
		(net "GND")
	)
	(via
		(at -257.210044 18.001828)
		(size 0.5588)
		(drill 0.254)
		(layers "F.Cu" "B.Cu")
		(net "GND")
	)
	(via
		(at -380.248899 27.784999)
		(size 0.5588)
		(drill 0.254)
		(layers "F.Cu" "B.Cu")
		(net "GND")
	)
	(via
		(at -242.964556 11.664213)
		(size 0.5588)
		(drill 0.254)
		(layers "F.Cu" "B.Cu")
		(net "GND")
	)
	(via
		(at -61.722 0.127)
		(size 0.5588)
		(drill 0.254)
		(layers "F.Cu" "B.Cu")
		(net "GND")
	)
	(via
		(at -380.248899 32.864999)
		(size 0.5588)
		(drill 0.254)
		(layers "F.Cu" "B.Cu")
		(net "GND")
	)
	(via
		(at -227.965 11.43)
		(size 0.5588)
		(drill 0.254)
		(layers "F.Cu" "B.Cu")
		(net "GND")
	)
	(via
		(at -382.285979 5.628579)
		(size 0.5588)
		(drill 0.254)
		(layers "F.Cu" "B.Cu")
		(net "GND")
	)
	(via
		(at -32.964557 15.464823)
		(size 0.5588)
		(drill 0.254)
		(layers "F.Cu" "B.Cu")
		(net "GND")
	)
	(via
		(at -387.365979 5.628579)
		(size 0.5588)
		(drill 0.254)
		(layers "F.Cu" "B.Cu")
		(net "GND")
	)
	(via
		(at -339.725 15.875)
		(size 0.5588)
		(drill 0.254)
		(layers "F.Cu" "B.Cu")
		(net "GND")
	)
	(via
		(at -100.250081 39.9669)
		(size 0.5588)
		(drill 0.254)
		(layers "F.Cu" "B.Cu")
		(net "GND")
	)
	(via
		(at -15.113 18.034)
		(size 0.5588)
		(drill 0.254)
		(layers "F.Cu" "B.Cu")
		(net "GND")
	)
	(via
		(at -2.413 8.509)
		(size 0.5588)
		(drill 0.254)
		(layers "F.Cu" "B.Cu")
		(net "GND")
	)
	(via
		(at -154.079999 36.039999)
		(size 0.5588)
		(drill 0.254)
		(layers "F.Cu" "B.Cu")
		(net "GND")
	)
	(via
		(at -371.269999 28.419999)
		(size 0.5588)
		(drill 0.254)
		(layers "F.Cu" "B.Cu")
		(net "GND")
	)
	(via
		(at -35.306 2.159)
		(size 0.5588)
		(drill 0.254)
		(layers "F.Cu" "B.Cu")
		(net "GND")
	)
	(via
		(at -354.461613 -3.569396)
		(size 0.5588)
		(drill 0.254)
		(layers "F.Cu" "B.Cu")
		(net "GND")
	)
	(via
		(at -285.940599 40.000674)
		(size 0.5588)
		(drill 0.254)
		(layers "F.Cu" "B.Cu")
		(net "GND")
	)
	(via
		(at -91.567 22.1234)
		(size 0.5588)
		(drill 0.254)
		(layers "F.Cu" "B.Cu")
		(net "GND")
	)
	(via
		(at -130.81 16.51)
		(size 0.5588)
		(drill 0.254)
		(layers "F.Cu" "B.Cu")
		(net "GND")
	)
	(via
		(at -93.41136 46.50232)
		(size 0.5588)
		(drill 0.254)
		(layers "F.Cu" "B.Cu")
		(net "GND")
	)
	(via
		(at -246.8318 18.7452)
		(size 0.5588)
		(drill 0.254)
		(layers "F.Cu" "B.Cu")
		(net "GND")
	)
	(via
		(at -92.71 -3.175)
		(size 0.5588)
		(drill 0.254)
		(layers "F.Cu" "B.Cu")
		(net "GND")
	)
	(via
		(at -94.82614 48.82007)
		(size 0.5588)
		(drill 0.254)
		(layers "F.Cu" "B.Cu")
		(net "GND")
	)
	(via
		(at -146.685 3.175)
		(size 0.5588)
		(drill 0.254)
		(layers "F.Cu" "B.Cu")
		(net "GND")
	)
	(via
		(at -242.989956 23.039423)
		(size 0.5588)
		(drill 0.254)
		(layers "F.Cu" "B.Cu")
		(net "GND")
	)
	(via
		(at -335.28 0.127)
		(size 0.5588)
		(drill 0.254)
		(layers "F.Cu" "B.Cu")
		(net "GND")
	)
	(via
		(at -127.635 19.685)
		(size 0.5588)
		(drill 0.254)
		(layers "F.Cu" "B.Cu")
		(net "GND")
	)
	(via
		(at -372.539999 25.879999)
		(size 0.5588)
		(drill 0.254)
		(layers "F.Cu" "B.Cu")
		(net "GND")
	)
	(via
		(at -102.040601 46.059595)
		(size 0.5588)
		(drill 0.254)
		(layers "F.Cu" "B.Cu")
		(net "GND")
	)
	(via
		(at -218.44 14.605)
		(size 0.5588)
		(drill 0.254)
		(layers "F.Cu" "B.Cu")
		(net "GND")
	)
	(via
		(at -156.619999 25.879999)
		(size 0.5588)
		(drill 0.254)
		(layers "F.Cu" "B.Cu")
		(net "GND")
	)
	(via
		(at -372.125979 4.358579)
		(size 0.5588)
		(drill 0.254)
		(layers "F.Cu" "B.Cu")
		(net "GND")
	)
	(via
		(at -22.606 5.334)
		(size 0.5588)
		(drill 0.254)
		(layers "F.Cu" "B.Cu")
		(net "GND")
	)
	(via
		(at -196.215 17.78)
		(size 0.5588)
		(drill 0.254)
		(layers "F.Cu" "B.Cu")
		(net "GND")
	)
	(via
		(at -155.349999 24.609999)
		(size 0.5588)
		(drill 0.254)
		(layers "F.Cu" "B.Cu")
		(net "GND")
	)
	(via
		(at -245.239957 23.039423)
		(size 0.5588)
		(drill 0.254)
		(layers "F.Cu" "B.Cu")
		(net "GND")
	)
	(via
		(at -376.349999 28.419999)
		(size 0.5588)
		(drill 0.254)
		(layers "F.Cu" "B.Cu")
		(net "GND")
	)
	(via
		(at -60.350001 37.61486)
		(size 0.5588)
		(drill 0.254)
		(layers "F.Cu" "B.Cu")
		(net "GND")
	)
	(via
		(at -311.65008 39.9669)
		(size 0.5588)
		(drill 0.254)
		(layers "F.Cu" "B.Cu")
		(net "GND")
	)
	(via
		(at -133.985 9.525)
		(size 0.5588)
		(drill 0.254)
		(layers "F.Cu" "B.Cu")
		(net "GND")
	)
	(via
		(at -143.51 6.35)
		(size 0.5588)
		(drill 0.254)
		(layers "F.Cu" "B.Cu")
		(net "GND")
	)
	(via
		(at -242.964556 15.464823)
		(size 0.5588)
		(drill 0.254)
		(layers "F.Cu" "B.Cu")
		(net "GND")
	)
	(via
		(at -364.871 22.225)
		(size 0.5588)
		(drill 0.254)
		(layers "F.Cu" "B.Cu")
		(net "GND")
	)
	(via
		(at -156.619999 27.149999)
		(size 0.5588)
		(drill 0.254)
		(layers "F.Cu" "B.Cu")
		(net "GND")
	)
	(via
		(at -5.588 5.334)
		(size 0.5588)
		(drill 0.254)
		(layers "F.Cu" "B.Cu")
		(net "GND")
	)
	(via
		(at -246.210044 21.815138)
		(size 0.5588)
		(drill 0.254)
		(layers "F.Cu" "B.Cu")
		(net "GND")
	)
	(via
		(at -160.02 3.175)
		(size 0.5588)
		(drill 0.254)
		(layers "F.Cu" "B.Cu")
		(net "GND")
	)
	(via
		(at -97.850081 39.9669)
		(size 0.5588)
		(drill 0.254)
		(layers "F.Cu" "B.Cu")
		(net "GND")
	)
	(via
		(at -118.11 6.35)
		(size 0.5588)
		(drill 0.254)
		(layers "F.Cu" "B.Cu")
		(net "GND")
	)
	(via
		(at -36.210044 21.815138)
		(size 0.5588)
		(drill 0.254)
		(layers "F.Cu" "B.Cu")
		(net "GND")
	)
	(via
		(at -76.835 -3.175)
		(size 0.5588)
		(drill 0.254)
		(layers "F.Cu" "B.Cu")
		(net "GND")
	)
	(via
		(at -21.964556 15.464823)
		(size 0.5588)
		(drill 0.254)
		(layers "F.Cu" "B.Cu")
		(net "GND")
	)
	(via
		(at -387.365979 4.358579)
		(size 0.5588)
		(drill 0.254)
		(layers "F.Cu" "B.Cu")
		(net "GND")
	)
	(via
		(at -202.565 14.605)
		(size 0.5588)
		(drill 0.254)
		(layers "F.Cu" "B.Cu")
		(net "GND")
	)
	(via
		(at -234.315 -1.27)
		(size 0.5588)
		(drill 0.254)
		(layers "F.Cu" "B.Cu")
		(net "GND")
	)
	(via
		(at -199.517 30.48)
		(size 0.5588)
		(drill 0.254)
		(layers "F.Cu" "B.Cu")
		(net "GND")
	)
	(via
		(at -95.885 -3.175)
		(size 0.5588)
		(drill 0.254)
		(layers "F.Cu" "B.Cu")
		(net "GND")
	)
	(via
		(at -320.850001 45.211601)
		(size 0.5588)
		(drill 0.254)
		(layers "F.Cu" "B.Cu")
		(net "GND")
	)
	(via
		(at -215.265 11.43)
		(size 0.5588)
		(drill 0.254)
		(layers "F.Cu" "B.Cu")
		(net "GND")
	)
	(via
		(at -337.9216 19.0246)
		(size 0.5588)
		(drill 0.254)
		(layers "F.Cu" "B.Cu")
		(net "GND")
	)
	(via
		(at -11.938 21.209)
		(size 0.5588)
		(drill 0.254)
		(layers "F.Cu" "B.Cu")
		(net "GND")
	)
	(via
		(at -319.055854 36.102389)
		(size 0.5588)
		(drill 0.254)
		(layers "F.Cu" "B.Cu")
		(net "GND")
	)
	(via
		(at -112.760999 -1.666001)
		(size 0.5588)
		(drill 0.254)
		(layers "F.Cu" "B.Cu")
		(net "GND")
	)
	(via
		(at -304.673 -1.3716)
		(size 0.5588)
		(drill 0.254)
		(layers "F.Cu" "B.Cu")
		(net "GND")
	)
	(via
		(at -64.7192 43.345202)
		(size 0.5588)
		(drill 0.254)
		(layers "F.Cu" "B.Cu")
		(net "GND")
	)
	(via
		(at -282.321 0.635)
		(size 0.5588)
		(drill 0.254)
		(layers "F.Cu" "B.Cu")
		(net "GND")
	)
	(via
		(at -380.248899 37.944999)
		(size 0.5588)
		(drill 0.254)
		(layers "F.Cu" "B.Cu")
		(net "GND")
	)
	(via
		(at -218.44 40.513)
		(size 0.5588)
		(drill 0.254)
		(layers "F.Cu" "B.Cu")
		(net "GND")
	)
	(via
		(at -242.1255 19.13636)
		(size 0.5588)
		(drill 0.254)
		(layers "F.Cu" "B.Cu")
		(net "GND")
	)
	(via
		(at -98.171 1.397)
		(size 0.5588)
		(drill 0.254)
		(layers "F.Cu" "B.Cu")
		(net "GND")
	)
	(via
		(at -15.113 5.334)
		(size 0.5588)
		(drill 0.254)
		(layers "F.Cu" "B.Cu")
		(net "GND")
	)
	(via
		(at -253.964557 15.464823)
		(size 0.5588)
		(drill 0.254)
		(layers "F.Cu" "B.Cu")
		(net "GND")
	)
	(via
		(at -51.435 -3.175)
		(size 0.5588)
		(drill 0.254)
		(layers "F.Cu" "B.Cu")
		(net "GND")
	)
	(via
		(at -91.821 4.826)
		(size 0.5588)
		(drill 0.254)
		(layers "F.Cu" "B.Cu")
		(net "GND")
	)
	(via
		(at -157.889999 39.849999)
		(size 0.5588)
		(drill 0.254)
		(layers "F.Cu" "B.Cu")
		(net "GND")
	)
	(via
		(at -354.0125 20.955)
		(size 0.5588)
		(drill 0.254)
		(layers "F.Cu" "B.Cu")
		(net "GND")
	)
	(via
		(at -236.855 1.905)
		(size 0.5588)
		(drill 0.254)
		(layers "F.Cu" "B.Cu")
		(net "GND")
	)
	(via
		(at -152.809999 33.499999)
		(size 0.5588)
		(drill 0.254)
		(layers "F.Cu" "B.Cu")
		(net "GND")
	)
	(via
		(at -205.74 17.78)
		(size 0.5588)
		(drill 0.254)
		(layers "F.Cu" "B.Cu")
		(net "GND")
	)
	(via
		(at -94.996 8.001)
		(size 0.5588)
		(drill 0.254)
		(layers "F.Cu" "B.Cu")
		(net "GND")
	)
	(via
		(at -90.859402 33.5407)
		(size 0.5588)
		(drill 0.254)
		(layers "F.Cu" "B.Cu")
		(net "GND")
	)
	(via
		(at -378.879613 38.569613)
		(size 0.5588)
		(drill 0.254)
		(layers "F.Cu" "B.Cu")
		(net "GND")
	)
	(via
		(at -156.619999 22.069999)
		(size 0.5588)
		(drill 0.254)
		(layers "F.Cu" "B.Cu")
		(net "GND")
	)
	(via
		(at -380.248899 36.674999)
		(size 0.5588)
		(drill 0.254)
		(layers "F.Cu" "B.Cu")
		(net "GND")
	)
	(via
		(at -8.763 14.859)
		(size 0.5588)
		(drill 0.254)
		(layers "F.Cu" "B.Cu")
		(net "GND")
	)
	(via
		(at -21.16074 19.14144)
		(size 0.5588)
		(drill 0.254)
		(layers "F.Cu" "B.Cu")
		(net "GND")
	)
	(via
		(at -10.16 -3.175)
		(size 0.5588)
		(drill 0.254)
		(layers "F.Cu" "B.Cu")
		(net "GND")
	)
	(via
		(at -378.889999 39.849999)
		(size 0.5588)
		(drill 0.254)
		(layers "F.Cu" "B.Cu")
		(net "GND")
	)
	(via
		(at -373.809999 24.609999)
		(size 0.5588)
		(drill 0.254)
		(layers "F.Cu" "B.Cu")
		(net "GND")
	)
	(via
		(at -157.889999 30.959999)
		(size 0.5588)
		(drill 0.254)
		(layers "F.Cu" "B.Cu")
		(net "GND")
	)
	(via
		(at -309.25008 39.9669)
		(size 0.5588)
		(drill 0.254)
		(layers "F.Cu" "B.Cu")
		(net "GND")
	)
	(via
		(at -137.16 22.86)
		(size 0.5588)
		(drill 0.254)
		(layers "F.Cu" "B.Cu")
		(net "GND")
	)
	(via
		(at -374.665979 3.088579)
		(size 0.5588)
		(drill 0.254)
		(layers "F.Cu" "B.Cu")
		(net "GND")
	)
	(via
		(at -92.65 45.211601)
		(size 0.5588)
		(drill 0.254)
		(layers "F.Cu" "B.Cu")
		(net "GND")
	)
	(via
		(at -28.956 2.159)
		(size 0.5588)
		(drill 0.254)
		(layers "F.Cu" "B.Cu")
		(net "GND")
	)
	(via
		(at -160.02 6.477)
		(size 0.5588)
		(drill 0.254)
		(layers "F.Cu" "B.Cu")
		(net "GND")
	)
	(via
		(at -133.985 26.035)
		(size 0.5588)
		(drill 0.254)
		(layers "F.Cu" "B.Cu")
		(net "GND")
	)
	(via
		(at -221.615 5.08)
		(size 0.5588)
		(drill 0.254)
		(layers "F.Cu" "B.Cu")
		(net "GND")
	)
	(via
		(at -341.63 -3.683)
		(size 0.5588)
		(drill 0.254)
		(layers "F.Cu" "B.Cu")
		(net "GND")
	)
	(via
		(at -22.606 2.159)
		(size 0.5588)
		(drill 0.254)
		(layers "F.Cu" "B.Cu")
		(net "GND")
	)
	(via
		(at -383.555979 3.088579)
		(size 0.5588)
		(drill 0.254)
		(layers "F.Cu" "B.Cu")
		(net "GND")
	)
	(via
		(at -170.815 -1.27)
		(size 0.5588)
		(drill 0.254)
		(layers "F.Cu" "B.Cu")
		(net "GND")
	)
	(via
		(at -18.2118 30.734)
		(size 0.5588)
		(drill 0.254)
		(layers "F.Cu" "B.Cu")
		(net "GND")
	)
	(via
		(at -215.265 24.13)
		(size 0.5588)
		(drill 0.254)
		(layers "F.Cu" "B.Cu")
		(net "GND")
	)
	(via
		(at -381.015979 4.358579)
		(size 0.5588)
		(drill 0.254)
		(layers "F.Cu" "B.Cu")
		(net "GND")
	)
	(via
		(at -15.113 24.384)
		(size 0.5588)
		(drill 0.254)
		(layers "F.Cu" "B.Cu")
		(net "GND")
	)
	(via
		(at -36.210044 14.239319)
		(size 0.5588)
		(drill 0.254)
		(layers "F.Cu" "B.Cu")
		(net "GND")
	)
	(via
		(at -212.09 33.655)
		(size 0.5588)
		(drill 0.254)
		(layers "F.Cu" "B.Cu")
		(net "GND")
	)
	(via
		(at -224.79 14.605)
		(size 0.5588)
		(drill 0.254)
		(layers "F.Cu" "B.Cu")
		(net "GND")
	)
	(via
		(at -3.81 -3.175)
		(size 0.5588)
		(drill 0.254)
		(layers "F.Cu" "B.Cu")
		(net "GND")
	)
	(via
		(at -88.445635 38.6588)
		(size 0.5588)
		(drill 0.254)
		(layers "F.Cu" "B.Cu")
		(net "GND")
	)
	(via
		(at -376.349999 24.609999)
		(size 0.5588)
		(drill 0.254)
		(layers "F.Cu" "B.Cu")
		(net "GND")
	)
	(via
		(at -202.565 11.43)
		(size 0.5588)
		(drill 0.254)
		(layers "F.Cu" "B.Cu")
		(net "GND")
	)
	(via
		(at -329.8952 7.6708)
		(size 0.5588)
		(drill 0.254)
		(layers "F.Cu" "B.Cu")
		(net "GND")
	)
	(via
		(at -305.79568 43.09364)
		(size 0.5588)
		(drill 0.254)
		(layers "F.Cu" "B.Cu")
		(net "GND")
	)
	(via
		(at -151.539999 37.309999)
		(size 0.5588)
		(drill 0.254)
		(layers "F.Cu" "B.Cu")
		(net "GND")
	)
	(via
		(at -375.079999 22.069999)
		(size 0.5588)
		(drill 0.254)
		(layers "F.Cu" "B.Cu")
		(net "GND")
	)
	(via
		(at -57.950001 34.72942)
		(size 0.5588)
		(drill 0.254)
		(layers "F.Cu" "B.Cu")
		(net "GND")
	)
	(via
		(at -196.215 -1.27)
		(size 0.5588)
		(drill 0.254)
		(layers "F.Cu" "B.Cu")
		(net "GND")
	)
	(via
		(at -7.747 40.259)
		(size 0.5588)
		(drill 0.254)
		(layers "F.Cu" "B.Cu")
		(net "GND")
	)
	(via
		(at 0.762 24.384)
		(size 0.5588)
		(drill 0.254)
		(layers "F.Cu" "B.Cu")
		(net "GND")
	)
	(via
		(at -278.950001 37.61486)
		(size 0.5588)
		(drill 0.254)
		(layers "F.Cu" "B.Cu")
		(net "GND")
	)
	(via
		(at -24.214557 19.265433)
		(size 0.5588)
		(drill 0.254)
		(layers "F.Cu" "B.Cu")
		(net "GND")
	)
	(via
		(at -7.747 37.084)
		(size 0.5588)
		(drill 0.254)
		(layers "F.Cu" "B.Cu")
		(net "GND")
	)
	(via
		(at -58.42 3.429)
		(size 0.5588)
		(drill 0.254)
		(layers "F.Cu" "B.Cu")
		(net "GND")
	)
	(via
		(at -22.86 -3.175)
		(size 0.5588)
		(drill 0.254)
		(layers "F.Cu" "B.Cu")
		(net "GND")
	)
	(via
		(at -92.840602 33.5407)
		(size 0.5588)
		(drill 0.254)
		(layers "F.Cu" "B.Cu")
		(net "GND")
	)
	(via
		(at -65.150002 37.58946)
		(size 0.5588)
		(drill 0.254)
		(layers "F.Cu" "B.Cu")
		(net "GND")
	)
	(via
		(at -189.865 -1.27)
		(size 0.5588)
		(drill 0.254)
		(layers "F.Cu" "B.Cu")
		(net "GND")
	)
	(via
		(at -5.588 8.509)
		(size 0.5588)
		(drill 0.254)
		(layers "F.Cu" "B.Cu")
		(net "GND")
	)
	(via
		(at -236.855 -3.683)
		(size 0.5588)
		(drill 0.254)
		(layers "F.Cu" "B.Cu")
		(net "GND")
	)
	(via
		(at -193.04 1.905)
		(size 0.5588)
		(drill 0.254)
		(layers "F.Cu" "B.Cu")
		(net "GND")
	)
	(via
		(at -140.335 45.085)
		(size 0.5588)
		(drill 0.254)
		(layers "F.Cu" "B.Cu")
		(net "GND")
	)
	(via
		(at -380.248899 41.754999)
		(size 0.5588)
		(drill 0.254)
		(layers "F.Cu" "B.Cu")
		(net "GND")
	)
	(via
		(at -48.35906 -3.23596)
		(size 0.5588)
		(drill 0.254)
		(layers "F.Cu" "B.Cu")
		(net "GND")
	)
	(via
		(at -54.61 -3.175)
		(size 0.5588)
		(drill 0.254)
		(layers "F.Cu" "B.Cu")
		(net "GND")
	)
	(via
		(at -155.349999 29.689999)
		(size 0.5588)
		(drill 0.254)
		(layers "F.Cu" "B.Cu")
		(net "GND")
	)
	(via
		(at -62.750002 37.61486)
		(size 0.5588)
		(drill 0.254)
		(layers "F.Cu" "B.Cu")
		(net "GND")
	)
	(via
		(at -91.43016 47.67072)
		(size 0.5588)
		(drill 0.254)
		(layers "F.Cu" "B.Cu")
		(net "GND")
	)
	(via
		(at -321.4594 39.13632)
		(size 0.5588)
		(drill 0.254)
		(layers "F.Cu" "B.Cu")
		(net "GND")
	)
	(via
		(at -114.935 -3.175)
		(size 0.5588)
		(drill 0.254)
		(layers "F.Cu" "B.Cu")
		(net "GND")
	)
	(via
		(at -208.915 36.83)
		(size 0.5588)
		(drill 0.254)
		(layers "F.Cu" "B.Cu")
		(net "GND")
	)
	(via
		(at -133.985 45.085)
		(size 0.5588)
		(drill 0.254)
		(layers "F.Cu" "B.Cu")
		(net "GND")
	)
	(via
		(at -375.079999 36.039999)
		(size 0.5588)
		(drill 0.254)
		(layers "F.Cu" "B.Cu")
		(net "GND")
	)
	(via
		(at -24.239957 23.039423)
		(size 0.5588)
		(drill 0.254)
		(layers "F.Cu" "B.Cu")
		(net "GND")
	)
	(via
		(at -2.413 5.334)
		(size 0.5588)
		(drill 0.254)
		(layers "F.Cu" "B.Cu")
		(net "GND")
	)
	(via
		(at -316.99454 46.83887)
		(size 0.5588)
		(drill 0.254)
		(layers "F.Cu" "B.Cu")
		(net "GND")
	)
	(via
		(at -377.619999 36.039999)
		(size 0.5588)
		(drill 0.254)
		(layers "F.Cu" "B.Cu")
		(net "GND")
	)
	(via
		(at -163.4998 31.8516)
		(size 0.5588)
		(drill 0.254)
		(layers "F.Cu" "B.Cu")
		(net "GND")
	)
	(via
		(at -85.344 13.462)
		(size 0.5588)
		(drill 0.254)
		(layers "F.Cu" "B.Cu")
		(net "GND")
	)
	(via
		(at -372.539999 27.149999)
		(size 0.5588)
		(drill 0.254)
		(layers "F.Cu" "B.Cu")
		(net "GND")
	)
	(via
		(at -99.850001 45.211601)
		(size 0.5588)
		(drill 0.254)
		(layers "F.Cu" "B.Cu")
		(net "GND")
	)
	(via
		(at -62.750002 34.72942)
		(size 0.5588)
		(drill 0.254)
		(layers "F.Cu" "B.Cu")
		(net "GND")
	)
	(via
		(at -336.423 6.847601)
		(size 0.5588)
		(drill 0.254)
		(layers "F.Cu" "B.Cu")
		(net "GND")
	)
	(via
		(at -177.165 -1.27)
		(size 0.5588)
		(drill 0.254)
		(layers "F.Cu" "B.Cu")
		(net "GND")
	)
	(via
		(at -257.175 1.905)
		(size 0.5588)
		(drill 0.254)
		(layers "F.Cu" "B.Cu")
		(net "GND")
	)
	(via
		(at -283.750001 34.72942)
		(size 0.5588)
		(drill 0.254)
		(layers "F.Cu" "B.Cu")
		(net "GND")
	)
	(via
		(at -93.050081 39.9669)
		(size 0.5588)
		(drill 0.254)
		(layers "F.Cu" "B.Cu")
		(net "GND")
	)
	(via
		(at -160.655 -3.683)
		(size 0.5588)
		(drill 0.254)
		(layers "F.Cu" "B.Cu")
		(net "GND")
	)
	(via
		(at -151.539999 41.119999)
		(size 0.5588)
		(drill 0.254)
		(layers "F.Cu" "B.Cu")
		(net "GND")
	)
	(via
		(at -64.940599 40.000674)
		(size 0.5588)
		(drill 0.254)
		(layers "F.Cu" "B.Cu")
		(net "GND")
	)
	(via
		(at -384.825979 4.358579)
		(size 0.5588)
		(drill 0.254)
		(layers "F.Cu" "B.Cu")
		(net "GND")
	)
	(via
		(at -90.426835 38.6588)
		(size 0.5588)
		(drill 0.254)
		(layers "F.Cu" "B.Cu")
		(net "GND")
	)
	(via
		(at -154.079999 41.119999)
		(size 0.5588)
		(drill 0.254)
		(layers "F.Cu" "B.Cu")
		(net "GND")
	)
	(via
		(at -2.413 24.384)
		(size 0.5588)
		(drill 0.254)
		(layers "F.Cu" "B.Cu")
		(net "GND")
	)
	(via
		(at -155.349999 38.579999)
		(size 0.5588)
		(drill 0.254)
		(layers "F.Cu" "B.Cu")
		(net "GND")
	)
	(via
		(at -86.77688 41.92524)
		(size 0.5588)
		(drill 0.254)
		(layers "F.Cu" "B.Cu")
		(net "GND")
	)
	(via
		(at -156.464 3.175)
		(size 0.5588)
		(drill 0.254)
		(layers "F.Cu" "B.Cu")
		(net "GND")
	)
	(via
		(at -143.51 41.91)
		(size 0.5588)
		(drill 0.254)
		(layers "F.Cu" "B.Cu")
		(net "GND")
	)
	(via
		(at -10.922 40.259)
		(size 0.5588)
		(drill 0.254)
		(layers "F.Cu" "B.Cu")
		(net "GND")
	)
	(via
		(at -378.889999 19.529999)
		(size 0.5588)
		(drill 0.254)
		(layers "F.Cu" "B.Cu")
		(net "GND")
	)
	(via
		(at -15.113 31.369)
		(size 0.5588)
		(drill 0.254)
		(layers "F.Cu" "B.Cu")
		(net "GND")
	)
	(via
		(at -65.717801 26.45934)
		(size 0.5588)
		(drill 0.254)
		(layers "F.Cu" "B.Cu")
		(net "GND")
	)
	(via
		(at -137.16 29.21)
		(size 0.5588)
		(drill 0.254)
		(layers "F.Cu" "B.Cu")
		(net "GND")
	)
	(via
		(at -15.113 2.159)
		(size 0.5588)
		(drill 0.254)
		(layers "F.Cu" "B.Cu")
		(net "GND")
	)
	(via
		(at -133.985 3.175)
		(size 0.5588)
		(drill 0.254)
		(layers "F.Cu" "B.Cu")
		(net "GND")
	)
	(via
		(at -150.269999 33.499999)
		(size 0.5588)
		(drill 0.254)
		(layers "F.Cu" "B.Cu")
		(net "GND")
	)
	(via
		(at -375.079999 30.959999)
		(size 0.5588)
		(drill 0.254)
		(layers "F.Cu" "B.Cu")
		(net "GND")
	)
	(via
		(at -282.194823 31.48584)
		(size 0.5588)
		(drill 0.254)
		(layers "F.Cu" "B.Cu")
		(net "GND")
	)
	(via
		(at -88.25008 39.9669)
		(size 0.5588)
		(drill 0.254)
		(layers "F.Cu" "B.Cu")
		(net "GND")
	)
	(via
		(at -105.029 -3.175)
		(size 0.5588)
		(drill 0.254)
		(layers "F.Cu" "B.Cu")
		(net "GND")
	)
	(via
		(at -323.040601 46.059595)
		(size 0.5588)
		(drill 0.254)
		(layers "F.Cu" "B.Cu")
		(net "GND")
	)
	(via
		(at -349.25 19.05)
		(size 0.5588)
		(drill 0.254)
		(layers "F.Cu" "B.Cu")
		(net "GND")
	)
	(via
		(at -283.959399 40.000674)
		(size 0.5588)
		(drill 0.254)
		(layers "F.Cu" "B.Cu")
		(net "GND")
	)
	(via
		(at -231.013 -3.683)
		(size 0.5588)
		(drill 0.254)
		(layers "F.Cu" "B.Cu")
		(net "GND")
	)
	(via
		(at -218.44 -3.683)
		(size 0.5588)
		(drill 0.254)
		(layers "F.Cu" "B.Cu")
		(net "GND")
	)
	(via
		(at -249.682 1.905)
		(size 0.5588)
		(drill 0.254)
		(layers "F.Cu" "B.Cu")
		(net "GND")
	)
	(via
		(at -199.39 1.905)
		(size 0.5588)
		(drill 0.254)
		(layers "F.Cu" "B.Cu")
		(net "GND")
	)
	(via
		(at -100.4594 37.96792)
		(size 0.5588)
		(drill 0.254)
		(layers "F.Cu" "B.Cu")
		(net "GND")
	)
	(via
		(at -357.1875 20.955)
		(size 0.5588)
		(drill 0.254)
		(layers "F.Cu" "B.Cu")
		(net "GND")
	)
	(via
		(at -380.248899 26.514999)
		(size 0.5588)
		(drill 0.254)
		(layers "F.Cu" "B.Cu")
		(net "GND")
	)
	(via
		(at -316.23 17.78)
		(size 0.5588)
		(drill 0.254)
		(layers "F.Cu" "B.Cu")
		(net "GND")
	)
	(via
		(at -202.565 5.08)
		(size 0.5588)
		(drill 0.254)
		(layers "F.Cu" "B.Cu")
		(net "GND")
	)
	(via
		(at -377.205979 3.088579)
		(size 0.5588)
		(drill 0.254)
		(layers "F.Cu" "B.Cu")
		(net "GND")
	)
	(via
		(at -313.840602 34.7091)
		(size 0.5588)
		(drill 0.254)
		(layers "F.Cu" "B.Cu")
		(net "GND")
	)
	(via
		(at -68.072 0.127)
		(size 0.5588)
		(drill 0.254)
		(layers "F.Cu" "B.Cu")
		(net "GND")
	)
	(via
		(at -205.74 -3.683)
		(size 0.5588)
		(drill 0.254)
		(layers "F.Cu" "B.Cu")
		(net "GND")
	)
	(via
		(at -2.413 27.559)
		(size 0.5588)
		(drill 0.254)
		(layers "F.Cu" "B.Cu")
		(net "GND")
	)
	(via
		(at -153.035 -3.175)
		(size 0.5588)
		(drill 0.254)
		(layers "F.Cu" "B.Cu")
		(net "GND")
	)
	(via
		(at -21.964556 11.664213)
		(size 0.5588)
		(drill 0.254)
		(layers "F.Cu" "B.Cu")
		(net "GND")
	)
	(via
		(at -102.4406 39.13632)
		(size 0.5588)
		(drill 0.254)
		(layers "F.Cu" "B.Cu")
		(net "GND")
	)
	(via
		(at -315.82614 48.82007)
		(size 0.5588)
		(drill 0.254)
		(layers "F.Cu" "B.Cu")
		(net "GND")
	)
	(via
		(at -193.04 14.605)
		(size 0.5588)
		(drill 0.254)
		(layers "F.Cu" "B.Cu")
		(net "GND")
	)
	(via
		(at -94.82614 46.83887)
		(size 0.5588)
		(drill 0.254)
		(layers "F.Cu" "B.Cu")
		(net "GND")
	)
	(via
		(at -15.113 11.684)
		(size 0.5588)
		(drill 0.254)
		(layers "F.Cu" "B.Cu")
		(net "GND")
	)
	(via
		(at -166.497 9.525)
		(size 0.5588)
		(drill 0.254)
		(layers "F.Cu" "B.Cu")
		(net "GND")
	)
	(via
		(at -294.64 9.779)
		(size 0.5588)
		(drill 0.254)
		(layers "F.Cu" "B.Cu")
		(net "GND")
	)
	(via
		(at -363.347 23.749)
		(size 0.5588)
		(drill 0.254)
		(layers "F.Cu" "B.Cu")
		(net "GND")
	)
	(via
		(at -57.454701 43.345202)
		(size 0.5588)
		(drill 0.254)
		(layers "F.Cu" "B.Cu")
		(net "GND")
	)
	(via
		(at -308.85 45.211601)
		(size 0.5588)
		(drill 0.254)
		(layers "F.Cu" "B.Cu")
		(net "GND")
	)
	(via
		(at -35.306 5.334)
		(size 0.5588)
		(drill 0.254)
		(layers "F.Cu" "B.Cu")
		(net "GND")
	)
	(via
		(at -130.81 29.21)
		(size 0.5588)
		(drill 0.254)
		(layers "F.Cu" "B.Cu")
		(net "GND")
	)
	(via
		(at -133.985 19.685)
		(size 0.5588)
		(drill 0.254)
		(layers "F.Cu" "B.Cu")
		(net "GND")
	)
	(via
		(at -157.889999 33.499999)
		(size 0.5588)
		(drill 0.254)
		(layers "F.Cu" "B.Cu")
		(net "GND")
	)
	(via
		(at -121.285 9.525)
		(size 0.5588)
		(drill 0.254)
		(layers "F.Cu" "B.Cu")
		(net "GND")
	)
	(via
		(at 0.762 30.48)
		(size 0.5588)
		(drill 0.254)
		(layers "F.Cu" "B.Cu")
		(net "GND")
	)
	(via
		(at -343.0524 19.05)
		(size 0.5588)
		(drill 0.254)
		(layers "F.Cu" "B.Cu")
		(net "GND")
	)
	(via
		(at -127.635 -3.175)
		(size 0.5588)
		(drill 0.254)
		(layers "F.Cu" "B.Cu")
		(net "GND")
	)
	(via
		(at -208.915 5.08)
		(size 0.5588)
		(drill 0.254)
		(layers "F.Cu" "B.Cu")
		(net "GND")
	)
	(via
		(at -257.210044 14.239319)
		(size 0.5588)
		(drill 0.254)
		(layers "F.Cu" "B.Cu")
		(net "GND")
	)
	(via
		(at -384.825979 3.088579)
		(size 0.5588)
		(drill 0.254)
		(layers "F.Cu" "B.Cu")
		(net "GND")
	)
	(via
		(at -157.879613 38.569613)
		(size 0.5588)
		(drill 0.254)
		(layers "F.Cu" "B.Cu")
		(net "GND")
	)
	(via
		(at -389.905979 3.088579)
		(size 0.5588)
		(drill 0.254)
		(layers "F.Cu" "B.Cu")
		(net "GND")
	)
	(via
		(at -388.635979 4.358579)
		(size 0.5588)
		(drill 0.254)
		(layers "F.Cu" "B.Cu")
		(net "GND")
	)
	(via
		(at -354.203 4.572)
		(size 0.5588)
		(drill 0.254)
		(layers "F.Cu" "B.Cu")
		(net "GND")
	)
	(via
		(at -36.8554 18.8214)
		(size 0.5588)
		(drill 0.254)
		(layers "F.Cu" "B.Cu")
		(net "GND")
	)
	(via
		(at -124.46 0)
		(size 0.5588)
		(drill 0.254)
		(layers "F.Cu" "B.Cu")
		(net "GND")
	)
	(via
		(at -378.889999 23.339999)
		(size 0.5588)
		(drill 0.254)
		(layers "F.Cu" "B.Cu")
		(net "GND")
	)
	(via
		(at -63.5816 32.766)
		(size 0.5588)
		(drill 0.254)
		(layers "F.Cu" "B.Cu")
		(net "GND")
	)
	(via
		(at -61.194823 31.48584)
		(size 0.5588)
		(drill 0.254)
		(layers "F.Cu" "B.Cu")
		(net "GND")
	)
	(via
		(at -154.079999 20.799999)
		(size 0.5588)
		(drill 0.254)
		(layers "F.Cu" "B.Cu")
		(net "GND")
	)
	(via
		(at -375.079999 41.119999)
		(size 0.5588)
		(drill 0.254)
		(layers "F.Cu" "B.Cu")
		(net "GND")
	)
	(via
		(at -84.79568 43.09364)
		(size 0.5588)
		(drill 0.254)
		(layers "F.Cu" "B.Cu")
		(net "GND")
	)
	(via
		(at -348.2975 28.575)
		(size 0.5588)
		(drill 0.254)
		(layers "F.Cu" "B.Cu")
		(net "GND")
	)
	(via
		(at -157.889999 19.529999)
		(size 0.5588)
		(drill 0.254)
		(layers "F.Cu" "B.Cu")
		(net "GND")
	)
	(via
		(at -64.6992 32.766)
		(size 0.5588)
		(drill 0.254)
		(layers "F.Cu" "B.Cu")
		(net "GND")
	)
	(via
		(at -4.572 37.084)
		(size 0.5588)
		(drill 0.254)
		(layers "F.Cu" "B.Cu")
		(net "GND")
	)
	(via
		(at -278.454701 43.345202)
		(size 0.5588)
		(drill 0.254)
		(layers "F.Cu" "B.Cu")
		(net "GND")
	)
	(via
		(at -93.41136 47.67072)
		(size 0.5588)
		(drill 0.254)
		(layers "F.Cu" "B.Cu")
		(net "GND")
	)
	(via
		(at -29.21 -3.175)
		(size 0.5588)
		(drill 0.254)
		(layers "F.Cu" "B.Cu")
		(net "GND")
	)
	(via
		(at -253.15418 19.16684)
		(size 0.5588)
		(drill 0.254)
		(layers "F.Cu" "B.Cu")
		(net "GND")
	)
	(via
		(at -2.413 14.859)
		(size 0.5588)
		(drill 0.254)
		(layers "F.Cu" "B.Cu")
		(net "GND")
	)
	(via
		(at -102.040601 47.227995)
		(size 0.5588)
		(drill 0.254)
		(layers "F.Cu" "B.Cu")
		(net "GND")
	)
	(via
		(at -25.781 2.159)
		(size 0.5588)
		(drill 0.254)
		(layers "F.Cu" "B.Cu")
		(net "GND")
	)
	(via
		(at -377.619999 42.389999)
		(size 0.5588)
		(drill 0.254)
		(layers "F.Cu" "B.Cu")
		(net "GND")
	)
	(via
		(at -360.299 23.749)
		(size 0.5588)
		(drill 0.254)
		(layers "F.Cu" "B.Cu")
		(net "GND")
	)
	(via
		(at -153.035 3.175)
		(size 0.5588)
		(drill 0.254)
		(layers "F.Cu" "B.Cu")
		(net "GND")
	)
	(via
		(at -180.34 -3.683)
		(size 0.5588)
		(drill 0.254)
		(layers "F.Cu" "B.Cu")
		(net "GND")
	)
	(via
		(at -15.113 40.894)
		(size 0.5588)
		(drill 0.254)
		(layers "F.Cu" "B.Cu")
		(net "GND")
	)
	(via
		(at -319.405 14.605)
		(size 0.5588)
		(drill 0.254)
		(layers "F.Cu" "B.Cu")
		(net "GND")
	)
	(via
		(at -278.4348 44.488202)
		(size 0.5588)
		(drill 0.254)
		(layers "F.Cu" "B.Cu")
		(net "GND")
	)
	(via
		(at -143.51 16.51)
		(size 0.5588)
		(drill 0.254)
		(layers "F.Cu" "B.Cu")
		(net "GND")
	)
	(via
		(at -157.889999 29.689999)
		(size 0.5588)
		(drill 0.254)
		(layers "F.Cu" "B.Cu")
		(net "GND")
	)
	(via
		(at -156.619999 36.039999)
		(size 0.5588)
		(drill 0.254)
		(layers "F.Cu" "B.Cu")
		(net "GND")
	)
	(via
		(at -15.113 21.209)
		(size 0.5588)
		(drill 0.254)
		(layers "F.Cu" "B.Cu")
		(net "GND")
	)
	(via
		(at -25.781 5.334)
		(size 0.5588)
		(drill 0.254)
		(layers "F.Cu" "B.Cu")
		(net "GND")
	)
	(via
		(at -19.431 5.334)
		(size 0.5588)
		(drill 0.254)
		(layers "F.Cu" "B.Cu")
		(net "GND")
	)
	(via
		(at -91.821 14.351)
		(size 0.5588)
		(drill 0.254)
		(layers "F.Cu" "B.Cu")
		(net "GND")
	)
	(via
		(at -218.44 33.655)
		(size 0.5588)
		(drill 0.254)
		(layers "F.Cu" "B.Cu")
		(net "GND")
	)
	(via
		(at -202.565 -1.27)
		(size 0.5588)
		(drill 0.254)
		(layers "F.Cu" "B.Cu")
		(net "GND")
	)
	(via
		(at -94.996 14.351)
		(size 0.5588)
		(drill 0.254)
		(layers "F.Cu" "B.Cu")
		(net "GND")
	)
	(via
		(at -155.349999 33.499999)
		(size 0.5588)
		(drill 0.254)
		(layers "F.Cu" "B.Cu")
		(net "GND")
	)
	(via
		(at -146.685 38.735)
		(size 0.5588)
		(drill 0.254)
		(layers "F.Cu" "B.Cu")
		(net "GND")
	)
	(via
		(at -32.989957 23.039423)
		(size 0.5588)
		(drill 0.254)
		(layers "F.Cu" "B.Cu")
		(net "GND")
	)
	(via
		(at -379.745979 4.358579)
		(size 0.5588)
		(drill 0.254)
		(layers "F.Cu" "B.Cu")
		(net "GND")
	)
	(via
		(at -11.938 18.034)
		(size 0.5588)
		(drill 0.254)
		(layers "F.Cu" "B.Cu")
		(net "GND")
	)
	(via
		(at -377.619999 41.119999)
		(size 0.5588)
		(drill 0.254)
		(layers "F.Cu" "B.Cu")
		(net "GND")
	)
	(via
		(at -202.565 30.48)
		(size 0.5588)
		(drill 0.254)
		(layers "F.Cu" "B.Cu")
		(net "GND")
	)
	(via
		(at -150.269999 34.769999)
		(size 0.5588)
		(drill 0.254)
		(layers "F.Cu" "B.Cu")
		(net "GND")
	)
	(via
		(at -352.425 15.875)
		(size 0.5588)
		(drill 0.254)
		(layers "F.Cu" "B.Cu")
		(net "GND")
	)
	(via
		(at -212.09 27.305)
		(size 0.5588)
		(drill 0.254)
		(layers "F.Cu" "B.Cu")
		(net "GND")
	)
	(via
		(at -338.455 6.985)
		(size 0.5588)
		(drill 0.254)
		(layers "F.Cu" "B.Cu")
		(net "GND")
	)
	(via
		(at -231.14 1.905)
		(size 0.5588)
		(drill 0.254)
		(layers "F.Cu" "B.Cu")
		(net "GND")
	)
	(via
		(at -313.055 14.605)
		(size 0.5588)
		(drill 0.254)
		(layers "F.Cu" "B.Cu")
		(net "GND")
	)
	(via
		(at 0.762 18.034)
		(size 0.5588)
		(drill 0.254)
		(layers "F.Cu" "B.Cu")
		(net "GND")
	)
	(via
		(at -156.619999 30.959999)
		(size 0.5588)
		(drill 0.254)
		(layers "F.Cu" "B.Cu")
		(net "GND")
	)
	(via
		(at -88.392 4.826)
		(size 0.5588)
		(drill 0.254)
		(layers "F.Cu" "B.Cu")
		(net "GND")
	)
	(via
		(at -205.74 40.005)
		(size 0.5588)
		(drill 0.254)
		(layers "F.Cu" "B.Cu")
		(net "GND")
	)
	(via
		(at -149.86 0)
		(size 0.5588)
		(drill 0.254)
		(layers "F.Cu" "B.Cu")
		(net "GND")
	)
	(via
		(at -262.255 -3.683)
		(size 0.5588)
		(drill 0.254)
		(layers "F.Cu" "B.Cu")
		(net "GND")
	)
	(via
		(at -8.763 18.034)
		(size 0.5588)
		(drill 0.254)
		(layers "F.Cu" "B.Cu")
		(net "GND")
	)
	(via
		(at -311.426835 38.6588)
		(size 0.5588)
		(drill 0.254)
		(layers "F.Cu" "B.Cu")
		(net "GND")
	)
	(via
		(at -307.77688 41.92524)
		(size 0.5588)
		(drill 0.254)
		(layers "F.Cu" "B.Cu")
		(net "GND")
	)
	(via
		(at -156.619999 20.799999)
		(size 0.5588)
		(drill 0.254)
		(layers "F.Cu" "B.Cu")
		(net "GND")
	)
	(via
		(at -64.135 -3.175)
		(size 0.5588)
		(drill 0.254)
		(layers "F.Cu" "B.Cu")
		(net "GND")
	)
	(via
		(at -371.269999 33.499999)
		(size 0.5588)
		(drill 0.254)
		(layers "F.Cu" "B.Cu")
		(net "GND")
	)
	(via
		(at -21.964556 19.265433)
		(size 0.5588)
		(drill 0.254)
		(layers "F.Cu" "B.Cu")
		(net "GND")
	)
	(via
		(at -344.4875 20.955)
		(size 0.5588)
		(drill 0.254)
		(layers "F.Cu" "B.Cu")
		(net "GND")
	)
	(via
		(at -231.14 33.655)
		(size 0.5588)
		(drill 0.254)
		(layers "F.Cu" "B.Cu")
		(net "GND")
	)
	(via
		(at -205.74 14.605)
		(size 0.5588)
		(drill 0.254)
		(layers "F.Cu" "B.Cu")
		(net "GND")
	)
	(via
		(at -32.131 2.159)
		(size 0.5588)
		(drill 0.254)
		(layers "F.Cu" "B.Cu")
		(net "GND")
	)
	(via
		(at -64.897 3.302)
		(size 0.5588)
		(drill 0.254)
		(layers "F.Cu" "B.Cu")
		(net "GND")
	)
	(via
		(at -212.09 40.513)
		(size 0.5588)
		(drill 0.254)
		(layers "F.Cu" "B.Cu")
		(net "GND")
	)
	(via
		(at -94.996 4.826)
		(size 0.5588)
		(drill 0.254)
		(layers "F.Cu" "B.Cu")
		(net "GND")
	)
	(via
		(at -35.16376 23.21306)
		(size 0.5588)
		(drill 0.254)
		(layers "F.Cu" "B.Cu")
		(net "GND")
	)
	(via
		(at -221.615 -1.27)
		(size 0.5588)
		(drill 0.254)
		(layers "F.Cu" "B.Cu")
		(net "GND")
	)
	(via
		(at -67.31 -3.175)
		(size 0.5588)
		(drill 0.254)
		(layers "F.Cu" "B.Cu")
		(net "GND")
	)
	(via
		(at -368.3 41.275)
		(size 0.5588)
		(drill 0.254)
		(layers "F.Cu" "B.Cu")
		(net "GND")
	)
	(via
		(at -91.821 11.176)
		(size 0.5588)
		(drill 0.254)
		(layers "F.Cu" "B.Cu")
		(net "GND")
	)
	(via
		(at -133.985 32.385)
		(size 0.5588)
		(drill 0.254)
		(layers "F.Cu" "B.Cu")
		(net "GND")
	)
	(via
		(at -57.950001 37.61486)
		(size 0.5588)
		(drill 0.254)
		(layers "F.Cu" "B.Cu")
		(net "GND")
	)
	(via
		(at -5.588 2.159)
		(size 0.5588)
		(drill 0.254)
		(layers "F.Cu" "B.Cu")
		(net "GND")
	)
	(via
		(at -152.809999 38.579999)
		(size 0.5588)
		(drill 0.254)
		(layers "F.Cu" "B.Cu")
		(net "GND")
	)
	(via
		(at -363.22 19.1516)
		(size 0.5588)
		(drill 0.254)
		(layers "F.Cu" "B.Cu")
		(net "GND")
	)
	(via
		(at -152.809999 29.689999)
		(size 0.5588)
		(drill 0.254)
		(layers "F.Cu" "B.Cu")
		(net "GND")
	)
	(via
		(at -68.072 3.302)
		(size 0.5588)
		(drill 0.254)
		(layers "F.Cu" "B.Cu")
		(net "GND")
	)
	(via
		(at -8.763 21.209)
		(size 0.5588)
		(drill 0.254)
		(layers "F.Cu" "B.Cu")
		(net "GND")
	)
	(via
		(at -62.959399 40.000674)
		(size 0.5588)
		(drill 0.254)
		(layers "F.Cu" "B.Cu")
		(net "GND")
	)
	(via
		(at -26.035 -3.175)
		(size 0.5588)
		(drill 0.254)
		(layers "F.Cu" "B.Cu")
		(net "GND")
	)
	(via
		(at -286.717801 26.45934)
		(size 0.5588)
		(drill 0.254)
		(layers "F.Cu" "B.Cu")
		(net "GND")
	)
	(via
		(at -234.315 17.78)
		(size 0.5588)
		(drill 0.254)
		(layers "F.Cu" "B.Cu")
		(net "GND")
	)
	(via
		(at -21.989956 23.039423)
		(size 0.5588)
		(drill 0.254)
		(layers "F.Cu" "B.Cu")
		(net "GND")
	)
	(via
		(at -4.318 -0.381)
		(size 0.5588)
		(drill 0.254)
		(layers "F.Cu" "B.Cu")
		(net "GND")
	)
	(via
		(at -242.964556 19.265433)
		(size 0.5588)
		(drill 0.254)
		(layers "F.Cu" "B.Cu")
		(net "GND")
	)
	(via
		(at -231.14 14.605)
		(size 0.5588)
		(drill 0.254)
		(layers "F.Cu" "B.Cu")
		(net "GND")
	)
	(via
		(at -137.16 41.91)
		(size 0.5588)
		(drill 0.254)
		(layers "F.Cu" "B.Cu")
		(net "GND")
	)
	(via
		(at -378.475979 3.088579)
		(size 0.5588)
		(drill 0.254)
		(layers "F.Cu" "B.Cu")
		(net "GND")
	)
	(via
		(at -157.889999 28.419999)
		(size 0.5588)
		(drill 0.254)
		(layers "F.Cu" "B.Cu")
		(net "GND")
	)
	(via
		(at -33.960044 14.239319)
		(size 0.5588)
		(drill 0.254)
		(layers "F.Cu" "B.Cu")
		(net "GND")
	)
	(via
		(at -98.171 11.176)
		(size 0.5588)
		(drill 0.254)
		(layers "F.Cu" "B.Cu")
		(net "GND")
	)
	(via
		(at -159.248899 26.514999)
		(size 0.5588)
		(drill 0.254)
		(layers "F.Cu" "B.Cu")
		(net "GND")
	)
	(via
		(at -189.865 5.08)
		(size 0.5588)
		(drill 0.254)
		(layers "F.Cu" "B.Cu")
		(net "GND")
	)
	(via
		(at -80.01 -3.175)
		(size 0.5588)
		(drill 0.254)
		(layers "F.Cu" "B.Cu")
		(net "GND")
	)
	(via
		(at -86.9696 22.225)
		(size 0.5588)
		(drill 0.254)
		(layers "F.Cu" "B.Cu")
		(net "GND")
	)
	(via
		(at -379.745979 3.088579)
		(size 0.5588)
		(drill 0.254)
		(layers "F.Cu" "B.Cu")
		(net "GND")
	)
	(via
		(at -151.539999 30.959999)
		(size 0.5588)
		(drill 0.254)
		(layers "F.Cu" "B.Cu")
		(net "GND")
	)
	(via
		(at -224.79 33.655)
		(size 0.5588)
		(drill 0.254)
		(layers "F.Cu" "B.Cu")
		(net "GND")
	)
	(via
		(at -314.41136 47.67072)
		(size 0.5588)
		(drill 0.254)
		(layers "F.Cu" "B.Cu")
		(net "GND")
	)
	(via
		(at -314.050081 39.9669)
		(size 0.5588)
		(drill 0.254)
		(layers "F.Cu" "B.Cu")
		(net "GND")
	)
	(via
		(at -167.64 -3.683)
		(size 0.5588)
		(drill 0.254)
		(layers "F.Cu" "B.Cu")
		(net "GND")
	)
	(via
		(at -146.685 -3.175)
		(size 0.5588)
		(drill 0.254)
		(layers "F.Cu" "B.Cu")
		(net "GND")
	)
	(via
		(at -375.079999 27.149999)
		(size 0.5588)
		(drill 0.254)
		(layers "F.Cu" "B.Cu")
		(net "GND")
	)
	(via
		(at -319.055854 37.270789)
		(size 0.5588)
		(drill 0.254)
		(layers "F.Cu" "B.Cu")
		(net "GND")
	)
	(via
		(at -151.539999 32.229999)
		(size 0.5588)
		(drill 0.254)
		(layers "F.Cu" "B.Cu")
		(net "GND")
	)
	(via
		(at -2.3749 21.209)
		(size 0.5588)
		(drill 0.254)
		(layers "F.Cu" "B.Cu")
		(net "GND")
	)
	(via
		(at -352.425 31.75)
		(size 0.5588)
		(drill 0.254)
		(layers "F.Cu" "B.Cu")
		(net "GND")
	)
	(via
		(at -245.214557 19.265433)
		(size 0.5588)
		(drill 0.254)
		(layers "F.Cu" "B.Cu")
		(net "GND")
	)
	(via
		(at -323.040601 47.227995)
		(size 0.5588)
		(drill 0.254)
		(layers "F.Cu" "B.Cu")
		(net "GND")
	)
	(via
		(at -252.54712 10.38606)
		(size 0.5588)
		(drill 0.254)
		(layers "F.Cu" "B.Cu")
		(net "GND")
	)
	(via
		(at -100.4594 39.13632)
		(size 0.5588)
		(drill 0.254)
		(layers "F.Cu" "B.Cu")
		(net "GND")
	)
	(via
		(at -281.350001 34.72942)
		(size 0.5588)
		(drill 0.254)
		(layers "F.Cu" "B.Cu")
		(net "GND")
	)
	(via
		(at -45.085 -3.175)
		(size 0.5588)
		(drill 0.254)
		(layers "F.Cu" "B.Cu")
		(net "GND")
	)
	(via
		(at -196.215 30.48)
		(size 0.5588)
		(drill 0.254)
		(layers "F.Cu" "B.Cu")
		(net "GND")
	)
	(via
		(at -88.3539 22.1107)
		(size 0.5588)
		(drill 0.254)
		(layers "F.Cu" "B.Cu")
		(net "GND")
	)
	(via
		(at -89.535 -3.175)
		(size 0.5588)
		(drill 0.254)
		(layers "F.Cu" "B.Cu")
		(net "GND")
	)
	(via
		(at -150.269999 24.609999)
		(size 0.5588)
		(drill 0.254)
		(layers "F.Cu" "B.Cu")
		(net "GND")
	)
	(via
		(at -15.113 34.544)
		(size 0.5588)
		(drill 0.254)
		(layers "F.Cu" "B.Cu")
		(net "GND")
	)
	(via
		(at -373.809999 23.339999)
		(size 0.5588)
		(drill 0.254)
		(layers "F.Cu" "B.Cu")
		(net "GND")
	)
	(via
		(at -255.905 -3.683)
		(size 0.5588)
		(drill 0.254)
		(layers "F.Cu" "B.Cu")
		(net "GND")
	)
	(via
		(at -375.079999 25.879999)
		(size 0.5588)
		(drill 0.254)
		(layers "F.Cu" "B.Cu")
		(net "GND")
	)
	(via
		(at -159.248899 41.754999)
		(size 0.5588)
		(drill 0.254)
		(layers "F.Cu" "B.Cu")
		(net "GND")
	)
	(via
		(at -92.840602 34.7091)
		(size 0.5588)
		(drill 0.254)
		(layers "F.Cu" "B.Cu")
		(net "GND")
	)
	(via
		(at -41.91 -3.175)
		(size 0.5588)
		(drill 0.254)
		(layers "F.Cu" "B.Cu")
		(net "GND")
	)
	(via
		(at -102.4406 37.96792)
		(size 0.5588)
		(drill 0.254)
		(layers "F.Cu" "B.Cu")
		(net "GND")
	)
	(via
		(at -180.34 1.905)
		(size 0.5588)
		(drill 0.254)
		(layers "F.Cu" "B.Cu")
		(net "GND")
	)
	(via
		(at -95.99454 46.83887)
		(size 0.5588)
		(drill 0.254)
		(layers "F.Cu" "B.Cu")
		(net "GND")
	)
	(via
		(at -386.095979 5.628579)
		(size 0.5588)
		(drill 0.254)
		(layers "F.Cu" "B.Cu")
		(net "GND")
	)
	(via
		(at -224.79 27.305)
		(size 0.5588)
		(drill 0.254)
		(layers "F.Cu" "B.Cu")
		(net "GND")
	)
	(via
		(at -149.86 6.35)
		(size 0.5588)
		(drill 0.254)
		(layers "F.Cu" "B.Cu")
		(net "GND")
	)
	(via
		(at -373.395979 4.358579)
		(size 0.5588)
		(drill 0.254)
		(layers "F.Cu" "B.Cu")
		(net "GND")
	)
	(via
		(at -311.859402 33.5407)
		(size 0.5588)
		(drill 0.254)
		(layers "F.Cu" "B.Cu")
		(net "GND")
	)
	(via
		(at -376.349999 33.499999)
		(size 0.5588)
		(drill 0.254)
		(layers "F.Cu" "B.Cu")
		(net "GND")
	)
	(via
		(at -279.148601 26.462459)
		(size 0.5588)
		(drill 0.254)
		(layers "F.Cu" "B.Cu")
		(net "GND")
	)
	(via
		(at -279.4 3.81)
		(size 0.5588)
		(drill 0.254)
		(layers "F.Cu" "B.Cu")
		(net "GND")
	)
	(via
		(at -16.51 -3.175)
		(size 0.5588)
		(drill 0.254)
		(layers "F.Cu" "B.Cu")
		(net "GND")
	)
	(via
		(at -375.079999 42.389999)
		(size 0.5588)
		(drill 0.254)
		(layers "F.Cu" "B.Cu")
		(net "GND")
	)
	(via
		(at -17.907 27.5844)
		(size 0.5588)
		(drill 0.254)
		(layers "F.Cu" "B.Cu")
		(net "GND")
	)
	(via
		(at -72.39 27.2796)
		(size 0.5588)
		(drill 0.254)
		(layers "F.Cu" "B.Cu")
		(net "GND")
	)
	(via
		(at -19.03 43.561)
		(size 0.5588)
		(drill 0.254)
		(layers "F.Cu" "B.Cu")
		(net "GND")
	)
	(via
		(at -130.81 0)
		(size 0.5588)
		(drill 0.254)
		(layers "F.Cu" "B.Cu")
		(net "GND")
	)
	(via
		(at -321.123762 45.992791)
		(size 0.5588)
		(drill 0.254)
		(layers "F.Cu" "B.Cu")
		(net "GND")
	)
	(via
		(at -234.315 30.48)
		(size 0.5588)
		(drill 0.254)
		(layers "F.Cu" "B.Cu")
		(net "GND")
	)
	(via
		(at -61.722 10.287)
		(size 0.5588)
		(drill 0.254)
		(layers "F.Cu" "B.Cu")
		(net "GND")
	)
	(via
		(at -333.51216 20.52574)
		(size 0.5588)
		(drill 0.254)
		(layers "F.Cu" "B.Cu")
		(net "GND")
	)
	(via
		(at -372.539999 42.389999)
		(size 0.5588)
		(drill 0.254)
		(layers "F.Cu" "B.Cu")
		(net "GND")
	)
	(via
		(at -285.6992 32.766)
		(size 0.5588)
		(drill 0.254)
		(layers "F.Cu" "B.Cu")
		(net "GND")
	)
	(via
		(at -321.059401 47.227995)
		(size 0.5588)
		(drill 0.254)
		(layers "F.Cu" "B.Cu")
		(net "GND")
	)
	(via
		(at -372.539999 30.959999)
		(size 0.5588)
		(drill 0.254)
		(layers "F.Cu" "B.Cu")
		(net "GND")
	)
	(via
		(at -351.155 2.032)
		(size 0.5588)
		(drill 0.254)
		(layers "F.Cu" "B.Cu")
		(net "GND")
	)
	(via
		(at -278.13 -3.683)
		(size 0.5588)
		(drill 0.254)
		(layers "F.Cu" "B.Cu")
		(net "GND")
	)
	(via
		(at -328.93 -3.683)
		(size 0.5588)
		(drill 0.254)
		(layers "F.Cu" "B.Cu")
		(net "GND")
	)
	(via
		(at -189.865 11.43)
		(size 0.5588)
		(drill 0.254)
		(layers "F.Cu" "B.Cu")
		(net "GND")
	)
	(via
		(at -156.619999 42.389999)
		(size 0.5588)
		(drill 0.254)
		(layers "F.Cu" "B.Cu")
		(net "GND")
	)
	(via
		(at -388.635979 5.628579)
		(size 0.5588)
		(drill 0.254)
		(layers "F.Cu" "B.Cu")
		(net "GND")
	)
	(via
		(at -36.10102 10.48766)
		(size 0.5588)
		(drill 0.254)
		(layers "F.Cu" "B.Cu")
		(net "GND")
	)
	(via
		(at -257.9951 25.5397)
		(size 0.5588)
		(drill 0.254)
		(layers "F.Cu" "B.Cu")
		(net "GND")
	)
	(via
		(at -196.215 24.13)
		(size 0.5588)
		(drill 0.254)
		(layers "F.Cu" "B.Cu")
		(net "GND")
	)
	(via
		(at -151.539999 42.389999)
		(size 0.5588)
		(drill 0.254)
		(layers "F.Cu" "B.Cu")
		(net "GND")
	)
	(via
		(at -193.04 27.305)
		(size 0.5588)
		(drill 0.254)
		(layers "F.Cu" "B.Cu")
		(net "GND")
	)
	(via
		(at -88.445635 37.4904)
		(size 0.5588)
		(drill 0.254)
		(layers "F.Cu" "B.Cu")
		(net "GND")
	)
	(via
		(at -4.572 44.069)
		(size 0.5588)
		(drill 0.254)
		(layers "F.Cu" "B.Cu")
		(net "GND")
	)
	(via
		(at -414.782 34.417)
		(size 0.5588)
		(drill 0.254)
		(layers "F.Cu" "B.Cu")
		(net "GND")
	)
	(via
		(at -15.113 27.559)
		(size 0.5588)
		(drill 0.254)
		(layers "F.Cu" "B.Cu")
		(net "GND")
	)
	(via
		(at -383.555979 5.628579)
		(size 0.5588)
		(drill 0.254)
		(layers "F.Cu" "B.Cu")
		(net "GND")
	)
	(via
		(at -382.285979 3.088579)
		(size 0.5588)
		(drill 0.254)
		(layers "F.Cu" "B.Cu")
		(net "GND")
	)
	(via
		(at -323.4406 37.96792)
		(size 0.5588)
		(drill 0.254)
		(layers "F.Cu" "B.Cu")
		(net "GND")
	)
	(via
		(at -6.985 -3.175)
		(size 0.5588)
		(drill 0.254)
		(layers "F.Cu" "B.Cu")
		(net "GND")
	)
	(via
		(at -146.685 45.085)
		(size 0.5588)
		(drill 0.254)
		(layers "F.Cu" "B.Cu")
		(net "GND")
	)
	(via
		(at -357.1875 26.9875)
		(size 0.5588)
		(drill 0.254)
		(layers "F.Cu" "B.Cu")
		(net "GND")
	)
	(via
		(at -375.079999 20.799999)
		(size 0.5588)
		(drill 0.254)
		(layers "F.Cu" "B.Cu")
		(net "GND")
	)
	(via
		(at -152.809999 34.769999)
		(size 0.5588)
		(drill 0.254)
		(layers "F.Cu" "B.Cu")
		(net "GND")
	)
	(via
		(at -389.905979 4.358579)
		(size 0.5588)
		(drill 0.254)
		(layers "F.Cu" "B.Cu")
		(net "GND")
	)
	(via
		(at -347.98 0.127)
		(size 0.5588)
		(drill 0.254)
		(layers "F.Cu" "B.Cu")
		(net "GND")
	)
	(via
		(at -36.210044 18.001828)
		(size 0.5588)
		(drill 0.254)
		(layers "F.Cu" "B.Cu")
		(net "GND")
	)
	(via
		(at -245.214557 11.664213)
		(size 0.5588)
		(drill 0.254)
		(layers "F.Cu" "B.Cu")
		(net "GND")
	)
	(via
		(at -83.185 -3.175)
		(size 0.5588)
		(drill 0.254)
		(layers "F.Cu" "B.Cu")
		(net "GND")
	)
	(via
		(at -60.96 -3.175)
		(size 0.5588)
		(drill 0.254)
		(layers "F.Cu" "B.Cu")
		(net "GND")
	)
	(via
		(at -183.515 -1.27)
		(size 0.5588)
		(drill 0.254)
		(layers "F.Cu" "B.Cu")
		(net "GND")
	)
	(via
		(at -371.269999 34.769999)
		(size 0.5588)
		(drill 0.254)
		(layers "F.Cu" "B.Cu")
		(net "GND")
	)
	(via
		(at -205.74 11.43)
		(size 0.5588)
		(drill 0.254)
		(layers "F.Cu" "B.Cu")
		(net "GND")
	)
	(via
		(at -199.39 11.43)
		(size 0.5588)
		(drill 0.254)
		(layers "F.Cu" "B.Cu")
		(net "GND")
	)
	(via
		(at -157.889999 34.769999)
		(size 0.5588)
		(drill 0.254)
		(layers "F.Cu" "B.Cu")
		(net "GND")
	)
	(via
		(at -346.075 15.875)
		(size 0.5588)
		(drill 0.254)
		(layers "F.Cu" "B.Cu")
		(net "GND")
	)
	(via
		(at -286.150002 34.72942)
		(size 0.5588)
		(drill 0.254)
		(layers "F.Cu" "B.Cu")
		(net "GND")
	)
	(via
		(at -227.965 24.13)
		(size 0.5588)
		(drill 0.254)
		(layers "F.Cu" "B.Cu")
		(net "GND")
	)
	(via
		(at -377.619999 32.229999)
		(size 0.5588)
		(drill 0.254)
		(layers "F.Cu" "B.Cu")
		(net "GND")
	)
	(via
		(at -196.215 36.83)
		(size 0.5588)
		(drill 0.254)
		(layers "F.Cu" "B.Cu")
		(net "GND")
	)
	(via
		(at -381.015979 5.628579)
		(size 0.5588)
		(drill 0.254)
		(layers "F.Cu" "B.Cu")
		(net "GND")
	)
	(via
		(at -11.938 11.684)
		(size 0.5588)
		(drill 0.254)
		(layers "F.Cu" "B.Cu")
		(net "GND")
	)
	(via
		(at -173.99 -3.683)
		(size 0.5588)
		(drill 0.254)
		(layers "F.Cu" "B.Cu")
		(net "GND")
	)
	(via
		(at -61.722 3.302)
		(size 0.5588)
		(drill 0.254)
		(layers "F.Cu" "B.Cu")
		(net "GND")
	)
	(via
		(at -376.349999 39.849999)
		(size 0.5588)
		(drill 0.254)
		(layers "F.Cu" "B.Cu")
		(net "GND")
	)
	(via
		(at -159.2326 35.8902)
		(size 0.5588)
		(drill 0.254)
		(layers "F.Cu" "B.Cu")
		(net "GND")
	)
	(via
		(at -15.113 44.069)
		(size 0.5588)
		(drill 0.254)
		(layers "F.Cu" "B.Cu")
		(net "GND")
	)
	(via
		(at -157.889999 24.609999)
		(size 0.5588)
		(drill 0.254)
		(layers "F.Cu" "B.Cu")
		(net "GND")
	)
	(via
		(at -8.763 11.684)
		(size 0.5588)
		(drill 0.254)
		(layers "F.Cu" "B.Cu")
		(net "GND")
	)
	(via
		(at -170.815 11.43)
		(size 0.5588)
		(drill 0.254)
		(layers "F.Cu" "B.Cu")
		(net "GND")
	)
	(via
		(at -355.727 24.511)
		(size 0.5588)
		(drill 0.254)
		(layers "F.Cu" "B.Cu")
		(net "GND")
	)
	(via
		(at -159.6898 33.0454)
		(size 0.5588)
		(drill 0.254)
		(layers "F.Cu" "B.Cu")
		(net "GND")
	)
	(via
		(at -373.809999 39.849999)
		(size 0.5588)
		(drill 0.254)
		(layers "F.Cu" "B.Cu")
		(net "GND")
	)
	(via
		(at -193.04 -3.683)
		(size 0.5588)
		(drill 0.254)
		(layers "F.Cu" "B.Cu")
		(net "GND")
	)
	(via
		(at -313.65 45.211601)
		(size 0.5588)
		(drill 0.254)
		(layers "F.Cu" "B.Cu")
		(net "GND")
	)
	(via
		(at -386.095979 3.088579)
		(size 0.5588)
		(drill 0.254)
		(layers "F.Cu" "B.Cu")
		(net "GND")
	)
	(via
		(at -25.210044 25.615748)
		(size 0.5588)
		(drill 0.254)
		(layers "F.Cu" "B.Cu")
		(net "GND")
	)
	(via
		(at -72.39 26.1874)
		(size 0.5588)
		(drill 0.254)
		(layers "F.Cu" "B.Cu")
		(net "GND")
	)
	(via
		(at -218.44 20.955)
		(size 0.5588)
		(drill 0.254)
		(layers "F.Cu" "B.Cu")
		(net "GND")
	)
	(via
		(at -159.248899 27.784999)
		(size 0.5588)
		(drill 0.254)
		(layers "F.Cu" "B.Cu")
		(net "GND")
	)
	(via
		(at -156.619999 37.309999)
		(size 0.5588)
		(drill 0.254)
		(layers "F.Cu" "B.Cu")
		(net "GND")
	)
	(via
		(at -347.6625 20.955)
		(size 0.5588)
		(drill 0.254)
		(layers "F.Cu" "B.Cu")
		(net "GND")
	)
	(via
		(at -154.079999 22.069999)
		(size 0.5588)
		(drill 0.254)
		(layers "F.Cu" "B.Cu")
		(net "GND")
	)
	(via
		(at -24.214557 11.664213)
		(size 0.5588)
		(drill 0.254)
		(layers "F.Cu" "B.Cu")
		(net "GND")
	)
	(via
		(at -373.395979 3.088579)
		(size 0.5588)
		(drill 0.254)
		(layers "F.Cu" "B.Cu")
		(net "GND")
	)
	(via
		(at -221.615 24.13)
		(size 0.5588)
		(drill 0.254)
		(layers "F.Cu" "B.Cu")
		(net "GND")
	)
	(via
		(at -100.07124 36.0553)
		(size 0.5588)
		(drill 0.254)
		(layers "F.Cu" "B.Cu")
		(net "GND")
	)
	(via
		(at -10.668 -0.381)
		(size 0.5588)
		(drill 0.254)
		(layers "F.Cu" "B.Cu")
		(net "GND")
	)
	(via
		(at -98.171 4.826)
		(size 0.5588)
		(drill 0.254)
		(layers "F.Cu" "B.Cu")
		(net "GND")
	)
	(via
		(at -234.315 24.13)
		(size 0.5588)
		(drill 0.254)
		(layers "F.Cu" "B.Cu")
		(net "GND")
	)
	(via
		(at -311.859402 34.7091)
		(size 0.5588)
		(drill 0.254)
		(layers "F.Cu" "B.Cu")
		(net "GND")
	)
	(via
		(at -212.09 20.955)
		(size 0.5588)
		(drill 0.254)
		(layers "F.Cu" "B.Cu")
		(net "GND")
	)
	(via
		(at -89.8398 22.2504)
		(size 0.5588)
		(drill 0.254)
		(layers "F.Cu" "B.Cu")
		(net "GND")
	)
	(via
		(at -64.897 6.477)
		(size 0.5588)
		(drill 0.254)
		(layers "F.Cu" "B.Cu")
		(net "GND")
	)
	(via
		(at -215.265 5.08)
		(size 0.5588)
		(drill 0.254)
		(layers "F.Cu" "B.Cu")
		(net "GND")
	)
	(via
		(at -98.055854 36.102389)
		(size 0.5588)
		(drill 0.254)
		(layers "F.Cu" "B.Cu")
		(net "GND")
	)
	(via
		(at -91.821 8.001)
		(size 0.5588)
		(drill 0.254)
		(layers "F.Cu" "B.Cu")
		(net "GND")
	)
	(via
		(at -318.850081 39.9669)
		(size 0.5588)
		(drill 0.254)
		(layers "F.Cu" "B.Cu")
		(net "GND")
	)
	(via
		(at -155.349999 23.339999)
		(size 0.5588)
		(drill 0.254)
		(layers "F.Cu" "B.Cu")
		(net "GND")
	)
	(via
		(at -374.665979 5.628579)
		(size 0.5588)
		(drill 0.254)
		(layers "F.Cu" "B.Cu")
		(net "GND")
	)
	(via
		(at -61.194823 29.50464)
		(size 0.5588)
		(drill 0.254)
		(layers "F.Cu" "B.Cu")
		(net "GND")
	)
	(via
		(at -224.79 1.905)
		(size 0.5588)
		(drill 0.254)
		(layers "F.Cu" "B.Cu")
		(net "GND")
	)
	(via
		(at -288.925 0.635)
		(size 0.5588)
		(drill 0.254)
		(layers "F.Cu" "B.Cu")
		(net "GND")
	)
	(via
		(at -311.25 45.211601)
		(size 0.5588)
		(drill 0.254)
		(layers "F.Cu" "B.Cu")
		(net "GND")
	)
	(via
		(at -146.685 9.525)
		(size 0.5588)
		(drill 0.254)
		(layers "F.Cu" "B.Cu")
		(net "GND")
	)
	(via
		(at -379.745979 5.628579)
		(size 0.5588)
		(drill 0.254)
		(layers "F.Cu" "B.Cu")
		(net "GND")
	)
	(via
		(at -313.055 11.43)
		(size 0.5588)
		(drill 0.254)
		(layers "F.Cu" "B.Cu")
		(net "GND")
	)
	(via
		(at -82.169 16.637)
		(size 0.5588)
		(drill 0.254)
		(layers "F.Cu" "B.Cu")
		(net "GND")
	)
	(via
		(at -153.035 9.525)
		(size 0.5588)
		(drill 0.254)
		(layers "F.Cu" "B.Cu")
		(net "GND")
	)
	(via
		(at -5.588 14.859)
		(size 0.5588)
		(drill 0.254)
		(layers "F.Cu" "B.Cu")
		(net "GND")
	)
	(via
		(at -25.210044 21.815138)
		(size 0.5588)
		(drill 0.254)
		(layers "F.Cu" "B.Cu")
		(net "GND")
	)
	(via
		(at -386.095979 4.358579)
		(size 0.5588)
		(drill 0.254)
		(layers "F.Cu" "B.Cu")
		(net "GND")
	)
	(via
		(at -372.125979 3.088579)
		(size 0.5588)
		(drill 0.254)
		(layers "F.Cu" "B.Cu")
		(net "GND")
	)
	(via
		(at -208.915 24.13)
		(size 0.5588)
		(drill 0.254)
		(layers "F.Cu" "B.Cu")
		(net "GND")
	)
	(via
		(at -159.3088 38.4302)
		(size 0.5588)
		(drill 0.254)
		(layers "F.Cu" "B.Cu")
		(net "GND")
	)
	(via
		(at -224.79 20.955)
		(size 0.5588)
		(drill 0.254)
		(layers "F.Cu" "B.Cu")
		(net "GND")
	)
	(via
		(at -218.44 1.905)
		(size 0.5588)
		(drill 0.254)
		(layers "F.Cu" "B.Cu")
		(net "GND")
	)
	(via
		(at -309.445635 37.4904)
		(size 0.5588)
		(drill 0.254)
		(layers "F.Cu" "B.Cu")
		(net "GND")
	)
	(via
		(at 0.762 5.334)
		(size 0.5588)
		(drill 0.254)
		(layers "F.Cu" "B.Cu")
		(net "GND")
	)
	(via
		(at -351.155 -1.778)
		(size 0.5588)
		(drill 0.254)
		(layers "F.Cu" "B.Cu")
		(net "GND")
	)
	(via
		(at -309.445635 38.6588)
		(size 0.5588)
		(drill 0.254)
		(layers "F.Cu" "B.Cu")
		(net "GND")
	)
	(via
		(at -65.150002 34.72942)
		(size 0.5588)
		(drill 0.254)
		(layers "F.Cu" "B.Cu")
		(net "GND")
	)
	(via
		(at -286.004 3.81)
		(size 0.5588)
		(drill 0.254)
		(layers "F.Cu" "B.Cu")
		(net "GND")
	)
	(via
		(at -231.14 40.513)
		(size 0.5588)
		(drill 0.254)
		(layers "F.Cu" "B.Cu")
		(net "GND")
	)
	(via
		(at -90.65008 39.9669)
		(size 0.5588)
		(drill 0.254)
		(layers "F.Cu" "B.Cu")
		(net "GND")
	)
	(via
		(at -91.43016 46.50232)
		(size 0.5588)
		(drill 0.254)
		(layers "F.Cu" "B.Cu")
		(net "GND")
	)
	(via
		(at -380.248899 22.704999)
		(size 0.5588)
		(drill 0.254)
		(layers "F.Cu" "B.Cu")
		(net "GND")
	)
	(via
		(at -205.74 1.905)
		(size 0.5588)
		(drill 0.254)
		(layers "F.Cu" "B.Cu")
		(net "GND")
	)
	(via
		(at -28.956 8.509)
		(size 0.5588)
		(drill 0.254)
		(layers "F.Cu" "B.Cu")
		(net "GND")
	)
	(via
		(at -22.909243 25.666548)
		(size 0.5588)
		(drill 0.254)
		(layers "F.Cu" "B.Cu")
		(net "GND")
	)
	(via
		(at -155.349999 28.419999)
		(size 0.5588)
		(drill 0.254)
		(layers "F.Cu" "B.Cu")
		(net "GND")
	)
	(via
		(at -381.015979 3.088579)
		(size 0.5588)
		(drill 0.254)
		(layers "F.Cu" "B.Cu")
		(net "GND")
	)
	(via
		(at -218.44 27.305)
		(size 0.5588)
		(drill 0.254)
		(layers "F.Cu" "B.Cu")
		(net "GND")
	)
	(via
		(at -127.635 9.525)
		(size 0.5588)
		(drill 0.254)
		(layers "F.Cu" "B.Cu")
		(net "GND")
	)
	(via
		(at -256.1409 23.2156)
		(size 0.5588)
		(drill 0.254)
		(layers "F.Cu" "B.Cu")
		(net "GND")
	)
	(via
		(at -332.8924 11.85926)
		(size 0.5588)
		(drill 0.254)
		(layers "F.Cu" "B.Cu")
		(net "GND")
	)
	(via
		(at -335.28 -3.683)
		(size 0.5588)
		(drill 0.254)
		(layers "F.Cu" "B.Cu")
		(net "GND")
	)
	(via
		(at -318.450001 45.211601)
		(size 0.5588)
		(drill 0.254)
		(layers "F.Cu" "B.Cu")
		(net "GND")
	)
	(via
		(at -372.539999 37.309999)
		(size 0.5588)
		(drill 0.254)
		(layers "F.Cu" "B.Cu")
		(net "GND")
	)
	(via
		(at -371.269999 23.339999)
		(size 0.5588)
		(drill 0.254)
		(layers "F.Cu" "B.Cu")
		(net "GND")
	)
	(via
		(at -11.938 5.334)
		(size 0.5588)
		(drill 0.254)
		(layers "F.Cu" "B.Cu")
		(net "GND")
	)
	(via
		(at -86.36 -3.175)
		(size 0.5588)
		(drill 0.254)
		(layers "F.Cu" "B.Cu")
		(net "GND")
	)
	(via
		(at -378.889999 29.689999)
		(size 0.5588)
		(drill 0.254)
		(layers "F.Cu" "B.Cu")
		(net "GND")
	)
	(via
		(at -208.915 43.18)
		(size 0.5588)
		(drill 0.254)
		(layers "F.Cu" "B.Cu")
		(net "GND")
	)
	(via
		(at -368.3 22.225)
		(size 0.5588)
		(drill 0.254)
		(layers "F.Cu" "B.Cu")
		(net "GND")
	)
	(via
		(at -253.964557 19.265433)
		(size 0.5588)
		(drill 0.254)
		(layers "F.Cu" "B.Cu")
		(net "GND")
	)
	(via
		(at -371.269999 38.579999)
		(size 0.5588)
		(drill 0.254)
		(layers "F.Cu" "B.Cu")
		(net "GND")
	)
	(via
		(at -2.413 18.034)
		(size 0.5588)
		(drill 0.254)
		(layers "F.Cu" "B.Cu")
		(net "GND")
	)
	(via
		(at -344.805 2.032)
		(size 0.5588)
		(drill 0.254)
		(layers "F.Cu" "B.Cu")
		(net "GND")
	)
	(via
		(at -378.889999 33.499999)
		(size 0.5588)
		(drill 0.254)
		(layers "F.Cu" "B.Cu")
		(net "GND")
	)
	(via
		(at -64.719101 44.488202)
		(size 0.5588)
		(drill 0.254)
		(layers "F.Cu" "B.Cu")
		(net "GND")
	)
	(via
		(at -375.935979 4.358579)
		(size 0.5588)
		(drill 0.254)
		(layers "F.Cu" "B.Cu")
		(net "GND")
	)
	(via
		(at -256.214557 19.303533)
		(size 0.5588)
		(drill 0.254)
		(layers "F.Cu" "B.Cu")
		(net "GND")
	)
	(via
		(at -170.815 5.08)
		(size 0.5588)
		(drill 0.254)
		(layers "F.Cu" "B.Cu")
		(net "GND")
	)
	(via
		(at -117.205999 -1.666001)
		(size 0.5588)
		(drill 0.254)
		(layers "F.Cu" "B.Cu")
		(net "GND")
	)
	(via
		(at 0.762 11.684)
		(size 0.5588)
		(drill 0.254)
		(layers "F.Cu" "B.Cu")
		(net "GND")
	)
	(via
		(at -193.04 33.655)
		(size 0.5588)
		(drill 0.254)
		(layers "F.Cu" "B.Cu")
		(net "GND")
	)
	(via
		(at -86.77688 43.09364)
		(size 0.5588)
		(drill 0.254)
		(layers "F.Cu" "B.Cu")
		(net "GND")
	)
	(via
		(at -151.539999 22.069999)
		(size 0.5588)
		(drill 0.254)
		(layers "F.Cu" "B.Cu")
		(net "GND")
	)
	(via
		(at -368.3 34.925)
		(size 0.5588)
		(drill 0.254)
		(layers "F.Cu" "B.Cu")
		(net "GND")
	)
	(via
		(at -183.515 11.43)
		(size 0.5588)
		(drill 0.254)
		(layers "F.Cu" "B.Cu")
		(net "GND")
	)
	(via
		(at -371.269999 24.609999)
		(size 0.5588)
		(drill 0.254)
		(layers "F.Cu" "B.Cu")
		(net "GND")
	)
	(via
		(at -312.43016 46.50232)
		(size 0.5588)
		(drill 0.254)
		(layers "F.Cu" "B.Cu")
		(net "GND")
	)
	(via
		(at -94.996 11.176)
		(size 0.5588)
		(drill 0.254)
		(layers "F.Cu" "B.Cu")
		(net "GND")
	)
	(via
		(at -302.641 8.636)
		(size 0.5588)
		(drill 0.254)
		(layers "F.Cu" "B.Cu")
		(net "GND")
	)
	(via
		(at -155.349999 34.769999)
		(size 0.5588)
		(drill 0.254)
		(layers "F.Cu" "B.Cu")
		(net "GND")
	)
	(via
		(at -215.265 43.18)
		(size 0.5588)
		(drill 0.254)
		(layers "F.Cu" "B.Cu")
		(net "GND")
	)
	(via
		(at -227.965 -1.27)
		(size 0.5588)
		(drill 0.254)
		(layers "F.Cu" "B.Cu")
		(net "GND")
	)
	(via
		(at -133.985 38.735)
		(size 0.5588)
		(drill 0.254)
		(layers "F.Cu" "B.Cu")
		(net "GND")
	)
	(via
		(at -186.69 1.905)
		(size 0.5588)
		(drill 0.254)
		(layers "F.Cu" "B.Cu")
		(net "GND")
	)
	(via
		(at -31.64586 10.541)
		(size 0.5588)
		(drill 0.254)
		(layers "F.Cu" "B.Cu")
		(net "GND")
	)
	(via
		(at -352.425 44.45)
		(size 0.5588)
		(drill 0.254)
		(layers "F.Cu" "B.Cu")
		(net "GND")
	)
	(via
		(at -18.161 37.084)
		(size 0.5588)
		(drill 0.254)
		(layers "F.Cu" "B.Cu")
		(net "GND")
	)
	(via
		(at -389.905979 5.628579)
		(size 0.5588)
		(drill 0.254)
		(layers "F.Cu" "B.Cu")
		(net "GND")
	)
	(via
		(at -199.39 -3.683)
		(size 0.5588)
		(drill 0.254)
		(layers "F.Cu" "B.Cu")
		(net "GND")
	)
	(via
		(at -341.1728 21.0058)
		(size 0.5588)
		(drill 0.254)
		(layers "F.Cu" "B.Cu")
		(net "GND")
	)
	(via
		(at -322.58 -3.683)
		(size 0.5588)
		(drill 0.254)
		(layers "F.Cu" "B.Cu")
		(net "GND")
	)
	(via
		(at -25.8318 18.7452)
		(size 0.5588)
		(drill 0.254)
		(layers "F.Cu" "B.Cu")
		(net "GND")
	)
	(via
		(at -221.615 43.18)
		(size 0.5588)
		(drill 0.254)
		(layers "F.Cu" "B.Cu")
		(net "GND")
	)
	(via
		(at -372.125979 5.628579)
		(size 0.5588)
		(drill 0.254)
		(layers "F.Cu" "B.Cu")
		(net "GND")
	)
	(via
		(at -137.16 6.35)
		(size 0.5588)
		(drill 0.254)
		(layers "F.Cu" "B.Cu")
		(net "GND")
	)
	(via
		(at -154.079999 27.149999)
		(size 0.5588)
		(drill 0.254)
		(layers "F.Cu" "B.Cu")
		(net "GND")
	)
	(via
		(at -208.915 17.78)
		(size 0.5588)
		(drill 0.254)
		(layers "F.Cu" "B.Cu")
		(net "GND")
	)
	(via
		(at -108.585 -3.175)
		(size 0.5588)
		(drill 0.254)
		(layers "F.Cu" "B.Cu")
		(net "GND")
	)
	(via
		(at -208.915 -1.27)
		(size 0.5588)
		(drill 0.254)
		(layers "F.Cu" "B.Cu")
		(net "GND")
	)
	(via
		(at -336.50936 20.85848)
		(size 0.5588)
		(drill 0.254)
		(layers "F.Cu" "B.Cu")
		(net "GND")
	)
	(via
		(at -121.285 -3.175)
		(size 0.5588)
		(drill 0.254)
		(layers "F.Cu" "B.Cu")
		(net "GND")
	)
	(via
		(at -257.210044 21.815138)
		(size 0.5588)
		(drill 0.254)
		(layers "F.Cu" "B.Cu")
		(net "GND")
	)
	(via
		(at -130.81 22.86)
		(size 0.5588)
		(drill 0.254)
		(layers "F.Cu" "B.Cu")
		(net "GND")
	)
	(via
		(at -382.285979 4.358579)
		(size 0.5588)
		(drill 0.254)
		(layers "F.Cu" "B.Cu")
		(net "GND")
	)
	(via
		(at -234.315 11.43)
		(size 0.5588)
		(drill 0.254)
		(layers "F.Cu" "B.Cu")
		(net "GND")
	)
	(via
		(at -99.06 -3.175)
		(size 0.5588)
		(drill 0.254)
		(layers "F.Cu" "B.Cu")
		(net "GND")
	)
	(via
		(at -137.16 35.56)
		(size 0.5588)
		(drill 0.254)
		(layers "F.Cu" "B.Cu")
		(net "GND")
	)
	(via
		(at -388.635979 3.088579)
		(size 0.5588)
		(drill 0.254)
		(layers "F.Cu" "B.Cu")
		(net "GND")
	)
	(via
		(at -254.960044 14.239319)
		(size 0.5588)
		(drill 0.254)
		(layers "F.Cu" "B.Cu")
		(net "GND")
	)
	(via
		(at -19.685 -3.175)
		(size 0.5588)
		(drill 0.254)
		(layers "F.Cu" "B.Cu")
		(net "GND")
	)
	(via
		(at -115.88496 20.83308)
		(size 0.5588)
		(drill 0.254)
		(layers "F.Cu" "B.Cu")
		(net "GND")
	)
	(via
		(at -338.455 -1.778)
		(size 0.5588)
		(drill 0.254)
		(layers "F.Cu" "B.Cu")
		(net "GND")
	)
	(via
		(at -358.775 44.45)
		(size 0.5588)
		(drill 0.254)
		(layers "F.Cu" "B.Cu")
		(net "GND")
	)
	(via
		(at -221.615 11.43)
		(size 0.5588)
		(drill 0.254)
		(layers "F.Cu" "B.Cu")
		(net "GND")
	)
	(via
		(at -358.648 25.527)
		(size 0.5588)
		(drill 0.254)
		(layers "F.Cu" "B.Cu")
		(net "GND")
	)
	(via
		(at -100.123762 45.992791)
		(size 0.5588)
		(drill 0.254)
		(layers "F.Cu" "B.Cu")
		(net "GND")
	)
	(via
		(at 0.762 8.509)
		(size 0.5588)
		(drill 0.254)
		(layers "F.Cu" "B.Cu")
		(net "GND")
	)
	(via
		(at -305.79568 41.92524)
		(size 0.5588)
		(drill 0.254)
		(layers "F.Cu" "B.Cu")
		(net "GND")
	)
	(via
		(at -285.940599 38.832274)
		(size 0.5588)
		(drill 0.254)
		(layers "F.Cu" "B.Cu")
		(net "GND")
	)
	(via
		(at -368.3 28.575)
		(size 0.5588)
		(drill 0.254)
		(layers "F.Cu" "B.Cu")
		(net "GND")
	)
	(via
		(at -154.079999 42.389999)
		(size 0.5588)
		(drill 0.254)
		(layers "F.Cu" "B.Cu")
		(net "GND")
	)
	(via
		(at -224.79 -3.683)
		(size 0.5588)
		(drill 0.254)
		(layers "F.Cu" "B.Cu")
		(net "GND")
	)
	(via
		(at -377.619999 19.529999)
		(size 0.5588)
		(drill 0.254)
		(layers "F.Cu" "B.Cu")
		(net "GND")
	)
	(via
		(at -372.539999 22.069999)
		(size 0.5588)
		(drill 0.254)
		(layers "F.Cu" "B.Cu")
		(net "GND")
	)
	(via
		(at -321.07124 36.0553)
		(size 0.5588)
		(drill 0.254)
		(layers "F.Cu" "B.Cu")
		(net "GND")
	)
	(via
		(at -112.88776 20.50034)
		(size 0.5588)
		(drill 0.254)
		(layers "F.Cu" "B.Cu")
		(net "GND")
	)
	(via
		(at -297.18 -3.683)
		(size 0.5588)
		(drill 0.254)
		(layers "F.Cu" "B.Cu")
		(net "GND")
	)
	(via
		(at -297.688 2.730602)
		(size 0.5588)
		(drill 0.254)
		(layers "F.Cu" "B.Cu")
		(net "GND")
	)
	(via
		(at -315.82614 46.83887)
		(size 0.5588)
		(drill 0.254)
		(layers "F.Cu" "B.Cu")
		(net "GND")
	)
	(via
		(at -205.74 30.48)
		(size 0.5588)
		(drill 0.254)
		(layers "F.Cu" "B.Cu")
		(net "GND")
	)
	(via
		(at -321.4594 37.96792)
		(size 0.5588)
		(drill 0.254)
		(layers "F.Cu" "B.Cu")
		(net "GND")
	)
	(via
		(at -316.23 5.08)
		(size 0.5588)
		(drill 0.254)
		(layers "F.Cu" "B.Cu")
		(net "GND")
	)
	(via
		(at -177.165 5.08)
		(size 0.5588)
		(drill 0.254)
		(layers "F.Cu" "B.Cu")
		(net "GND")
	)
	(via
		(at -363.601 20.574)
		(size 0.5588)
		(drill 0.254)
		(layers "F.Cu" "B.Cu")
		(net "GND")
	)
	(via
		(at -380.248899 43.024999)
		(size 0.5588)
		(drill 0.254)
		(layers "F.Cu" "B.Cu")
		(net "GND")
	)
	(via
		(at -95.99454 48.82007)
		(size 0.5588)
		(drill 0.254)
		(layers "F.Cu" "B.Cu")
		(net "GND")
	)
	(via
		(at -152.809999 28.419999)
		(size 0.5588)
		(drill 0.254)
		(layers "F.Cu" "B.Cu")
		(net "GND")
	)
	(via
		(at -140.335 -3.175)
		(size 0.5588)
		(drill 0.254)
		(layers "F.Cu" "B.Cu")
		(net "GND")
	)
	(via
		(at -373.809999 28.419999)
		(size 0.5588)
		(drill 0.254)
		(layers "F.Cu" "B.Cu")
		(net "GND")
	)
	(via
		(at -384.825979 5.628579)
		(size 0.5588)
		(drill 0.254)
		(layers "F.Cu" "B.Cu")
		(net "GND")
	)
	(via
		(at -124.46 22.86)
		(size 0.5588)
		(drill 0.254)
		(layers "F.Cu" "B.Cu")
		(net "GND")
	)
	(via
		(at -373.809999 33.499999)
		(size 0.5588)
		(drill 0.254)
		(layers "F.Cu" "B.Cu")
		(net "GND")
	)
	(via
		(at -177.165 11.43)
		(size 0.5588)
		(drill 0.254)
		(layers "F.Cu" "B.Cu")
		(net "GND")
	)
	(via
		(at -376.349999 29.689999)
		(size 0.5588)
		(drill 0.254)
		(layers "F.Cu" "B.Cu")
		(net "GND")
	)
	(via
		(at -307.77688 43.09364)
		(size 0.5588)
		(drill 0.254)
		(layers "F.Cu" "B.Cu")
		(net "GND")
	)
	(via
		(at -90.426835 37.4904)
		(size 0.5588)
		(drill 0.254)
		(layers "F.Cu" "B.Cu")
		(net "GND")
	)
	(via
		(at -150.269999 23.339999)
		(size 0.5588)
		(drill 0.254)
		(layers "F.Cu" "B.Cu")
		(net "GND")
	)
	(via
		(at -186.69 14.605)
		(size 0.5588)
		(drill 0.254)
		(layers "F.Cu" "B.Cu")
		(net "GND")
	)
	(via
		(at -151.539999 36.039999)
		(size 0.5588)
		(drill 0.254)
		(layers "F.Cu" "B.Cu")
		(net "GND")
	)
	(via
		(at -323.4406 39.13632)
		(size 0.5588)
		(drill 0.254)
		(layers "F.Cu" "B.Cu")
		(net "GND")
	)
	(via
		(at -5.3721 21.2344)
		(size 0.5588)
		(drill 0.254)
		(layers "F.Cu" "B.Cu")
		(net "GND")
	)
	(via
		(at -377.619999 22.069999)
		(size 0.5588)
		(drill 0.254)
		(layers "F.Cu" "B.Cu")
		(net "GND")
	)
	(via
		(at -387.365979 3.088579)
		(size 0.5588)
		(drill 0.254)
		(layers "F.Cu" "B.Cu")
		(net "GND")
	)
	(via
		(at -154.079999 30.959999)
		(size 0.5588)
		(drill 0.254)
		(layers "F.Cu" "B.Cu")
		(net "GND")
	)
	(via
		(at -150.269999 29.689999)
		(size 0.5588)
		(drill 0.254)
		(layers "F.Cu" "B.Cu")
		(net "GND")
	)
	(via
		(at -376.349999 23.339999)
		(size 0.5588)
		(drill 0.254)
		(layers "F.Cu" "B.Cu")
		(net "GND")
	)
	(via
		(at -314.41136 46.50232)
		(size 0.5588)
		(drill 0.254)
		(layers "F.Cu" "B.Cu")
		(net "GND")
	)
	(via
		(at -102.235 -3.175)
		(size 0.5588)
		(drill 0.254)
		(layers "F.Cu" "B.Cu")
		(net "GND")
	)
	(via
		(at -323.250001 45.211601)
		(size 0.5588)
		(drill 0.254)
		(layers "F.Cu" "B.Cu")
		(net "GND")
	)
	(via
		(at -373.809999 34.769999)
		(size 0.5588)
		(drill 0.254)
		(layers "F.Cu" "B.Cu")
		(net "GND")
	)
	(via
		(at -365.125 25.4)
		(size 0.5588)
		(drill 0.254)
		(layers "F.Cu" "B.Cu")
		(net "GND")
	)
	(via
		(at -358.775 15.875)
		(size 0.5588)
		(drill 0.254)
		(layers "F.Cu" "B.Cu")
		(net "GND")
	)
	(via
		(at -365.125 44.45)
		(size 0.5588)
		(drill 0.254)
		(layers "F.Cu" "B.Cu")
		(net "GND")
	)
	(via
		(at -208.915 30.48)
		(size 0.5588)
		(drill 0.254)
		(layers "F.Cu" "B.Cu")
		(net "GND")
	)
	(via
		(at -85.344 7.112)
		(size 0.5588)
		(drill 0.254)
		(layers "F.Cu" "B.Cu")
		(net "GND")
	)
	(via
		(at -140.335 38.735)
		(size 0.5588)
		(drill 0.254)
		(layers "F.Cu" "B.Cu")
		(net "GND")
	)
	(via
		(at -64.897 0.127)
		(size 0.5588)
		(drill 0.254)
		(layers "F.Cu" "B.Cu")
		(net "GND")
	)
	(via
		(at -377.205979 5.628579)
		(size 0.5588)
		(drill 0.254)
		(layers "F.Cu" "B.Cu")
		(net "GND")
	)
	(via
		(at -377.205979 4.358579)
		(size 0.5588)
		(drill 0.254)
		(layers "F.Cu" "B.Cu")
		(net "GND")
	)
	(via
		(at -98.171 8.001)
		(size 0.5588)
		(drill 0.254)
		(layers "F.Cu" "B.Cu")
		(net "GND")
	)
	(via
		(at -58.547 0.127)
		(size 0.5588)
		(drill 0.254)
		(layers "F.Cu" "B.Cu")
		(net "GND")
	)
	(via
		(at -166.497 0.127)
		(size 0.5588)
		(drill 0.254)
		(layers "F.Cu" "B.Cu")
		(net "GND")
	)
	(via
		(at -303.53 -3.683)
		(size 0.5588)
		(drill 0.254)
		(layers "F.Cu" "B.Cu")
		(net "GND")
	)
	(via
		(at -374.665979 4.358579)
		(size 0.5588)
		(drill 0.254)
		(layers "F.Cu" "B.Cu")
		(net "GND")
	)
	(via
		(at -246.210044 25.615748)
		(size 0.5588)
		(drill 0.254)
		(layers "F.Cu" "B.Cu")
		(net "GND")
	)
	(via
		(at 0.762 2.159)
		(size 0.5588)
		(drill 0.254)
		(layers "F.Cu" "B.Cu")
		(net "GND")
	)
	(via
		(at -376.349999 38.579999)
		(size 0.5588)
		(drill 0.254)
		(layers "F.Cu" "B.Cu")
		(net "GND")
	)
	(via
		(at -11.938 14.859)
		(size 0.5588)
		(drill 0.254)
		(layers "F.Cu" "B.Cu")
		(net "GND")
	)
	(via
		(at -316.23 11.43)
		(size 0.5588)
		(drill 0.254)
		(layers "F.Cu" "B.Cu")
		(net "GND")
	)
	(via
		(at -344.6018 6.5024)
		(size 0.5588)
		(drill 0.254)
		(layers "F.Cu" "B.Cu")
		(net "GND")
	)
	(via
		(at 0.762 21.209)
		(size 0.5588)
		(drill 0.254)
		(layers "F.Cu" "B.Cu")
		(net "GND")
	)
	(via
		(at -33.858444 22.094538)
		(size 0.5588)
		(drill 0.254)
		(layers "F.Cu" "B.Cu")
		(net "GND")
	)
	(via
		(at -130.81 35.56)
		(size 0.5588)
		(drill 0.254)
		(layers "F.Cu" "B.Cu")
		(net "GND")
	)
	(via
		(at -32.385 -3.175)
		(size 0.5588)
		(drill 0.254)
		(layers "F.Cu" "B.Cu")
		(net "GND")
	)
	(via
		(at -375.935979 3.088579)
		(size 0.5588)
		(drill 0.254)
		(layers "F.Cu" "B.Cu")
		(net "GND")
	)
	(via
		(at -58.148601 26.462459)
		(size 0.5588)
		(drill 0.254)
		(layers "F.Cu" "B.Cu")
		(net "GND")
	)
	(via
		(at -321.250081 39.9669)
		(size 0.5588)
		(drill 0.254)
		(layers "F.Cu" "B.Cu")
		(net "GND")
	)
	(via
		(at -38.735 -3.175)
		(size 0.5588)
		(drill 0.254)
		(layers "F.Cu" "B.Cu")
		(net "GND")
	)
	(via
		(at -234.315 5.08)
		(size 0.5588)
		(drill 0.254)
		(layers "F.Cu" "B.Cu")
		(net "GND")
	)
	(via
		(at -156.619999 32.229999)
		(size 0.5588)
		(drill 0.254)
		(layers "F.Cu" "B.Cu")
		(net "GND")
	)
	(via
		(at -130.81 6.35)
		(size 0.5588)
		(drill 0.254)
		(layers "F.Cu" "B.Cu")
		(net "GND")
	)
	(via
		(at -421.259 7.874)
		(size 0.5588)
		(drill 0.254)
		(layers "F.Cu" "B.Cu")
		(net "GND")
	)
	(via
		(at -243.2758 14.6558)
		(size 0.5588)
		(drill 0.254)
		(layers "F.Cu" "B.Cu")
		(net "GND")
	)
	(via
		(at -378.475979 5.628579)
		(size 0.5588)
		(drill 0.254)
		(layers "F.Cu" "B.Cu")
		(net "GND")
	)
	(via
		(at -313.840602 33.5407)
		(size 0.5588)
		(drill 0.254)
		(layers "F.Cu" "B.Cu")
		(net "GND")
	)
	(via
		(at -224.79 40.513)
		(size 0.5588)
		(drill 0.254)
		(layers "F.Cu" "B.Cu")
		(net "GND")
	)
	(via
		(at -352.3742 33.8328)
		(size 0.5588)
		(drill 0.254)
		(layers "F.Cu" "B.Cu")
		(net "GND")
	)
	(via
		(at -123.551 6.644401)
		(size 0.5588)
		(drill 0.254)
		(layers "F.Cu" "B.Cu")
		(net "GND")
	)
	(via
		(at -299.466 10.287)
		(size 0.5588)
		(drill 0.254)
		(layers "F.Cu" "B.Cu")
		(net "GND")
	)
	(via
		(at -215.265 -1.27)
		(size 0.5588)
		(drill 0.254)
		(layers "F.Cu" "B.Cu")
		(net "GND")
	)
	(via
		(at -196.215 5.08)
		(size 0.5588)
		(drill 0.254)
		(layers "F.Cu" "B.Cu")
		(net "GND")
	)
	(via
		(at -350.52 26.9875)
		(size 0.5588)
		(drill 0.254)
		(layers "F.Cu" "B.Cu")
		(net "GND")
	)
	(via
		(at -4.572 40.259)
		(size 0.5588)
		(drill 0.254)
		(layers "F.Cu" "B.Cu")
		(net "GND")
	)
	(via
		(at -196.215 43.18)
		(size 0.5588)
		(drill 0.254)
		(layers "F.Cu" "B.Cu")
		(net "GND")
	)
	(via
		(at -90.859402 34.7091)
		(size 0.5588)
		(drill 0.254)
		(layers "F.Cu" "B.Cu")
		(net "GND")
	)
	(via
		(at -316.99454 48.82007)
		(size 0.5588)
		(drill 0.254)
		(layers "F.Cu" "B.Cu")
		(net "GND")
	)
	(via
		(at -115.423 6.847601)
		(size 0.5588)
		(drill 0.254)
		(layers "F.Cu" "B.Cu")
		(net "GND")
	)
	(via
		(at -60.350001 34.72942)
		(size 0.5588)
		(drill 0.254)
		(layers "F.Cu" "B.Cu")
		(net "GND")
	)
	(via
		(at -344.805 -1.778)
		(size 0.5588)
		(drill 0.254)
		(layers "F.Cu" "B.Cu")
		(net "GND")
	)
	(via
		(at -155.349999 39.849999)
		(size 0.5588)
		(drill 0.254)
		(layers "F.Cu" "B.Cu")
		(net "GND")
	)
	(via
		(at -373.809999 29.689999)
		(size 0.5588)
		(drill 0.254)
		(layers "F.Cu" "B.Cu")
		(net "GND")
	)
	(via
		(at -73.66 -3.175)
		(size 0.5588)
		(drill 0.254)
		(layers "F.Cu" "B.Cu")
		(net "GND")
	)
	(via
		(at -159.248899 43.024999)
		(size 0.5588)
		(drill 0.254)
		(layers "F.Cu" "B.Cu")
		(net "GND")
	)
	(via
		(at -143.51 0)
		(size 0.5588)
		(drill 0.254)
		(layers "F.Cu" "B.Cu")
		(net "GND")
	)
	(via
		(at -254.858444 22.094538)
		(size 0.5588)
		(drill 0.254)
		(layers "F.Cu" "B.Cu")
		(net "GND")
	)
	(via
		(at -87.85 45.211601)
		(size 0.5588)
		(drill 0.254)
		(layers "F.Cu" "B.Cu")
		(net "GND")
	)
	(via
		(at -0.635 -3.175)
		(size 0.5588)
		(drill 0.254)
		(layers "F.Cu" "B.Cu")
		(net "GND")
	)
	(via
		(at -346.3925 26.9875)
		(size 0.5588)
		(drill 0.254)
		(layers "F.Cu" "B.Cu")
		(net "GND")
	)
	(via
		(at -156.464 9.525)
		(size 0.5588)
		(drill 0.254)
		(layers "F.Cu" "B.Cu")
		(net "GND")
	)
	(via
		(at -372.539999 36.039999)
		(size 0.5588)
		(drill 0.254)
		(layers "F.Cu" "B.Cu")
		(net "GND")
	)
	(via
		(at -8.763 5.334)
		(size 0.5588)
		(drill 0.254)
		(layers "F.Cu" "B.Cu")
		(net "GND")
	)
	(via
		(at -15.113 14.859)
		(size 0.5588)
		(drill 0.254)
		(layers "F.Cu" "B.Cu")
		(net "GND")
	)
	(via
		(at -257.26644 10.4775)
		(size 0.5588)
		(drill 0.254)
		(layers "F.Cu" "B.Cu")
		(net "GND")
	)
	(via
		(at -85.344 3.937)
		(size 0.5588)
		(drill 0.254)
		(layers "F.Cu" "B.Cu")
		(net "GND")
	)
	(via
		(at -64.940599 38.832274)
		(size 0.5588)
		(drill 0.254)
		(layers "F.Cu" "B.Cu")
		(net "GND")
	)
	(via
		(at -243.205 1.905)
		(size 0.5588)
		(drill 0.254)
		(layers "F.Cu" "B.Cu")
		(net "GND")
	)
	(via
		(at -154.079999 32.229999)
		(size 0.5588)
		(drill 0.254)
		(layers "F.Cu" "B.Cu")
		(net "GND")
	)
	(via
		(at -19.431 2.159)
		(size 0.5588)
		(drill 0.254)
		(layers "F.Cu" "B.Cu")
		(net "GND")
	)
	(via
		(at -150.269999 39.849999)
		(size 0.5588)
		(drill 0.254)
		(layers "F.Cu" "B.Cu")
		(net "GND")
	)
	(via
		(at -375.935979 5.628579)
		(size 0.5588)
		(drill 0.254)
		(layers "F.Cu" "B.Cu")
		(net "GND")
	)
	(via
		(at -316.23 -3.683)
		(size 0.5588)
		(drill 0.254)
		(layers "F.Cu" "B.Cu")
		(net "GND")
	)
	(via
		(at -281.026423 29.50464)
		(size 0.5588)
		(drill 0.254)
		(layers "F.Cu" "B.Cu")
		(net "GND")
	)
	(via
		(at -19.431 8.509)
		(size 0.5588)
		(drill 0.254)
		(layers "F.Cu" "B.Cu")
		(net "GND")
	)
	(via
		(at -278.950001 34.72942)
		(size 0.5588)
		(drill 0.254)
		(layers "F.Cu" "B.Cu")
		(net "GND")
	)
	(via
		(at -2.413 30.48)
		(size 0.5588)
		(drill 0.254)
		(layers "F.Cu" "B.Cu")
		(net "GND")
	)
	(via
		(at -284.48 -3.683)
		(size 0.5588)
		(drill 0.254)
		(layers "F.Cu" "B.Cu")
		(net "GND")
	)
	(via
		(at -60.026423 31.48584)
		(size 0.5588)
		(drill 0.254)
		(layers "F.Cu" "B.Cu")
		(net "GND")
	)
	(via
		(at -373.395979 5.628579)
		(size 0.5588)
		(drill 0.254)
		(layers "F.Cu" "B.Cu")
		(net "GND")
	)
	(via
		(at -130.81 41.91)
		(size 0.5588)
		(drill 0.254)
		(layers "F.Cu" "B.Cu")
		(net "GND")
	)
	(via
		(at -355.6 19.05)
		(size 0.5588)
		(drill 0.254)
		(layers "F.Cu" "B.Cu")
		(net "GND")
	)
	(via
		(at 0.762 14.859)
		(size 0.5588)
		(drill 0.254)
		(layers "F.Cu" "B.Cu")
		(net "GND")
	)
	(via
		(at -18.161 40.259)
		(size 0.5588)
		(drill 0.254)
		(layers "F.Cu" "B.Cu")
		(net "GND")
	)
	(via
		(at -281.026423 31.48584)
		(size 0.5588)
		(drill 0.254)
		(layers "F.Cu" "B.Cu")
		(net "GND")
	)
	(via
		(at -88.392 8.001)
		(size 0.5588)
		(drill 0.254)
		(layers "F.Cu" "B.Cu")
		(net "GND")
	)
	(via
		(at -18.161 33.909)
		(size 0.5588)
		(drill 0.254)
		(layers "F.Cu" "B.Cu")
		(net "GND")
	)
	(via
		(at -377.619999 30.959999)
		(size 0.5588)
		(drill 0.254)
		(layers "F.Cu" "B.Cu")
		(net "GND")
	)
	(via
		(at -355.6254 33.4137)
		(size 0.5588)
		(drill 0.254)
		(layers "F.Cu" "B.Cu")
		(net "GND")
	)
	(via
		(at -32.964557 19.303533)
		(size 0.5588)
		(drill 0.254)
		(layers "F.Cu" "B.Cu")
		(net "GND")
	)
	(via
		(at -257.8554 18.8214)
		(size 0.5588)
		(drill 0.254)
		(layers "F.Cu" "B.Cu")
		(net "GND")
	)
	(via
		(at -378.889999 34.769999)
		(size 0.5588)
		(drill 0.254)
		(layers "F.Cu" "B.Cu")
		(net "GND")
	)
	(via
		(at -152.809999 23.339999)
		(size 0.5588)
		(drill 0.254)
		(layers "F.Cu" "B.Cu")
		(net "GND")
	)
	(via
		(at -32.1564 19.15414)
		(size 0.5588)
		(drill 0.254)
		(layers "F.Cu" "B.Cu")
		(net "GND")
	)
	(via
		(at -371.269999 39.849999)
		(size 0.5588)
		(drill 0.254)
		(layers "F.Cu" "B.Cu")
		(net "GND")
	)
	(via
		(at -360.68 -3.683)
		(size 0.5588)
		(drill 0.254)
		(layers "F.Cu" "B.Cu")
		(net "GND")
	)
	(via
		(at -15.113 37.719)
		(size 0.5588)
		(drill 0.254)
		(layers "F.Cu" "B.Cu")
		(net "GND")
	)
	(via
		(at -347.98 -3.683)
		(size 0.5588)
		(drill 0.254)
		(layers "F.Cu" "B.Cu")
		(net "GND")
	)
	(via
		(at -302.514 4.635602)
		(size 0.5588)
		(drill 0.254)
		(layers "F.Cu" "B.Cu")
		(net "GND")
	)
	(via
		(at -312.43016 47.67072)
		(size 0.5588)
		(drill 0.254)
		(layers "F.Cu" "B.Cu")
		(net "GND")
	)
	(via
		(at -321.037054 37.270789)
		(size 0.5588)
		(drill 0.254)
		(layers "F.Cu" "B.Cu")
		(net "GND")
	)
	(via
		(at -286.150002 37.58946)
		(size 0.5588)
		(drill 0.254)
		(layers "F.Cu" "B.Cu")
		(net "GND")
	)
	(via
		(at -156.619999 41.119999)
		(size 0.5588)
		(drill 0.254)
		(layers "F.Cu" "B.Cu")
		(net "GND")
	)
	(via
		(at -70.485 -3.175)
		(size 0.5588)
		(drill 0.254)
		(layers "F.Cu" "B.Cu")
		(net "GND")
	)
	(via
		(at -285.7246 43.345202)
		(size 0.5588)
		(drill 0.254)
		(layers "F.Cu" "B.Cu")
		(net "GND")
	)
	(via
		(at -112.268 7.48792)
		(size 0.5588)
		(drill 0.254)
		(layers "F.Cu" "B.Cu")
		(net "GND")
	)
	(via
		(at -98.055854 37.270789)
		(size 0.5588)
		(drill 0.254)
		(layers "F.Cu" "B.Cu")
		(net "GND")
	)
	(via
		(at -361.95 41.275)
		(size 0.5588)
		(drill 0.254)
		(layers "F.Cu" "B.Cu")
		(net "GND")
	)
	(via
		(at -234.315 43.18)
		(size 0.5588)
		(drill 0.254)
		(layers "F.Cu" "B.Cu")
		(net "GND")
	)
	(via
		(at -355.6 41.275)
		(size 0.5588)
		(drill 0.254)
		(layers "F.Cu" "B.Cu")
		(net "GND")
	)
	(via
		(at -150.269999 28.419999)
		(size 0.5588)
		(drill 0.254)
		(layers "F.Cu" "B.Cu")
		(net "GND")
	)
	(via
		(at -88.392 14.478)
		(size 0.5588)
		(drill 0.254)
		(layers "F.Cu" "B.Cu")
		(net "GND")
	)
	(via
		(at -11.938 8.509)
		(size 0.5588)
		(drill 0.254)
		(layers "F.Cu" "B.Cu")
		(net "GND")
	)
	(via
		(at -152.809999 39.849999)
		(size 0.5588)
		(drill 0.254)
		(layers "F.Cu" "B.Cu")
		(net "GND")
	)
	(via
		(at -84.79568 41.92524)
		(size 0.5588)
		(drill 0.254)
		(layers "F.Cu" "B.Cu")
		(net "GND")
	)
	(via
		(at -10.922 37.084)
		(size 0.5588)
		(drill 0.254)
		(layers "F.Cu" "B.Cu")
		(net "GND")
	)
	(via
		(at -193.04 20.955)
		(size 0.5588)
		(drill 0.254)
		(layers "F.Cu" "B.Cu")
		(net "GND")
	)
	(via
		(at -311.426835 37.4904)
		(size 0.5588)
		(drill 0.254)
		(layers "F.Cu" "B.Cu")
		(net "GND")
	)
	(via
		(at -249.555 -3.683)
		(size 0.5588)
		(drill 0.254)
		(layers "F.Cu" "B.Cu")
		(net "GND")
	)
	(via
		(at -323.650082 39.9669)
		(size 0.5588)
		(drill 0.254)
		(layers "F.Cu" "B.Cu")
		(net "GND")
	)
	(via
		(at -376.349999 34.769999)
		(size 0.5588)
		(drill 0.254)
		(layers "F.Cu" "B.Cu")
		(net "GND")
	)
	(via
		(at -341.63 0.127)
		(size 0.5588)
		(drill 0.254)
		(layers "F.Cu" "B.Cu")
		(net "GND")
	)
	(via
		(at -227.965 43.18)
		(size 0.5588)
		(drill 0.254)
		(layers "F.Cu" "B.Cu")
		(net "GND")
	)
	(via
		(at -360.553 4.572)
		(size 0.5588)
		(drill 0.254)
		(layers "F.Cu" "B.Cu")
		(net "GND")
	)
	(via
		(at -378.475979 4.358579)
		(size 0.5588)
		(drill 0.254)
		(layers "F.Cu" "B.Cu")
		(net "GND")
	)
	(via
		(at -137.16 16.51)
		(size 0.5588)
		(drill 0.254)
		(layers "F.Cu" "B.Cu")
		(net "GND")
	)
	(via
		(at -159.248899 22.704999)
		(size 0.5588)
		(drill 0.254)
		(layers "F.Cu" "B.Cu")
		(net "GND")
	)
	(via
		(at -156.464 -3.683)
		(size 0.5588)
		(drill 0.254)
		(layers "F.Cu" "B.Cu")
		(net "GND")
	)
	(via
		(at -205.74 36.83)
		(size 0.5588)
		(drill 0.254)
		(layers "F.Cu" "B.Cu")
		(net "GND")
	)
	(via
		(at -372.539999 41.119999)
		(size 0.5588)
		(drill 0.254)
		(layers "F.Cu" "B.Cu")
		(net "GND")
	)
	(via
		(at -127.635 3.175)
		(size 0.5588)
		(drill 0.254)
		(layers "F.Cu" "B.Cu")
		(net "GND")
	)
	(via
		(at -13.335 -3.175)
		(size 0.5588)
		(drill 0.254)
		(layers "F.Cu" "B.Cu")
		(net "GND")
	)
	(via
		(at -243.909243 25.666548)
		(size 0.5588)
		(drill 0.254)
		(layers "F.Cu" "B.Cu")
		(net "GND")
	)
	(via
		(at -208.915 11.43)
		(size 0.5588)
		(drill 0.254)
		(layers "F.Cu" "B.Cu")
		(net "GND")
	)
	(via
		(at -102.650082 39.9669)
		(size 0.5588)
		(drill 0.254)
		(layers "F.Cu" "B.Cu")
		(net "GND")
	)
	(via
		(at -28.956 5.334)
		(size 0.5588)
		(drill 0.254)
		(layers "F.Cu" "B.Cu")
		(net "GND")
	)
	(via
		(at -140.335 9.525)
		(size 0.5588)
		(drill 0.254)
		(layers "F.Cu" "B.Cu")
		(net "GND")
	)
	(via
		(at -378.889999 28.419999)
		(size 0.5588)
		(drill 0.254)
		(layers "F.Cu" "B.Cu")
		(net "GND")
	)
	(via
		(at -199.39 17.78)
		(size 0.5588)
		(drill 0.254)
		(layers "F.Cu" "B.Cu")
		(net "GND")
	)
	(via
		(at -227.965 17.78)
		(size 0.5588)
		(drill 0.254)
		(layers "F.Cu" "B.Cu")
		(net "GND")
	)
	(via
		(at -243.205 -3.683)
		(size 0.5588)
		(drill 0.254)
		(layers "F.Cu" "B.Cu")
		(net "GND")
	)
	(via
		(at -375.079999 37.309999)
		(size 0.5588)
		(drill 0.254)
		(layers "F.Cu" "B.Cu")
		(net "GND")
	)
	(via
		(at -60.026423 29.50464)
		(size 0.5588)
		(drill 0.254)
		(layers "F.Cu" "B.Cu")
		(net "GND")
	)
	(via
		(at -57.4348 44.488202)
		(size 0.5588)
		(drill 0.254)
		(layers "F.Cu" "B.Cu")
		(net "GND")
	)
	(via
		(at -378.889999 24.609999)
		(size 0.5588)
		(drill 0.254)
		(layers "F.Cu" "B.Cu")
		(net "GND")
	)
	(via
		(at -5.588 11.684)
		(size 0.5588)
		(drill 0.254)
		(layers "F.Cu" "B.Cu")
		(net "GND")
	)
	(via
		(at -140.335 3.175)
		(size 0.5588)
		(drill 0.254)
		(layers "F.Cu" "B.Cu")
		(net "GND")
	)
	(via
		(at -25.781 8.509)
		(size 0.5588)
		(drill 0.254)
		(layers "F.Cu" "B.Cu")
		(net "GND")
	)
	(via
		(at -354.33 26.9875)
		(size 0.5588)
		(drill 0.254)
		(layers "F.Cu" "B.Cu")
		(net "GND")
	)
	(via
		(at -373.809999 38.579999)
		(size 0.5588)
		(drill 0.254)
		(layers "F.Cu" "B.Cu")
		(net "GND")
	)
	(via
		(at -350.8375 20.955)
		(size 0.5588)
		(drill 0.254)
		(layers "F.Cu" "B.Cu")
		(net "GND")
	)
	(via
		(at -100.037054 37.270789)
		(size 0.5588)
		(drill 0.254)
		(layers "F.Cu" "B.Cu")
		(net "GND")
	)
	(via
		(at -290.83 -3.683)
		(size 0.5588)
		(drill 0.254)
		(layers "F.Cu" "B.Cu")
		(net "GND")
	)
	(via
		(at -150.269999 38.579999)
		(size 0.5588)
		(drill 0.254)
		(layers "F.Cu" "B.Cu")
		(net "GND")
	)
	(via
		(at -283.959399 38.832274)
		(size 0.5588)
		(drill 0.254)
		(layers "F.Cu" "B.Cu")
		(net "GND")
	)
	(via
		(at -137.16 0)
		(size 0.5588)
		(drill 0.254)
		(layers "F.Cu" "B.Cu")
		(net "GND")
	)
	(via
		(at -8.763 8.509)
		(size 0.5588)
		(drill 0.254)
		(layers "F.Cu" "B.Cu")
		(net "GND")
	)
	(via
		(at -352.425 38.1)
		(size 0.5588)
		(drill 0.254)
		(layers "F.Cu" "B.Cu")
		(net "GND")
	)
	(via
		(at -32.131 5.334)
		(size 0.5588)
		(drill 0.254)
		(layers "F.Cu" "B.Cu")
		(net "GND")
	)
	(via
		(at -212.09 14.605)
		(size 0.5588)
		(drill 0.254)
		(layers "F.Cu" "B.Cu")
		(net "GND")
	)
	(via
		(at -284.5816 32.766)
		(size 0.5588)
		(drill 0.254)
		(layers "F.Cu" "B.Cu")
		(net "GND")
	)
	(via
		(at -332.105 -1.778)
		(size 0.5588)
		(drill 0.254)
		(layers "F.Cu" "B.Cu")
		(net "GND")
	)
	(via
		(at 0.762 27.559)
		(size 0.5588)
		(drill 0.254)
		(layers "F.Cu" "B.Cu")
		(net "GND")
	)
	(via
		(at -186.69 -3.683)
		(size 0.5588)
		(drill 0.254)
		(layers "F.Cu" "B.Cu")
		(net "GND")
	)
	(via
		(at -100.059401 47.227995)
		(size 0.5588)
		(drill 0.254)
		(layers "F.Cu" "B.Cu")
		(net "GND")
	)
	(via
		(at -371.269999 29.689999)
		(size 0.5588)
		(drill 0.254)
		(layers "F.Cu" "B.Cu")
		(net "GND")
	)
	(via
		(at -354.33 0.127)
		(size 0.5588)
		(drill 0.254)
		(layers "F.Cu" "B.Cu")
		(net "GND")
	)
	(via
		(at -348.9452 13.4366)
		(size 0.5588)
		(drill 0.254)
		(layers "F.Cu" "B.Cu")
		(net "GND")
	)
	(via
		(at -377.619999 25.879999)
		(size 0.5588)
		(drill 0.254)
		(layers "F.Cu" "B.Cu")
		(net "GND")
	)
	(via
		(at -309.88 -3.683)
		(size 0.5588)
		(drill 0.254)
		(layers "F.Cu" "B.Cu")
		(net "GND")
	)
	(via
		(at -88.392 11.176)
		(size 0.5588)
		(drill 0.254)
		(layers "F.Cu" "B.Cu")
		(net "GND")
	)
	(via
		(at -375.079999 32.229999)
		(size 0.5588)
		(drill 0.254)
		(layers "F.Cu" "B.Cu")
		(net "GND")
	)
	(via
		(at -154.079999 25.879999)
		(size 0.5588)
		(drill 0.254)
		(layers "F.Cu" "B.Cu")
		(net "GND")
	)
	(via
		(at -133.985 -3.175)
		(size 0.5588)
		(drill 0.254)
		(layers "F.Cu" "B.Cu")
		(net "GND")
	)
	(via
		(at -156.619999 19.529999)
		(size 0.5588)
		(drill 0.254)
		(layers "F.Cu" "B.Cu")
		(net "GND")
	)
	(via
		(at -221.615 17.78)
		(size 0.5588)
		(drill 0.254)
		(layers "F.Cu" "B.Cu")
		(net "GND")
	)
	(via
		(at -90.25 45.211601)
		(size 0.5588)
		(drill 0.254)
		(layers "F.Cu" "B.Cu")
		(net "GND")
	)
	(via
		(at -2.413 11.684)
		(size 0.5588)
		(drill 0.254)
		(layers "F.Cu" "B.Cu")
		(net "GND")
	)
	(via
		(at -377.619999 27.149999)
		(size 0.5588)
		(drill 0.254)
		(layers "F.Cu" "B.Cu")
		(net "GND")
	)
	(via
		(at -151.539999 25.879999)
		(size 0.5588)
		(drill 0.254)
		(layers "F.Cu" "B.Cu")
		(net "GND")
	)
	(via
		(at -285.719101 44.488202)
		(size 0.5588)
		(drill 0.254)
		(layers "F.Cu" "B.Cu")
		(net "GND")
	)
	(via
		(at -57.785 -3.175)
		(size 0.5588)
		(drill 0.254)
		(layers "F.Cu" "B.Cu")
		(net "GND")
	)
	(via
		(at -215.265 17.78)
		(size 0.5588)
		(drill 0.254)
		(layers "F.Cu" "B.Cu")
		(net "GND")
	)
	(via
		(at -22.2758 14.6558)
		(size 0.5588)
		(drill 0.254)
		(layers "F.Cu" "B.Cu")
		(net "GND")
	)
	(via
		(at -196.215 11.43)
		(size 0.5588)
		(drill 0.254)
		(layers "F.Cu" "B.Cu")
		(net "GND")
	)
	(via
		(at -157.889999 23.339999)
		(size 0.5588)
		(drill 0.254)
		(layers "F.Cu" "B.Cu")
		(net "GND")
	)
	(via
		(at -387.187201 31.841201)
		(size 0.5588)
		(drill 0.254)
		(layers "F.Cu" "B.Cu")
		(net "GND")
	)
	(via
		(at -5.588 18.034)
		(size 0.5588)
		(drill 0.254)
		(layers "F.Cu" "B.Cu")
		(net "GND")
	)
	(via
		(at -97.450001 45.211601)
		(size 0.5588)
		(drill 0.254)
		(layers "F.Cu" "B.Cu")
		(net "GND")
	)
	(via
		(at -420.624 34.29)
		(size 0.5588)
		(drill 0.254)
		(layers "F.Cu" "B.Cu")
		(net "GND")
	)
	(via
		(at -360.9975 20.6375)
		(size 0.5588)
		(drill 0.254)
		(layers "F.Cu" "B.Cu")
		(net "GND")
	)
	(via
		(at -152.809999 24.609999)
		(size 0.5588)
		(drill 0.254)
		(layers "F.Cu" "B.Cu")
		(net "GND")
	)
	(via
		(at -35.214557 19.303533)
		(size 0.5588)
		(drill 0.254)
		(layers "F.Cu" "B.Cu")
		(net "GND")
	)
	(via
		(at -36.9951 25.5397)
		(size 0.5588)
		(drill 0.254)
		(layers "F.Cu" "B.Cu")
		(net "GND")
	)
	(via
		(at -2.413 2.159)
		(size 0.5588)
		(drill 0.254)
		(layers "F.Cu" "B.Cu")
		(net "GND")
	)
	(via
		(at -202.565 17.78)
		(size 0.5588)
		(drill 0.254)
		(layers "F.Cu" "B.Cu")
		(net "GND")
	)
	(via
		(at -146.685 32.385)
		(size 0.5588)
		(drill 0.254)
		(layers "F.Cu" "B.Cu")
		(net "GND")
	)
	(via
		(at -151.539999 27.149999)
		(size 0.5588)
		(drill 0.254)
		(layers "F.Cu" "B.Cu")
		(net "GND")
	)
	(via
		(at -364.49 -0.254)
		(size 0.5588)
		(drill 0.254)
		(layers "F.Cu" "B.Cu")
		(net "GND")
	)
	(via
		(at -283.750001 37.61486)
		(size 0.5588)
		(drill 0.254)
		(layers "F.Cu" "B.Cu")
		(net "GND")
	)
	(via
		(at -231.14 27.305)
		(size 0.5588)
		(drill 0.254)
		(layers "F.Cu" "B.Cu")
		(net "GND")
	)
	(via
		(at -11.938 2.159)
		(size 0.5588)
		(drill 0.254)
		(layers "F.Cu" "B.Cu")
		(net "GND")
	)
	(via
		(at -205.74 43.18)
		(size 0.5588)
		(drill 0.254)
		(layers "F.Cu" "B.Cu")
		(net "GND")
	)
	(via
		(at -377.619999 37.309999)
		(size 0.5588)
		(drill 0.254)
		(layers "F.Cu" "B.Cu")
		(net "GND")
	)
	(via
		(at -282.194823 29.50464)
		(size 0.5588)
		(drill 0.254)
		(layers "F.Cu" "B.Cu")
		(net "GND")
	)
	(via
		(at -183.515 5.08)
		(size 0.5588)
		(drill 0.254)
		(layers "F.Cu" "B.Cu")
		(net "GND")
	)
	(via
		(at -253.989957 23.039423)
		(size 0.5588)
		(drill 0.254)
		(layers "F.Cu" "B.Cu")
		(net "GND")
	)
	(via
		(at -98.171 14.351)
		(size 0.5588)
		(drill 0.254)
		(layers "F.Cu" "B.Cu")
		(net "GND")
	)
	(via
		(at -15.113 8.509)
		(size 0.5588)
		(drill 0.254)
		(layers "F.Cu" "B.Cu")
		(net "GND")
	)
	(via
		(at -199.39 14.605)
		(size 0.5588)
		(drill 0.254)
		(layers "F.Cu" "B.Cu")
		(net "GND")
	)
	(via
		(at -377.619999 20.799999)
		(size 0.5588)
		(drill 0.254)
		(layers "F.Cu" "B.Cu")
		(net "GND")
	)
	(via
		(at -127.635 26.035)
		(size 0.5588)
		(drill 0.254)
		(layers "F.Cu" "B.Cu")
		(net "GND")
	)
	(via
		(at -13.843 -0.381)
		(size 0.5588)
		(drill 0.254)
		(layers "F.Cu" "B.Cu")
		(net "GND")
	)
	(via
		(at -102.250001 45.211601)
		(size 0.5588)
		(drill 0.254)
		(layers "F.Cu" "B.Cu")
		(net "GND")
	)
	(via
		(at -35.56 -3.175)
		(size 0.5588)
		(drill 0.254)
		(layers "F.Cu" "B.Cu")
		(net "GND")
	)
	(via
		(at -227.965 5.08)
		(size 0.5588)
		(drill 0.254)
		(layers "F.Cu" "B.Cu")
		(net "GND")
	)
	(via
		(at -10.795 44.069)
		(size 0.5588)
		(drill 0.254)
		(layers "F.Cu" "B.Cu")
		(net "GND")
	)
	(via
		(at -212.217 -3.683)
		(size 0.5588)
		(drill 0.254)
		(layers "F.Cu" "B.Cu")
		(net "GND")
	)
	(via
		(at -380.248899 31.594999)
		(size 0.5588)
		(drill 0.254)
		(layers "F.Cu" "B.Cu")
		(net "GND")
	)
	(via
		(at -355.6 28.575)
		(size 0.5588)
		(drill 0.254)
		(layers "F.Cu" "B.Cu")
		(net "GND")
	)
	(via
		(at -231.14 20.955)
		(size 0.5588)
		(drill 0.254)
		(layers "F.Cu" "B.Cu")
		(net "GND")
	)
	(via
		(at -173.99 1.905)
		(size 0.5588)
		(drill 0.254)
		(layers "F.Cu" "B.Cu")
		(net "GND")
	)
	(via
		(at -383.555979 4.358579)
		(size 0.5588)
		(drill 0.254)
		(layers "F.Cu" "B.Cu")
		(net "GND")
	)
	(via
		(at -205.74 33.655)
		(size 0.5588)
		(drill 0.254)
		(layers "F.Cu" "B.Cu")
		(net "GND")
	)
	(via
		(at -166.497 3.175)
		(size 0.5588)
		(drill 0.254)
		(layers "F.Cu" "B.Cu")
		(net "GND")
	)
	(via
		(at -372.539999 32.229999)
		(size 0.5588)
		(drill 0.254)
		(layers "F.Cu" "B.Cu")
		(net "GND")
	)
	(via
		(at -61.722 6.477)
		(size 0.5588)
		(drill 0.254)
		(layers "F.Cu" "B.Cu")
		(net "GND")
	)
	(via
		(at -143.51 35.56)
		(size 0.5588)
		(drill 0.254)
		(layers "F.Cu" "B.Cu")
		(net "GND")
	)
	(via
		(at -297.561 5.524602)
		(size 0.5588)
		(drill 0.254)
		(layers "F.Cu" "B.Cu")
		(net "GND")
	)
	(via
		(at -154.079999 37.309999)
		(size 0.5588)
		(drill 0.254)
		(layers "F.Cu" "B.Cu")
		(net "GND")
	)
	(via
		(at -281.350001 37.61486)
		(size 0.5588)
		(drill 0.254)
		(layers "F.Cu" "B.Cu")
		(net "GND")
	)
	(via
		(at -8.763 2.159)
		(size 0.5588)
		(drill 0.254)
		(layers "F.Cu" "B.Cu")
		(net "GND")
	)
	(via
		(at -62.959399 38.832274)
		(size 0.5588)
		(drill 0.254)
		(layers "F.Cu" "B.Cu")
		(net "GND")
	)
	(segment
		(start -419.618945 25.633944)
		(end -418.846 24.860999)
		(width 0.381)
		(layer "In1.Cu")
		(net "GND")
	)
	(segment
		(start -201.607001 35.110001)
		(end -200.834056 35.882946)
		(width 0.381)
		(layer "In1.Cu")
		(net "GND")
	)
	(segment
		(start -199.4408 25.307399)
		(end -198.44335 24.309949)
		(width 0.381)
		(layer "In1.Cu")
		(net "GND")
	)
	(segment
		(start -200.43825 26.30485)
		(end -199.4408 25.307399)
		(width 0.381)
		(layer "In1.Cu")
		(net "GND")
	)
	(segment
		(start -199.4408 25.307399)
		(end -198.44335 26.30485)
		(width 0.381)
		(layer "In1.Cu")
		(net "GND")
	)
	(segment
		(start -200.43825 24.309949)
		(end -199.4408 25.307399)
		(width 0.381)
		(layer "In1.Cu")
		(net "GND")
	)
	(segment
		(start -201.607001 35.110001)
		(end -200.834056 34.337056)
		(width 0.381)
		(layer "In1.Cu")
		(net "GND")
	)
	(segment
		(start -418.846 24.860999)
		(end -418.073055 25.633944)
		(width 0.381)
		(layer "In1.Cu")
		(net "GND")
	)
	(segment
		(start -205.93825 26.30485)
		(end -204.940799 25.307399)
		(width 0.381)
		(layer "In1.Cu")
		(net "GND")
	)
	(segment
		(start -202.379946 35.882946)
		(end -201.607001 35.110001)
		(width 0.381)
		(layer "In1.Cu")
		(net "GND")
	)
	(segment
		(start -205.93825 24.309949)
		(end -204.940799 25.307399)
		(width 0.381)
		(layer "In1.Cu")
		(net "GND")
	)
	(segment
		(start -204.940799 25.307399)
		(end -203.943349 24.309949)
		(width 0.381)
		(layer "In1.Cu")
		(net "GND")
	)
	(segment
		(start -204.940799 25.307399)
		(end -203.943349 26.30485)
		(width 0.381)
		(layer "In1.Cu")
		(net "GND")
	)
	(segment
		(start -202.379946 34.337056)
		(end -201.607001 35.110001)
		(width 0.381)
		(layer "In1.Cu")
		(net "GND")
	)
	(segment
		(start -419.618945 24.088054)
		(end -418.846 24.860999)
		(width 0.381)
		(layer "In1.Cu")
		(net "GND")
	)
	(segment
		(start -418.846 24.860999)
		(end -418.073055 24.088054)
		(width 0.381)
		(layer "In1.Cu")
		(net "GND")
	)
	(segment
		(start -205.93825 24.309949)
		(end -204.940799 25.307399)
		(width 0.381)
		(layer "In2.Cu")
		(net "GND")
	)
	(segment
		(start -201.607001 35.110001)
		(end -200.834056 35.882946)
		(width 0.381)
		(layer "In2.Cu")
		(net "GND")
	)
	(segment
		(start -199.4408 25.307399)
		(end -198.44335 26.30485)
		(width 0.381)
		(layer "In2.Cu")
		(net "GND")
	)
	(segment
		(start -205.93825 26.30485)
		(end -204.940799 25.307399)
		(width 0.381)
		(layer "In2.Cu")
		(net "GND")
	)
	(segment
		(start -200.43825 24.309949)
		(end -199.4408 25.307399)
		(width 0.381)
		(layer "In2.Cu")
		(net "GND")
	)
	(segment
		(start -202.379946 35.882946)
		(end -201.607001 35.110001)
		(width 0.381)
		(layer "In2.Cu")
		(net "GND")
	)
	(segment
		(start -204.940799 25.307399)
		(end -203.943349 26.30485)
		(width 0.381)
		(layer "In2.Cu")
		(net "GND")
	)
	(segment
		(start -200.43825 26.30485)
		(end -199.4408 25.307399)
		(width 0.381)
		(layer "In2.Cu")
		(net "GND")
	)
	(segment
		(start -201.607001 35.110001)
		(end -200.834056 34.337056)
		(width 0.381)
		(layer "In2.Cu")
		(net "GND")
	)
	(segment
		(start -199.4408 25.307399)
		(end -198.44335 24.309949)
		(width 0.381)
		(layer "In2.Cu")
		(net "GND")
	)
	(segment
		(start -202.379946 34.337056)
		(end -201.607001 35.110001)
		(width 0.381)
		(layer "In2.Cu")
		(net "GND")
	)
	(segment
		(start -204.940799 25.307399)
		(end -203.943349 24.309949)
		(width 0.381)
		(layer "In2.Cu")
		(net "GND")
	)
	(segment
		(start -418.846 24.860999)
		(end -418.073055 24.088054)
		(width 0.381)
		(layer "In4.Cu")
		(net "GND")
	)
	(segment
		(start -419.618945 24.088054)
		(end -418.846 24.860999)
		(width 0.381)
		(layer "In4.Cu")
		(net "GND")
	)
	(segment
		(start -418.846 24.860999)
		(end -418.073055 25.633944)
		(width 0.381)
		(layer "In4.Cu")
		(net "GND")
	)
	(segment
		(start -419.618945 25.633944)
		(end -418.846 24.860999)
		(width 0.381)
		(layer "In4.Cu")
		(net "GND")
	)
	(segment
		(start -201.607001 35.110001)
		(end -200.834056 34.337056)
		(width 0.381)
		(layer "In6.Cu")
		(net "GND")
	)
	(segment
		(start -418.846 24.860999)
		(end -418.073055 24.088054)
		(width 0.381)
		(layer "In6.Cu")
		(net "GND")
	)
	(segment
		(start -200.43825 26.30485)
		(end -199.4408 25.307399)
		(width 0.381)
		(layer "In6.Cu")
		(net "GND")
	)
	(segment
		(start -202.379946 34.337056)
		(end -201.607001 35.110001)
		(width 0.381)
		(layer "In6.Cu")
		(net "GND")
	)
	(segment
		(start -205.93825 26.30485)
		(end -204.940799 25.307399)
		(width 0.381)
		(layer "In6.Cu")
		(net "GND")
	)
	(segment
		(start -419.618945 25.633944)
		(end -418.846 24.860999)
		(width 0.381)
		(layer "In6.Cu")
		(net "GND")
	)
	(segment
		(start -205.93825 24.309949)
		(end -204.940799 25.307399)
		(width 0.381)
		(layer "In6.Cu")
		(net "GND")
	)
	(segment
		(start -418.846 24.860999)
		(end -418.073055 25.633944)
		(width 0.381)
		(layer "In6.Cu")
		(net "GND")
	)
	(segment
		(start -419.618945 24.088054)
		(end -418.846 24.860999)
		(width 0.381)
		(layer "In6.Cu")
		(net "GND")
	)
	(segment
		(start -201.607001 35.110001)
		(end -200.834056 35.882946)
		(width 0.381)
		(layer "In6.Cu")
		(net "GND")
	)
	(segment
		(start -199.4408 25.307399)
		(end -198.44335 24.309949)
		(width 0.381)
		(layer "In6.Cu")
		(net "GND")
	)
	(segment
		(start -204.940799 25.307399)
		(end -203.943349 26.30485)
		(width 0.381)
		(layer "In6.Cu")
		(net "GND")
	)
	(segment
		(start -204.940799 25.307399)
		(end -203.943349 24.309949)
		(width 0.381)
		(layer "In6.Cu")
		(net "GND")
	)
	(segment
		(start -199.4408 25.307399)
		(end -198.44335 26.30485)
		(width 0.381)
		(layer "In6.Cu")
		(net "GND")
	)
	(segment
		(start -200.43825 24.309949)
		(end -199.4408 25.307399)
		(width 0.381)
		(layer "In6.Cu")
		(net "GND")
	)
	(segment
		(start -202.379946 35.882946)
		(end -201.607001 35.110001)
		(width 0.381)
		(layer "In6.Cu")
		(net "GND")
	)
	(segment
		(start -92.218754 40.283359)
		(end -92.098416 40.163021)
		(width 0.10668)
		(layer "F.Cu")
		(net "ETH40G_B2_TX3P")
	)
	(segment
		(start -92.250001 41.340001)
		(end -92.250001 40.358794)
		(width 0.10668)
		(layer "F.Cu")
		(net "ETH40G_B2_TX3P")
	)
	(segment
		(start -92.067169 40.087586)
		(end -92.067169 34.581747)
		(width 0.10668)
		(layer "F.Cu")
		(net "ETH40G_B2_TX3P")
	)
	(via
		(at -92.256402 34.1249)
		(size 0.5588)
		(drill 0.254)
		(layers "F.Cu" "B.Cu")
		(net "ETH40G_B2_TX3P")
	)
	(arc
		(start -92.067169 34.581747)
		(mid -92.116349 34.334503)
		(end -92.256402 34.1249)
		(width 0.10668)
		(layer "F.Cu")
		(net "ETH40G_B2_TX3P")
	)
	(arc
		(start -92.250001 40.358794)
		(mid -92.24188 40.317969)
		(end -92.218754 40.283359)
		(width 0.10668)
		(layer "F.Cu")
		(net "ETH40G_B2_TX3P")
	)
	(arc
		(start -92.098416 40.163021)
		(mid -92.07529 40.128411)
		(end -92.067169 40.087586)
		(width 0.10668)
		(layer "F.Cu")
		(net "ETH40G_B2_TX3P")
	)
	(segment
		(start -75.460088 30.2895)
		(end -88.377057 30.2895)
		(width 0.11176)
		(layer "In5.Cu")
		(net "ETH40G_B2_TX3P")
	)
	(segment
		(start -71.5064 43.938162)
		(end -71.5064 34.460729)
		(width 0.11176)
		(layer "In5.Cu")
		(net "ETH40G_B2_TX3P")
	)
	(segment
		(start -92.021452 33.19526)
		(end -92.021452 33.55768)
		(width 0.11176)
		(layer "In5.Cu")
		(net "ETH40G_B2_TX3P")
	)
	(segment
		(start -73.040001 45.360001)
		(end -72.511453 44.831452)
		(width 0.11176)
		(layer "In5.Cu")
		(net "ETH40G_B2_TX3P")
	)
	(segment
		(start -91.37428 32.32404)
		(end -91.863027 32.812784)
		(width 0.11176)
		(layer "In5.Cu")
		(net "ETH40G_B2_TX3P")
	)
	(segment
		(start -72.511453 44.831452)
		(end -72.39969 44.831452)
		(width 0.11176)
		(layer "In5.Cu")
		(net "ETH40G_B2_TX3P")
	)
	(segment
		(start -71.987987 33.298077)
		(end -74.668802 30.617262)
		(width 0.11176)
		(layer "In5.Cu")
		(net "ETH40G_B2_TX3P")
	)
	(segment
		(start -90.02046 30.97022)
		(end -91.37428 32.32404)
		(width 0.11176)
		(layer "In5.Cu")
		(net "ETH40G_B2_TX3P")
	)
	(arc
		(start -91.863027 32.812784)
		(mid -91.980279 32.988266)
		(end -92.021452 33.19526)
		(width 0.11176)
		(layer "In5.Cu")
		(net "ETH40G_B2_TX3P")
	)
	(arc
		(start -72.39969 44.831452)
		(mid -71.768039 44.569813)
		(end -71.5064 43.938162)
		(width 0.11176)
		(layer "In5.Cu")
		(net "ETH40G_B2_TX3P")
	)
	(arc
		(start -92.021452 33.55768)
		(mid -92.082514 33.864657)
		(end -92.256402 34.1249)
		(width 0.11176)
		(layer "In5.Cu")
		(net "ETH40G_B2_TX3P")
	)
	(arc
		(start -71.5064 34.460729)
		(mid -71.63156 33.831506)
		(end -71.987987 33.298077)
		(width 0.11176)
		(layer "In5.Cu")
		(net "ETH40G_B2_TX3P")
	)
	(arc
		(start -88.377057 30.2895)
		(mid -89.26646 30.466413)
		(end -90.02046 30.97022)
		(width 0.11176)
		(layer "In5.Cu")
		(net "ETH40G_B2_TX3P")
	)
	(arc
		(start -74.668802 30.617262)
		(mid -75.031847 30.374683)
		(end -75.460088 30.2895)
		(width 0.11176)
		(layer "In5.Cu")
		(net "ETH40G_B2_TX3P")
	)
	(segment
		(start -91.45 41.340001)
		(end -91.45 40.358794)
		(width 0.10668)
		(layer "F.Cu")
		(net "ETH40G_B2_TX3N")
	)
	(segment
		(start -91.632829 40.087588)
		(end -91.632829 34.581734)
		(width 0.10668)
		(layer "F.Cu")
		(net "ETH40G_B2_TX3N")
	)
	(segment
		(start -91.481247 40.283359)
		(end -91.601582 40.163024)
		(width 0.10668)
		(layer "F.Cu")
		(net "ETH40G_B2_TX3N")
	)
	(via
		(at -91.443602 34.1249)
		(size 0.5588)
		(drill 0.254)
		(layers "F.Cu" "B.Cu")
		(net "ETH40G_B2_TX3N")
	)
	(arc
		(start -91.632829 34.581734)
		(mid -91.583651 34.334497)
		(end -91.443602 34.1249)
		(width 0.10668)
		(layer "F.Cu")
		(net "ETH40G_B2_TX3N")
	)
	(arc
		(start -91.601582 40.163024)
		(mid -91.624709 40.128414)
		(end -91.632829 40.087588)
		(width 0.10668)
		(layer "F.Cu")
		(net "ETH40G_B2_TX3N")
	)
	(arc
		(start -91.45 40.358794)
		(mid -91.458121 40.317969)
		(end -91.481247 40.283359)
		(width 0.10668)
		(layer "F.Cu")
		(net "ETH40G_B2_TX3N")
	)
	(segment
		(start -71.8493 43.938162)
		(end -71.8493 43.650411)
		(width 0.11176)
		(layer "In5.Cu")
		(net "ETH40G_B2_TX3N")
	)
	(segment
		(start -90.8607 32.295394)
		(end -91.620558 33.05525)
		(width 0.11176)
		(layer "In5.Cu")
		(net "ETH40G_B2_TX3N")
	)
	(segment
		(start -76.91914 30.86354)
		(end -77.442245 30.86354)
		(width 0.11176)
		(layer "In5.Cu")
		(net "ETH40G_B2_TX3N")
	)
	(segment
		(start -75.46009 30.6324)
		(end -76.688 30.6324)
		(width 0.11176)
		(layer "In5.Cu")
		(net "ETH40G_B2_TX3N")
	)
	(segment
		(start -90.405923 31.920729)
		(end -90.405923 31.993223)
		(width 0.11176)
		(layer "In5.Cu")
		(net "ETH40G_B2_TX3N")
	)
	(segment
		(start -85.4151 30.861)
		(end -85.83166 30.861)
		(width 0.11176)
		(layer "In5.Cu")
		(net "ETH40G_B2_TX3N")
	)
	(segment
		(start -90.405925 31.84062)
		(end -90.405923 31.920729)
		(width 0.11176)
		(layer "In5.Cu")
		(net "ETH40G_B2_TX3N")
	)
	(segment
		(start -72.08044 37.875601)
		(end -72.08044 37.438721)
		(width 0.11176)
		(layer "In5.Cu")
		(net "ETH40G_B2_TX3N")
	)
	(segment
		(start -82.25314 30.86354)
		(end -82.812786 30.86354)
		(width 0.11176)
		(layer "In5.Cu")
		(net "ETH40G_B2_TX3N")
	)
	(segment
		(start -72.51145 44.488552)
		(end -72.39969 44.488552)
		(width 0.11176)
		(layer "In5.Cu")
		(net "ETH40G_B2_TX3N")
	)
	(segment
		(start -85.83166 30.861)
		(end -86.06026 30.6324)
		(width 0.11176)
		(layer "In5.Cu")
		(net "ETH40G_B2_TX3N")
	)
	(segment
		(start -71.8493 43.650411)
		(end -72.08044 43.419271)
		(width 0.11176)
		(layer "In5.Cu")
		(net "ETH40G_B2_TX3N")
	)
	(segment
		(start -91.678552 33.195257)
		(end -91.678552 33.55768)
		(width 0.11176)
		(layer "In5.Cu")
		(net "ETH40G_B2_TX3N")
	)
	(segment
		(start -72.08044 43.419271)
		(end -72.08044 42.90314)
		(width 0.11176)
		(layer "In5.Cu")
		(net "ETH40G_B2_TX3N")
	)
	(segment
		(start -89.777992 31.212688)
		(end -90.405925 31.84062)
		(width 0.11176)
		(layer "In5.Cu")
		(net "ETH40G_B2_TX3N")
	)
	(segment
		(start -91.678549 33.19526)
		(end -91.678552 33.195257)
		(width 0.11176)
		(layer "In5.Cu")
		(net "ETH40G_B2_TX3N")
	)
	(segment
		(start -87.02883 30.6324)
		(end -87.25743 30.861)
		(width 0.11176)
		(layer "In5.Cu")
		(net "ETH40G_B2_TX3N")
	)
	(segment
		(start -82.022 30.6324)
		(end -82.25314 30.86354)
		(width 0.11176)
		(layer "In5.Cu")
		(net "ETH40G_B2_TX3N")
	)
	(segment
		(start -87.25743 30.861)
		(end -87.67399 30.861)
		(width 0.11176)
		(layer "In5.Cu")
		(net "ETH40G_B2_TX3N")
	)
	(segment
		(start -87.90259 30.6324)
		(end -88.377055 30.6324)
		(width 0.11176)
		(layer "In5.Cu")
		(net "ETH40G_B2_TX3N")
	)
	(segment
		(start -76.688 30.6324)
		(end -76.91914 30.86354)
		(width 0.11176)
		(layer "In5.Cu")
		(net "ETH40G_B2_TX3N")
	)
	(segment
		(start -77.442245 30.86354)
		(end -77.673385 30.6324)
		(width 0.11176)
		(layer "In5.Cu")
		(net "ETH40G_B2_TX3N")
	)
	(segment
		(start -87.67399 30.861)
		(end -87.90259 30.6324)
		(width 0.11176)
		(layer "In5.Cu")
		(net "ETH40G_B2_TX3N")
	)
	(segment
		(start -71.8493 38.106741)
		(end -72.08044 37.875601)
		(width 0.11176)
		(layer "In5.Cu")
		(net "ETH40G_B2_TX3N")
	)
	(segment
		(start -90.405923 31.993223)
		(end -90.708094 32.295394)
		(width 0.11176)
		(layer "In5.Cu")
		(net "ETH40G_B2_TX3N")
	)
	(segment
		(start -86.06026 30.6324)
		(end -87.02883 30.6324)
		(width 0.11176)
		(layer "In5.Cu")
		(net "ETH40G_B2_TX3N")
	)
	(segment
		(start -71.8493 37.207581)
		(end -71.8493 34.460731)
		(width 0.11176)
		(layer "In5.Cu")
		(net "ETH40G_B2_TX3N")
	)
	(segment
		(start -72.08044 38.754441)
		(end -71.8493 38.523301)
		(width 0.11176)
		(layer "In5.Cu")
		(net "ETH40G_B2_TX3N")
	)
	(segment
		(start -72.08044 41.23944)
		(end -71.8493 41.0083)
		(width 0.11176)
		(layer "In5.Cu")
		(net "ETH40G_B2_TX3N")
	)
	(segment
		(start -72.230455 33.540545)
		(end -74.91127 30.85973)
		(width 0.11176)
		(layer "In5.Cu")
		(net "ETH40G_B2_TX3N")
	)
	(segment
		(start -73.040001 43.960001)
		(end -72.51145 44.488552)
		(width 0.11176)
		(layer "In5.Cu")
		(net "ETH40G_B2_TX3N")
	)
	(segment
		(start -72.08044 41.720864)
		(end -72.08044 41.23944)
		(width 0.11176)
		(layer "In5.Cu")
		(net "ETH40G_B2_TX3N")
	)
	(segment
		(start -77.673385 30.6324)
		(end -82.022 30.6324)
		(width 0.11176)
		(layer "In5.Cu")
		(net "ETH40G_B2_TX3N")
	)
	(segment
		(start -72.08044 42.90314)
		(end -71.8493 42.672)
		(width 0.11176)
		(layer "In5.Cu")
		(net "ETH40G_B2_TX3N")
	)
	(segment
		(start -83.043926 30.6324)
		(end -85.1865 30.6324)
		(width 0.11176)
		(layer "In5.Cu")
		(net "ETH40G_B2_TX3N")
	)
	(segment
		(start -85.1865 30.6324)
		(end -85.4151 30.861)
		(width 0.11176)
		(layer "In5.Cu")
		(net "ETH40G_B2_TX3N")
	)
	(segment
		(start -72.08044 39.191321)
		(end -72.08044 38.754441)
		(width 0.11176)
		(layer "In5.Cu")
		(net "ETH40G_B2_TX3N")
	)
	(segment
		(start -71.8493 42.672)
		(end -71.8493 41.952004)
		(width 0.11176)
		(layer "In5.Cu")
		(net "ETH40G_B2_TX3N")
	)
	(segment
		(start -72.08044 37.438721)
		(end -71.8493 37.207581)
		(width 0.11176)
		(layer "In5.Cu")
		(net "ETH40G_B2_TX3N")
	)
	(segment
		(start -71.8493 41.0083)
		(end -71.8493 39.422461)
		(width 0.11176)
		(layer "In5.Cu")
		(net "ETH40G_B2_TX3N")
	)
	(segment
		(start -71.8493 39.422461)
		(end -72.08044 39.191321)
		(width 0.11176)
		(layer "In5.Cu")
		(net "ETH40G_B2_TX3N")
	)
	(segment
		(start -71.8493 38.523301)
		(end -71.8493 38.106741)
		(width 0.11176)
		(layer "In5.Cu")
		(net "ETH40G_B2_TX3N")
	)
	(segment
		(start -90.708094 32.295394)
		(end -90.8607 32.295394)
		(width 0.11176)
		(layer "In5.Cu")
		(net "ETH40G_B2_TX3N")
	)
	(segment
		(start -82.812786 30.86354)
		(end -83.043926 30.6324)
		(width 0.11176)
		(layer "In5.Cu")
		(net "ETH40G_B2_TX3N")
	)
	(segment
		(start -71.8493 41.952004)
		(end -72.08044 41.720864)
		(width 0.11176)
		(layer "In5.Cu")
		(net "ETH40G_B2_TX3N")
	)
	(arc
		(start -88.377055 30.6324)
		(mid -89.135237 30.783212)
		(end -89.777992 31.212688)
		(width 0.11176)
		(layer "In5.Cu")
		(net "ETH40G_B2_TX3N")
	)
	(arc
		(start -91.678552 33.55768)
		(mid -91.61749 33.864657)
		(end -91.443602 34.1249)
		(width 0.11176)
		(layer "In5.Cu")
		(net "ETH40G_B2_TX3N")
	)
	(arc
		(start -74.91127 30.85973)
		(mid -75.163071 30.691482)
		(end -75.46009 30.6324)
		(width 0.11176)
		(layer "In5.Cu")
		(net "ETH40G_B2_TX3N")
	)
	(arc
		(start -71.8493 34.460731)
		(mid -71.948359 33.962729)
		(end -72.230455 33.540545)
		(width 0.11176)
		(layer "In5.Cu")
		(net "ETH40G_B2_TX3N")
	)
	(arc
		(start -91.620558 33.05525)
		(mid -91.663478 33.119487)
		(end -91.678549 33.19526)
		(width 0.11176)
		(layer "In5.Cu")
		(net "ETH40G_B2_TX3N")
	)
	(arc
		(start -72.39969 44.488552)
		(mid -72.010505 44.327347)
		(end -71.8493 43.938162)
		(width 0.11176)
		(layer "In5.Cu")
		(net "ETH40G_B2_TX3N")
	)
	(segment
		(start -91.849999 44.865397)
		(end -91.66717 45.048226)
		(width 0.10668)
		(layer "F.Cu")
		(net "ETH40G_B2_TX2P")
	)
	(segment
		(start -91.849999 43.840001)
		(end -91.849999 44.865397)
		(width 0.10668)
		(layer "F.Cu")
		(net "ETH40G_B2_TX2P")
	)
	(segment
		(start -91.66717 45.048226)
		(end -91.66717 45.23565)
		(width 0.10668)
		(layer "F.Cu")
		(net "ETH40G_B2_TX2P")
	)
	(segment
		(start -92.24296 45.81144)
		(end -92.463932 46.03241)
		(width 0.10668)
		(layer "F.Cu")
		(net "ETH40G_B2_TX2P")
	)
	(segment
		(start -91.66717 45.23565)
		(end -92.24296 45.81144)
		(width 0.10668)
		(layer "F.Cu")
		(net "ETH40G_B2_TX2P")
	)
	(segment
		(start -92.64174 46.46168)
		(end -92.64174 46.638875)
		(width 0.10668)
		(layer "F.Cu")
		(net "ETH40G_B2_TX2P")
	)
	(via
		(at -92.82716 47.08652)
		(size 0.5588)
		(drill 0.254)
		(layers "F.Cu" "B.Cu")
		(net "ETH40G_B2_TX2P")
	)
	(arc
		(start -92.463932 46.03241)
		(mid -92.595529 46.229361)
		(end -92.64174 46.46168)
		(width 0.10668)
		(layer "F.Cu")
		(net "ETH40G_B2_TX2P")
	)
	(arc
		(start -92.64174 46.638875)
		(mid -92.689929 46.881138)
		(end -92.82716 47.08652)
		(width 0.10668)
		(layer "F.Cu")
		(net "ETH40G_B2_TX2P")
	)
	(segment
		(start -92.182493 45.649373)
		(end -91.827325 45.294205)
		(width 0.11176)
		(layer "In5.Cu")
		(net "ETH40G_B2_TX2P")
	)
	(segment
		(start -85.133221 32.768784)
		(end -84.938766 32.574332)
		(width 0.11176)
		(layer "In5.Cu")
		(net "ETH40G_B2_TX2P")
	)
	(segment
		(start -87.6735 42.8498)
		(end -87.6735 38.464851)
		(width 0.11176)
		(layer "In5.Cu")
		(net "ETH40G_B2_TX2P")
	)
	(segment
		(start -85.5218 36.595997)
		(end -85.5218 33.7069)
		(width 0.11176)
		(layer "In5.Cu")
		(net "ETH40G_B2_TX2P")
	)
	(segment
		(start -84.938766 32.574332)
		(end -84.517116 32.152679)
		(width 0.11176)
		(layer "In5.Cu")
		(net "ETH40G_B2_TX2P")
	)
	(segment
		(start -91.62145 44.79718)
		(end -91.62145 44.19425)
		(width 0.11176)
		(layer "In5.Cu")
		(net "ETH40G_B2_TX2P")
	)
	(segment
		(start -90.9882 43.561)
		(end -88.3847 43.561)
		(width 0.11176)
		(layer "In5.Cu")
		(net "ETH40G_B2_TX2P")
	)
	(segment
		(start -78.4152 43.5356)
		(end -78.5422 43.5356)
		(width 0.11176)
		(layer "In5.Cu")
		(net "ETH40G_B2_TX2P")
	)
	(segment
		(start -92.82716 47.08652)
		(end -92.74286 47.00222)
		(width 0.11176)
		(layer "In5.Cu")
		(net "ETH40G_B2_TX2P")
	)
	(segment
		(start -79.040002 44.033402)
		(end -79.040002 44.060001)
		(width 0.11176)
		(layer "In5.Cu")
		(net "ETH40G_B2_TX2P")
	)
	(segment
		(start -77.8564 32.9438)
		(end -77.8564 42.9768)
		(width 0.11176)
		(layer "In5.Cu")
		(net "ETH40G_B2_TX2P")
	)
	(segment
		(start -83.6676 31.8008)
		(end -78.9994 31.8008)
		(width 0.11176)
		(layer "In5.Cu")
		(net "ETH40G_B2_TX2P")
	)
	(segment
		(start -87.458768 37.946434)
		(end -87.366673 37.854341)
		(width 0.11176)
		(layer "In5.Cu")
		(net "ETH40G_B2_TX2P")
	)
	(arc
		(start -78.5422 43.5356)
		(mid -78.894199 43.681403)
		(end -79.040002 44.033402)
		(width 0.11176)
		(layer "In5.Cu")
		(net "ETH40G_B2_TX2P")
	)
	(arc
		(start -77.8564 42.9768)
		(mid -78.020069 43.371931)
		(end -78.4152 43.5356)
		(width 0.11176)
		(layer "In5.Cu")
		(net "ETH40G_B2_TX2P")
	)
	(arc
		(start -92.5884 46.62932)
		(mid -92.482908 46.098977)
		(end -92.182493 45.649373)
		(width 0.11176)
		(layer "In5.Cu")
		(net "ETH40G_B2_TX2P")
	)
	(arc
		(start -87.366673 37.854341)
		(mid -86.907286 37.547388)
		(end -86.365403 37.4396)
		(width 0.11176)
		(layer "In5.Cu")
		(net "ETH40G_B2_TX2P")
	)
	(arc
		(start -78.9994 31.8008)
		(mid -78.191177 32.135577)
		(end -77.8564 32.9438)
		(width 0.11176)
		(layer "In5.Cu")
		(net "ETH40G_B2_TX2P")
	)
	(arc
		(start -91.62145 44.19425)
		(mid -91.435975 43.746475)
		(end -90.9882 43.561)
		(width 0.11176)
		(layer "In5.Cu")
		(net "ETH40G_B2_TX2P")
	)
	(arc
		(start -91.827325 45.294205)
		(mid -91.674955 45.066168)
		(end -91.62145 44.79718)
		(width 0.11176)
		(layer "In5.Cu")
		(net "ETH40G_B2_TX2P")
	)
	(arc
		(start -88.3847 43.561)
		(mid -87.881806 43.352694)
		(end -87.6735 42.8498)
		(width 0.11176)
		(layer "In5.Cu")
		(net "ETH40G_B2_TX2P")
	)
	(arc
		(start -86.365403 37.4396)
		(mid -85.768886 37.192514)
		(end -85.5218 36.595997)
		(width 0.11176)
		(layer "In5.Cu")
		(net "ETH40G_B2_TX2P")
	)
	(arc
		(start -85.5218 33.7069)
		(mid -85.420812 33.199195)
		(end -85.133221 32.768784)
		(width 0.11176)
		(layer "In5.Cu")
		(net "ETH40G_B2_TX2P")
	)
	(arc
		(start -92.74286 47.00222)
		(mid -92.628543 46.831132)
		(end -92.5884 46.62932)
		(width 0.11176)
		(layer "In5.Cu")
		(net "ETH40G_B2_TX2P")
	)
	(arc
		(start -87.6735 38.464851)
		(mid -87.617694 38.184286)
		(end -87.458768 37.946434)
		(width 0.11176)
		(layer "In5.Cu")
		(net "ETH40G_B2_TX2P")
	)
	(arc
		(start -84.517116 32.152679)
		(mid -84.127355 31.89225)
		(end -83.6676 31.8008)
		(width 0.11176)
		(layer "In5.Cu")
		(net "ETH40G_B2_TX2P")
	)
	(segment
		(start -91.23283 45.415561)
		(end -92.156806 46.339536)
		(width 0.10668)
		(layer "F.Cu")
		(net "ETH40G_B2_TX2N")
	)
	(segment
		(start -91.050001 44.865397)
		(end -91.23283 45.048226)
		(width 0.10668)
		(layer "F.Cu")
		(net "ETH40G_B2_TX2N")
	)
	(segment
		(start -91.050001 43.840001)
		(end -91.050001 44.865397)
		(width 0.10668)
		(layer "F.Cu")
		(net "ETH40G_B2_TX2N")
	)
	(segment
		(start -91.23283 45.048226)
		(end -91.23283 45.415561)
		(width 0.10668)
		(layer "F.Cu")
		(net "ETH40G_B2_TX2N")
	)
	(segment
		(start -92.2074 46.461677)
		(end -92.2074 46.620481)
		(width 0.10668)
		(layer "F.Cu")
		(net "ETH40G_B2_TX2N")
	)
	(via
		(at -92.01436 47.08652)
		(size 0.5588)
		(drill 0.254)
		(layers "F.Cu" "B.Cu")
		(net "ETH40G_B2_TX2N")
	)
	(arc
		(start -92.156806 46.339536)
		(mid -92.19425 46.395575)
		(end -92.2074 46.461677)
		(width 0.10668)
		(layer "F.Cu")
		(net "ETH40G_B2_TX2N")
	)
	(arc
		(start -92.2074 46.620481)
		(mid -92.157231 46.8727)
		(end -92.01436 47.08652)
		(width 0.10668)
		(layer "F.Cu")
		(net "ETH40G_B2_TX2N")
	)
	(segment
		(start -90.193094 44.1198)
		(end -89.977194 43.9039)
		(width 0.11176)
		(layer "In5.Cu")
		(net "ETH40G_B2_TX2N")
	)
	(segment
		(start -87.16296 41.364218)
		(end -87.16296 41.034018)
		(width 0.11176)
		(layer "In5.Cu")
		(net "ETH40G_B2_TX2N")
	)
	(segment
		(start -85.1789 35.93194)
		(end -84.9884 35.74144)
		(width 0.11176)
		(layer "In5.Cu")
		(net "ETH40G_B2_TX2N")
	)
	(segment
		(start -78.4152 43.1927)
		(end -78.5422 43.1927)
		(width 0.11176)
		(layer "In5.Cu")
		(net "ETH40G_B2_TX2N")
	)
	(segment
		(start -84.9884 35.74144)
		(end -84.9884 35.32488)
		(width 0.11176)
		(layer "In5.Cu")
		(net "ETH40G_B2_TX2N")
	)
	(segment
		(start -80.819843 32.1437)
		(end -80.588703 32.37484)
		(width 0.11176)
		(layer "In5.Cu")
		(net "ETH40G_B2_TX2N")
	)
	(segment
		(start -87.16296 41.034018)
		(end -87.3306 40.866378)
		(width 0.11176)
		(layer "In5.Cu")
		(net "ETH40G_B2_TX2N")
	)
	(segment
		(start -87.3306 40.63524)
		(end -87.10168 40.40632)
		(width 0.11176)
		(layer "In5.Cu")
		(net "ETH40G_B2_TX2N")
	)
	(segment
		(start -81.467543 32.37484)
		(end -81.236403 32.1437)
		(width 0.11176)
		(layer "In5.Cu")
		(net "ETH40G_B2_TX2N")
	)
	(segment
		(start -84.94776 34.48668)
		(end -84.94776 34.1514)
		(width 0.11176)
		(layer "In5.Cu")
		(net "ETH40G_B2_TX2N")
	)
	(segment
		(start -87.10168 39.33952)
		(end -87.10168 39.01472)
		(width 0.11176)
		(layer "In5.Cu")
		(net "ETH40G_B2_TX2N")
	)
	(segment
		(start -84.890755 33.011252)
		(end -84.6963 32.8168)
		(width 0.11176)
		(layer "In5.Cu")
		(net "ETH40G_B2_TX2N")
	)
	(segment
		(start -87.32806 42.07732)
		(end -87.3306 42.07478)
		(width 0.11176)
		(layer "In5.Cu")
		(net "ETH40G_B2_TX2N")
	)
	(segment
		(start -78.1993 32.9438)
		(end -78.1993 42.9768)
		(width 0.11176)
		(layer "In5.Cu")
		(net "ETH40G_B2_TX2N")
	)
	(segment
		(start -79.040002 42.694898)
		(end -79.040002 42.660001)
		(width 0.11176)
		(layer "In5.Cu")
		(net "ETH40G_B2_TX2N")
	)
	(segment
		(start -87.3306 39.56844)
		(end -87.10168 39.33952)
		(width 0.11176)
		(layer "In5.Cu")
		(net "ETH40G_B2_TX2N")
	)
	(segment
		(start -87.3306 38.7858)
		(end -87.3306 38.464848)
		(width 0.11176)
		(layer "In5.Cu")
		(net "ETH40G_B2_TX2N")
	)
	(segment
		(start -83.6676 32.1437)
		(end -82.262563 32.1437)
		(width 0.11176)
		(layer "In5.Cu")
		(net "ETH40G_B2_TX2N")
	)
	(segment
		(start -91.27855 44.79718)
		(end -91.27855 44.19425)
		(width 0.11176)
		(layer "In5.Cu")
		(net "ETH40G_B2_TX2N")
	)
	(segment
		(start -82.262563 32.1437)
		(end -82.031423 32.37484)
		(width 0.11176)
		(layer "In5.Cu")
		(net "ETH40G_B2_TX2N")
	)
	(segment
		(start -79.793683 32.1437)
		(end -78.9994 32.1437)
		(width 0.11176)
		(layer "In5.Cu")
		(net "ETH40G_B2_TX2N")
	)
	(segment
		(start -87.3306 40.866378)
		(end -87.3306 40.63524)
		(width 0.11176)
		(layer "In5.Cu")
		(net "ETH40G_B2_TX2N")
	)
	(segment
		(start -84.94776 34.1514)
		(end -85.1789 33.92026)
		(width 0.11176)
		(layer "In5.Cu")
		(net "ETH40G_B2_TX2N")
	)
	(segment
		(start -87.3306 39.88276)
		(end -87.3306 39.56844)
		(width 0.11176)
		(layer "In5.Cu")
		(net "ETH40G_B2_TX2N")
	)
	(segment
		(start -87.10168 40.11168)
		(end -87.3306 39.88276)
		(width 0.11176)
		(layer "In5.Cu")
		(net "ETH40G_B2_TX2N")
	)
	(segment
		(start -85.1789 33.92026)
		(end -85.1789 33.7069)
		(width 0.11176)
		(layer "In5.Cu")
		(net "ETH40G_B2_TX2N")
	)
	(segment
		(start -92.01436 47.08652)
		(end -92.08565 47.015227)
		(width 0.11176)
		(layer "In5.Cu")
		(net "ETH40G_B2_TX2N")
	)
	(segment
		(start -88.763074 43.9039)
		(end -88.3847 43.9039)
		(width 0.11176)
		(layer "In5.Cu")
		(net "ETH40G_B2_TX2N")
	)
	(segment
		(start -87.3306 42.8498)
		(end -87.32806 42.84726)
		(width 0.11176)
		(layer "In5.Cu")
		(net "ETH40G_B2_TX2N")
	)
	(segment
		(start -89.370134 44.0944)
		(end -88.953574 44.0944)
		(width 0.11176)
		(layer "In5.Cu")
		(net "ETH40G_B2_TX2N")
	)
	(segment
		(start -85.1789 35.13438)
		(end -85.1789 34.71782)
		(width 0.11176)
		(layer "In5.Cu")
		(net "ETH40G_B2_TX2N")
	)
	(segment
		(start -85.1789 34.71782)
		(end -84.94776 34.48668)
		(width 0.11176)
		(layer "In5.Cu")
		(net "ETH40G_B2_TX2N")
	)
	(segment
		(start -87.3306 41.531858)
		(end -87.16296 41.364218)
		(width 0.11176)
		(layer "In5.Cu")
		(net "ETH40G_B2_TX2N")
	)
	(segment
		(start -89.560634 43.9039)
		(end -89.370134 44.0944)
		(width 0.11176)
		(layer "In5.Cu")
		(net "ETH40G_B2_TX2N")
	)
	(segment
		(start -87.3306 42.07478)
		(end -87.3306 41.531858)
		(width 0.11176)
		(layer "In5.Cu")
		(net "ETH40G_B2_TX2N")
	)
	(segment
		(start -88.953574 44.0944)
		(end -88.763074 43.9039)
		(width 0.11176)
		(layer "In5.Cu")
		(net "ETH40G_B2_TX2N")
	)
	(segment
		(start -90.774754 43.9039)
		(end -90.558854 44.1198)
		(width 0.11176)
		(layer "In5.Cu")
		(net "ETH40G_B2_TX2N")
	)
	(segment
		(start -87.2163 38.188903)
		(end -87.124207 38.09681)
		(width 0.11176)
		(layer "In5.Cu")
		(net "ETH40G_B2_TX2N")
	)
	(segment
		(start -81.236403 32.1437)
		(end -80.819843 32.1437)
		(width 0.11176)
		(layer "In5.Cu")
		(net "ETH40G_B2_TX2N")
	)
	(segment
		(start -90.9882 43.9039)
		(end -90.774754 43.9039)
		(width 0.11176)
		(layer "In5.Cu")
		(net "ETH40G_B2_TX2N")
	)
	(segment
		(start -84.9884 35.32488)
		(end -85.1789 35.13438)
		(width 0.11176)
		(layer "In5.Cu")
		(net "ETH40G_B2_TX2N")
	)
	(segment
		(start -80.024823 32.37484)
		(end -79.793683 32.1437)
		(width 0.11176)
		(layer "In5.Cu")
		(net "ETH40G_B2_TX2N")
	)
	(segment
		(start -80.588703 32.37484)
		(end -80.024823 32.37484)
		(width 0.11176)
		(layer "In5.Cu")
		(net "ETH40G_B2_TX2N")
	)
	(segment
		(start -89.977194 43.9039)
		(end -89.560634 43.9039)
		(width 0.11176)
		(layer "In5.Cu")
		(net "ETH40G_B2_TX2N")
	)
	(segment
		(start -87.10168 40.40632)
		(end -87.10168 40.11168)
		(width 0.11176)
		(layer "In5.Cu")
		(net "ETH40G_B2_TX2N")
	)
	(segment
		(start -91.940024 45.891841)
		(end -91.584856 45.536673)
		(width 0.11176)
		(layer "In5.Cu")
		(net "ETH40G_B2_TX2N")
	)
	(segment
		(start -87.32806 42.84726)
		(end -87.32806 42.07732)
		(width 0.11176)
		(layer "In5.Cu")
		(net "ETH40G_B2_TX2N")
	)
	(segment
		(start -87.10168 39.01472)
		(end -87.3306 38.7858)
		(width 0.11176)
		(layer "In5.Cu")
		(net "ETH40G_B2_TX2N")
	)
	(segment
		(start -85.1789 36.595997)
		(end -85.1789 35.93194)
		(width 0.11176)
		(layer "In5.Cu")
		(net "ETH40G_B2_TX2N")
	)
	(segment
		(start -82.031423 32.37484)
		(end -81.467543 32.37484)
		(width 0.11176)
		(layer "In5.Cu")
		(net "ETH40G_B2_TX2N")
	)
	(segment
		(start -90.558854 44.1198)
		(end -90.193094 44.1198)
		(width 0.11176)
		(layer "In5.Cu")
		(net "ETH40G_B2_TX2N")
	)
	(segment
		(start -84.6963 32.8168)
		(end -84.274647 32.395147)
		(width 0.11176)
		(layer "In5.Cu")
		(net "ETH40G_B2_TX2N")
	)
	(arc
		(start -86.3654 37.782503)
		(mid -85.526417 37.434982)
		(end -85.1789 36.595997)
		(width 0.11176)
		(layer "In5.Cu")
		(net "ETH40G_B2_TX2N")
	)
	(arc
		(start -92.08565 47.015227)
		(mid -92.203956 46.838172)
		(end -92.2455 46.62932)
		(width 0.11176)
		(layer "In5.Cu")
		(net "ETH40G_B2_TX2N")
	)
	(arc
		(start -78.5422 43.1927)
		(mid -78.894199 43.046897)
		(end -79.040002 42.694898)
		(width 0.11176)
		(layer "In5.Cu")
		(net "ETH40G_B2_TX2N")
	)
	(arc
		(start -91.27855 44.19425)
		(mid -91.193508 43.988942)
		(end -90.9882 43.9039)
		(width 0.11176)
		(layer "In5.Cu")
		(net "ETH40G_B2_TX2N")
	)
	(arc
		(start -91.584856 45.536673)
		(mid -91.358155 45.197391)
		(end -91.27855 44.79718)
		(width 0.11176)
		(layer "In5.Cu")
		(net "ETH40G_B2_TX2N")
	)
	(arc
		(start -87.3306 38.464848)
		(mid -87.300894 38.315508)
		(end -87.2163 38.188903)
		(width 0.11176)
		(layer "In5.Cu")
		(net "ETH40G_B2_TX2N")
	)
	(arc
		(start -92.2455 46.62932)
		(mid -92.166109 46.230199)
		(end -91.940024 45.891841)
		(width 0.11176)
		(layer "In5.Cu")
		(net "ETH40G_B2_TX2N")
	)
	(arc
		(start -87.124207 38.09681)
		(mid -86.776063 37.864188)
		(end -86.3654 37.782503)
		(width 0.11176)
		(layer "In5.Cu")
		(net "ETH40G_B2_TX2N")
	)
	(arc
		(start -88.3847 43.9039)
		(mid -87.639339 43.595161)
		(end -87.3306 42.8498)
		(width 0.11176)
		(layer "In5.Cu")
		(net "ETH40G_B2_TX2N")
	)
	(arc
		(start -78.1993 42.9768)
		(mid -78.262536 43.129464)
		(end -78.4152 43.1927)
		(width 0.11176)
		(layer "In5.Cu")
		(net "ETH40G_B2_TX2N")
	)
	(arc
		(start -85.1789 33.7069)
		(mid -85.104014 33.330418)
		(end -84.890755 33.011252)
		(width 0.11176)
		(layer "In5.Cu")
		(net "ETH40G_B2_TX2N")
	)
	(arc
		(start -78.9994 32.1437)
		(mid -78.433644 32.378044)
		(end -78.1993 32.9438)
		(width 0.11176)
		(layer "In5.Cu")
		(net "ETH40G_B2_TX2N")
	)
	(arc
		(start -84.274647 32.395147)
		(mid -83.996131 32.209049)
		(end -83.6676 32.1437)
		(width 0.11176)
		(layer "In5.Cu")
		(net "ETH40G_B2_TX2N")
	)
	(segment
		(start -89.667169 40.087586)
		(end -89.667169 38.498211)
		(width 0.10668)
		(layer "F.Cu")
		(net "ETH40G_B2_TX1P")
	)
	(segment
		(start -89.850001 41.340001)
		(end -89.850001 40.358794)
		(width 0.10668)
		(layer "F.Cu")
		(net "ETH40G_B2_TX1P")
	)
	(segment
		(start -89.818754 40.283359)
		(end -89.698416 40.163021)
		(width 0.10668)
		(layer "F.Cu")
		(net "ETH40G_B2_TX1P")
	)
	(via
		(at -89.842635 38.0746)
		(size 0.5588)
		(drill 0.254)
		(layers "F.Cu" "B.Cu")
		(net "ETH40G_B2_TX1P")
	)
	(arc
		(start -89.850001 40.358794)
		(mid -89.84188 40.317969)
		(end -89.818754 40.283359)
		(width 0.10668)
		(layer "F.Cu")
		(net "ETH40G_B2_TX1P")
	)
	(arc
		(start -89.667169 38.498211)
		(mid -89.712771 38.268954)
		(end -89.842635 38.0746)
		(width 0.10668)
		(layer "F.Cu")
		(net "ETH40G_B2_TX1P")
	)
	(arc
		(start -89.698416 40.163021)
		(mid -89.67529 40.128411)
		(end -89.667169 40.087586)
		(width 0.10668)
		(layer "F.Cu")
		(net "ETH40G_B2_TX1P")
	)
	(segment
		(start -83.567019 43.577172)
		(end -83.673701 43.577172)
		(width 0.10668)
		(layer "B.Cu")
		(net "ETH40G_B2_TX1P")
	)
	(segment
		(start -83.040002 44.060001)
		(end -83.491583 43.608419)
		(width 0.10668)
		(layer "B.Cu")
		(net "ETH40G_B2_TX1P")
	)
	(segment
		(start -84.476341 41.23436)
		(end -88.805045 41.23436)
		(width 0.10668)
		(layer "B.Cu")
		(net "ETH40G_B2_TX1P")
	)
	(segment
		(start -84.214721 43.036152)
		(end -84.214721 41.49598)
		(width 0.10668)
		(layer "B.Cu")
		(net "ETH40G_B2_TX1P")
	)
	(segment
		(start -89.653405 40.386)
		(end -89.653405 38.531442)
		(width 0.10668)
		(layer "B.Cu")
		(net "ETH40G_B2_TX1P")
	)
	(arc
		(start -84.214721 41.49598)
		(mid -84.291348 41.310987)
		(end -84.476341 41.23436)
		(width 0.10668)
		(layer "B.Cu")
		(net "ETH40G_B2_TX1P")
	)
	(arc
		(start -89.653405 38.531442)
		(mid -89.702584 38.284201)
		(end -89.842635 38.0746)
		(width 0.10668)
		(layer "B.Cu")
		(net "ETH40G_B2_TX1P")
	)
	(arc
		(start -83.491583 43.608419)
		(mid -83.526193 43.585292)
		(end -83.567019 43.577172)
		(width 0.10668)
		(layer "B.Cu")
		(net "ETH40G_B2_TX1P")
	)
	(arc
		(start -83.673701 43.577172)
		(mid -84.05626 43.418711)
		(end -84.214721 43.036152)
		(width 0.10668)
		(layer "B.Cu")
		(net "ETH40G_B2_TX1P")
	)
	(arc
		(start -88.805045 41.23436)
		(mid -89.404926 40.985881)
		(end -89.653405 40.386)
		(width 0.10668)
		(layer "B.Cu")
		(net "ETH40G_B2_TX1P")
	)
	(segment
		(start -89.232829 40.087588)
		(end -89.232829 38.564673)
		(width 0.10668)
		(layer "F.Cu")
		(net "ETH40G_B2_TX1N")
	)
	(segment
		(start -89.05 41.340001)
		(end -89.05 40.358794)
		(width 0.10668)
		(layer "F.Cu")
		(net "ETH40G_B2_TX1N")
	)
	(segment
		(start -89.081247 40.283359)
		(end -89.201582 40.163024)
		(width 0.10668)
		(layer "F.Cu")
		(net "ETH40G_B2_TX1N")
	)
	(via
		(at -89.029835 38.0746)
		(size 0.5588)
		(drill 0.254)
		(layers "F.Cu" "B.Cu")
		(net "ETH40G_B2_TX1N")
	)
	(arc
		(start -89.05 40.358794)
		(mid -89.058121 40.317969)
		(end -89.081247 40.283359)
		(width 0.10668)
		(layer "F.Cu")
		(net "ETH40G_B2_TX1N")
	)
	(arc
		(start -89.232829 38.564673)
		(mid -89.180073 38.299448)
		(end -89.029835 38.0746)
		(width 0.10668)
		(layer "F.Cu")
		(net "ETH40G_B2_TX1N")
	)
	(arc
		(start -89.201582 40.163024)
		(mid -89.224709 40.128414)
		(end -89.232829 40.087588)
		(width 0.10668)
		(layer "F.Cu")
		(net "ETH40G_B2_TX1N")
	)
	(segment
		(start -89.08828 39.236607)
		(end -89.08828 39.719847)
		(width 0.10668)
		(layer "B.Cu")
		(net "ETH40G_B2_TX1N")
	)
	(segment
		(start -89.219065 39.105822)
		(end -89.08828 39.236607)
		(width 0.10668)
		(layer "B.Cu")
		(net "ETH40G_B2_TX1N")
	)
	(segment
		(start -88.375848 40.80002)
		(end -88.147248 40.57142)
		(width 0.10668)
		(layer "B.Cu")
		(net "ETH40G_B2_TX1N")
	)
	(segment
		(start -84.946848 40.80002)
		(end -84.476341 40.80002)
		(width 0.10668)
		(layer "B.Cu")
		(net "ETH40G_B2_TX1N")
	)
	(segment
		(start -89.219065 38.531442)
		(end -89.219065 39.105822)
		(width 0.10668)
		(layer "B.Cu")
		(net "ETH40G_B2_TX1N")
	)
	(segment
		(start -87.735768 40.57142)
		(end -87.507168 40.80002)
		(width 0.10668)
		(layer "B.Cu")
		(net "ETH40G_B2_TX1N")
	)
	(segment
		(start -86.867088 40.57142)
		(end -86.455608 40.57142)
		(width 0.10668)
		(layer "B.Cu")
		(net "ETH40G_B2_TX1N")
	)
	(segment
		(start -83.491586 43.111585)
		(end -83.040002 42.660001)
		(width 0.10668)
		(layer "B.Cu")
		(net "ETH40G_B2_TX1N")
	)
	(segment
		(start -85.175448 40.57142)
		(end -84.946848 40.80002)
		(width 0.10668)
		(layer "B.Cu")
		(net "ETH40G_B2_TX1N")
	)
	(segment
		(start -85.586928 40.57142)
		(end -85.175448 40.57142)
		(width 0.10668)
		(layer "B.Cu")
		(net "ETH40G_B2_TX1N")
	)
	(segment
		(start -86.227008 40.80002)
		(end -85.815528 40.80002)
		(width 0.10668)
		(layer "B.Cu")
		(net "ETH40G_B2_TX1N")
	)
	(segment
		(start -88.805045 40.80002)
		(end -88.375848 40.80002)
		(width 0.10668)
		(layer "B.Cu")
		(net "ETH40G_B2_TX1N")
	)
	(segment
		(start -88.147248 40.57142)
		(end -87.735768 40.57142)
		(width 0.10668)
		(layer "B.Cu")
		(net "ETH40G_B2_TX1N")
	)
	(segment
		(start -83.780381 41.49598)
		(end -83.780381 43.036152)
		(width 0.10668)
		(layer "B.Cu")
		(net "ETH40G_B2_TX1N")
	)
	(segment
		(start -86.455608 40.57142)
		(end -86.227008 40.80002)
		(width 0.10668)
		(layer "B.Cu")
		(net "ETH40G_B2_TX1N")
	)
	(segment
		(start -89.219065 39.850632)
		(end -89.219065 40.386)
		(width 0.10668)
		(layer "B.Cu")
		(net "ETH40G_B2_TX1N")
	)
	(segment
		(start -83.673701 43.142832)
		(end -83.567021 43.142832)
		(width 0.10668)
		(layer "B.Cu")
		(net "ETH40G_B2_TX1N")
	)
	(segment
		(start -87.095688 40.80002)
		(end -86.867088 40.57142)
		(width 0.10668)
		(layer "B.Cu")
		(net "ETH40G_B2_TX1N")
	)
	(segment
		(start -85.815528 40.80002)
		(end -85.586928 40.57142)
		(width 0.10668)
		(layer "B.Cu")
		(net "ETH40G_B2_TX1N")
	)
	(segment
		(start -87.507168 40.80002)
		(end -87.095688 40.80002)
		(width 0.10668)
		(layer "B.Cu")
		(net "ETH40G_B2_TX1N")
	)
	(segment
		(start -89.08828 39.719847)
		(end -89.219065 39.850632)
		(width 0.10668)
		(layer "B.Cu")
		(net "ETH40G_B2_TX1N")
	)
	(arc
		(start -84.476341 40.80002)
		(mid -83.984223 41.003862)
		(end -83.780381 41.49598)
		(width 0.10668)
		(layer "B.Cu")
		(net "ETH40G_B2_TX1N")
	)
	(arc
		(start -89.219065 40.386)
		(mid -89.097801 40.678756)
		(end -88.805045 40.80002)
		(width 0.10668)
		(layer "B.Cu")
		(net "ETH40G_B2_TX1N")
	)
	(arc
		(start -83.780381 43.036152)
		(mid -83.749135 43.111586)
		(end -83.673701 43.142832)
		(width 0.10668)
		(layer "B.Cu")
		(net "ETH40G_B2_TX1N")
	)
	(arc
		(start -89.029835 38.0746)
		(mid -89.169886 38.284201)
		(end -89.219065 38.531442)
		(width 0.10668)
		(layer "B.Cu")
		(net "ETH40G_B2_TX1N")
	)
	(arc
		(start -83.567021 43.142832)
		(mid -83.526196 43.134711)
		(end -83.491586 43.111585)
		(width 0.10668)
		(layer "B.Cu")
		(net "ETH40G_B2_TX1N")
	)
	(segment
		(start -89.26717 45.092414)
		(end -89.26717 45.63872)
		(width 0.10668)
		(layer "F.Cu")
		(net "ETH40G_B2_TX0P")
	)
	(segment
		(start -89.418752 44.896644)
		(end -89.298417 45.016979)
		(width 0.10668)
		(layer "F.Cu")
		(net "ETH40G_B2_TX0P")
	)
	(segment
		(start -89.449999 43.840001)
		(end -89.449999 44.821208)
		(width 0.10668)
		(layer "F.Cu")
		(net "ETH40G_B2_TX0P")
	)
	(segment
		(start -85.54752 44.31538)
		(end -85.54752 42.914159)
		(width 0.10668)
		(layer "F.Cu")
		(net "ETH40G_B2_TX0P")
	)
	(segment
		(start -88.62455 46.28134)
		(end -87.51348 46.28134)
		(width 0.10668)
		(layer "F.Cu")
		(net "ETH40G_B2_TX0P")
	)
	(via
		(at -85.37988 42.50944)
		(size 0.5588)
		(drill 0.254)
		(layers "F.Cu" "B.Cu")
		(net "ETH40G_B2_TX0P")
	)
	(arc
		(start -89.449999 44.821208)
		(mid -89.441878 44.862034)
		(end -89.418752 44.896644)
		(width 0.10668)
		(layer "F.Cu")
		(net "ETH40G_B2_TX0P")
	)
	(arc
		(start -89.26717 45.63872)
		(mid -89.078951 46.093121)
		(end -88.62455 46.28134)
		(width 0.10668)
		(layer "F.Cu")
		(net "ETH40G_B2_TX0P")
	)
	(arc
		(start -89.298417 45.016979)
		(mid -89.275291 45.051589)
		(end -89.26717 45.092414)
		(width 0.10668)
		(layer "F.Cu")
		(net "ETH40G_B2_TX0P")
	)
	(arc
		(start -85.54752 42.914159)
		(mid -85.503952 42.695127)
		(end -85.37988 42.50944)
		(width 0.10668)
		(layer "F.Cu")
		(net "ETH40G_B2_TX0P")
	)
	(arc
		(start -87.51348 46.28134)
		(mid -86.123336 45.705524)
		(end -85.54752 44.31538)
		(width 0.10668)
		(layer "F.Cu")
		(net "ETH40G_B2_TX0P")
	)
	(segment
		(start -85.60086 41.975946)
		(end -85.60086 41.85666)
		(width 0.11176)
		(layer "In5.Cu")
		(net "ETH40G_B2_TX0P")
	)
	(segment
		(start -85.232522 40.967419)
		(end -84.228351 39.963247)
		(width 0.11176)
		(layer "In5.Cu")
		(net "ETH40G_B2_TX0P")
	)
	(segment
		(start -83.040002 35.577998)
		(end -83.040002 35.66)
		(width 0.11176)
		(layer "In5.Cu")
		(net "ETH40G_B2_TX0P")
	)
	(segment
		(start -83.9216 39.22268)
		(end -83.9216 35.6108)
		(width 0.11176)
		(layer "In5.Cu")
		(net "ETH40G_B2_TX0P")
	)
	(arc
		(start -85.60086 41.85666)
		(mid -85.505132 41.375406)
		(end -85.232522 40.967419)
		(width 0.11176)
		(layer "In5.Cu")
		(net "ETH40G_B2_TX0P")
	)
	(arc
		(start -83.4644 35.1536)
		(mid -83.164305 35.277903)
		(end -83.040002 35.577998)
		(width 0.11176)
		(layer "In5.Cu")
		(net "ETH40G_B2_TX0P")
	)
	(arc
		(start -85.37988 42.50944)
		(mid -85.54343 42.264671)
		(end -85.60086 41.975946)
		(width 0.11176)
		(layer "In5.Cu")
		(net "ETH40G_B2_TX0P")
	)
	(arc
		(start -83.9216 35.6108)
		(mid -83.787689 35.287511)
		(end -83.4644 35.1536)
		(width 0.11176)
		(layer "In5.Cu")
		(net "ETH40G_B2_TX0P")
	)
	(arc
		(start -84.228351 39.963247)
		(mid -84.001322 39.623472)
		(end -83.9216 39.22268)
		(width 0.11176)
		(layer "In5.Cu")
		(net "ETH40G_B2_TX0P")
	)
	(segment
		(start -87.93367 45.67428)
		(end -87.76095 45.847)
		(width 0.10668)
		(layer "F.Cu")
		(net "ETH40G_B2_TX0N")
	)
	(segment
		(start -85.98186 44.31538)
		(end -85.98186 44.19854)
		(width 0.10668)
		(layer "F.Cu")
		(net "ETH40G_B2_TX0N")
	)
	(segment
		(start -88.62455 45.847)
		(end -88.41627 45.847)
		(width 0.10668)
		(layer "F.Cu")
		(net "ETH40G_B2_TX0N")
	)
	(segment
		(start -85.98186 44.19854)
		(end -86.27396 43.90644)
		(width 0.10668)
		(layer "F.Cu")
		(net "ETH40G_B2_TX0N")
	)
	(segment
		(start -88.24355 45.67428)
		(end -87.93367 45.67428)
		(width 0.10668)
		(layer "F.Cu")
		(net "ETH40G_B2_TX0N")
	)
	(segment
		(start -86.27396 43.90644)
		(end -86.27396 43.518785)
		(width 0.10668)
		(layer "F.Cu")
		(net "ETH40G_B2_TX0N")
	)
	(segment
		(start -85.98186 43.226685)
		(end -85.98186 43.018405)
		(width 0.10668)
		(layer "F.Cu")
		(net "ETH40G_B2_TX0N")
	)
	(segment
		(start -88.83283 45.092414)
		(end -88.83283 45.63872)
		(width 0.10668)
		(layer "F.Cu")
		(net "ETH40G_B2_TX0N")
	)
	(segment
		(start -86.27396 43.518785)
		(end -85.98186 43.226685)
		(width 0.10668)
		(layer "F.Cu")
		(net "ETH40G_B2_TX0N")
	)
	(segment
		(start -87.76095 45.847)
		(end -87.51348 45.847)
		(width 0.10668)
		(layer "F.Cu")
		(net "ETH40G_B2_TX0N")
	)
	(segment
		(start -88.41627 45.847)
		(end -88.24355 45.67428)
		(width 0.10668)
		(layer "F.Cu")
		(net "ETH40G_B2_TX0N")
	)
	(segment
		(start -88.650001 43.840001)
		(end -88.650001 44.821208)
		(width 0.10668)
		(layer "F.Cu")
		(net "ETH40G_B2_TX0N")
	)
	(segment
		(start -88.681248 44.896644)
		(end -88.801583 45.016979)
		(width 0.10668)
		(layer "F.Cu")
		(net "ETH40G_B2_TX0N")
	)
	(via
		(at -86.19268 42.50944)
		(size 0.5588)
		(drill 0.254)
		(layers "F.Cu" "B.Cu")
		(net "ETH40G_B2_TX0N")
	)
	(arc
		(start -88.650001 44.821208)
		(mid -88.658122 44.862034)
		(end -88.681248 44.896644)
		(width 0.10668)
		(layer "F.Cu")
		(net "ETH40G_B2_TX0N")
	)
	(arc
		(start -88.801583 45.016979)
		(mid -88.824709 45.051589)
		(end -88.83283 45.092414)
		(width 0.10668)
		(layer "F.Cu")
		(net "ETH40G_B2_TX0N")
	)
	(arc
		(start -87.51348 45.847)
		(mid -86.430461 45.398399)
		(end -85.98186 44.31538)
		(width 0.10668)
		(layer "F.Cu")
		(net "ETH40G_B2_TX0N")
	)
	(arc
		(start -88.83283 45.63872)
		(mid -88.771826 45.785996)
		(end -88.62455 45.847)
		(width 0.10668)
		(layer "F.Cu")
		(net "ETH40G_B2_TX0N")
	)
	(arc
		(start -85.98186 43.018405)
		(mid -86.03665 42.742955)
		(end -86.19268 42.50944)
		(width 0.10668)
		(layer "F.Cu")
		(net "ETH40G_B2_TX0N")
	)
	(segment
		(start -84.2645 39.22268)
		(end -84.2645 39.00932)
		(width 0.11176)
		(layer "In5.Cu")
		(net "ETH40G_B2_TX0N")
	)
	(segment
		(start -84.2645 38.13556)
		(end -84.2645 37.729571)
		(width 0.11176)
		(layer "In5.Cu")
		(net "ETH40G_B2_TX0N")
	)
	(segment
		(start -85.94376 41.908494)
		(end -85.94376 41.85666)
		(width 0.11176)
		(layer "In5.Cu")
		(net "ETH40G_B2_TX0N")
	)
	(segment
		(start -84.49088 37.503191)
		(end -84.49088 37.153312)
		(width 0.11176)
		(layer "In5.Cu")
		(net "ETH40G_B2_TX0N")
	)
	(segment
		(start -84.49564 38.77818)
		(end -84.49564 38.3667)
		(width 0.11176)
		(layer "In5.Cu")
		(net "ETH40G_B2_TX0N")
	)
	(segment
		(start -83.040002 34.386302)
		(end -83.040002 34.26)
		(width 0.11176)
		(layer "In5.Cu")
		(net "ETH40G_B2_TX0N")
	)
	(segment
		(start -85.47499 40.72495)
		(end -84.470819 39.720779)
		(width 0.11176)
		(layer "In5.Cu")
		(net "ETH40G_B2_TX0N")
	)
	(segment
		(start -84.2645 39.00932)
		(end -84.49564 38.77818)
		(width 0.11176)
		(layer "In5.Cu")
		(net "ETH40G_B2_TX0N")
	)
	(segment
		(start -84.2645 37.729571)
		(end -84.49088 37.503191)
		(width 0.11176)
		(layer "In5.Cu")
		(net "ETH40G_B2_TX0N")
	)
	(segment
		(start -84.2645 36.926931)
		(end -84.2645 35.6108)
		(width 0.11176)
		(layer "In5.Cu")
		(net "ETH40G_B2_TX0N")
	)
	(segment
		(start -84.49564 38.3667)
		(end -84.2645 38.13556)
		(width 0.11176)
		(layer "In5.Cu")
		(net "ETH40G_B2_TX0N")
	)
	(segment
		(start -84.49088 37.153312)
		(end -84.2645 36.926931)
		(width 0.11176)
		(layer "In5.Cu")
		(net "ETH40G_B2_TX0N")
	)
	(arc
		(start -86.19268 42.50944)
		(mid -86.008452 42.233724)
		(end -85.94376 41.908494)
		(width 0.11176)
		(layer "In5.Cu")
		(net "ETH40G_B2_TX0N")
	)
	(arc
		(start -84.470819 39.720779)
		(mid -84.31812 39.492249)
		(end -84.2645 39.22268)
		(width 0.11176)
		(layer "In5.Cu")
		(net "ETH40G_B2_TX0N")
	)
	(arc
		(start -83.4644 34.8107)
		(mid -83.164305 34.686397)
		(end -83.040002 34.386302)
		(width 0.11176)
		(layer "In5.Cu")
		(net "ETH40G_B2_TX0N")
	)
	(arc
		(start -85.94376 41.85666)
		(mid -85.821931 41.244183)
		(end -85.47499 40.72495)
		(width 0.11176)
		(layer "In5.Cu")
		(net "ETH40G_B2_TX0N")
	)
	(arc
		(start -84.2645 35.6108)
		(mid -84.030156 35.045044)
		(end -83.4644 34.8107)
		(width 0.11176)
		(layer "In5.Cu")
		(net "ETH40G_B2_TX0N")
	)
	(segment
		(start -97.51314 35.558225)
		(end -99.00158 34.069785)
		(width 0.1016)
		(layer "F.Cu")
		(net "ETH40G_B2_SDA")
	)
	(segment
		(start -97.049999 38.205001)
		(end -97.51314 37.74186)
		(width 0.1016)
		(layer "F.Cu")
		(net "ETH40G_B2_SDA")
	)
	(segment
		(start -97.51314 37.74186)
		(end -97.51314 35.558225)
		(width 0.1016)
		(layer "F.Cu")
		(net "ETH40G_B2_SDA")
	)
	(segment
		(start -97.049999 41.340001)
		(end -97.049999 38.205001)
		(width 0.1016)
		(layer "F.Cu")
		(net "ETH40G_B2_SDA")
	)
	(segment
		(start -109.3978 16.0274)
		(end -110.195599 16.0274)
		(width 0.1016)
		(layer "F.Cu")
		(net "ETH40G_B2_SDA")
	)
	(segment
		(start -99.00158 34.069785)
		(end -99.00158 32.31388)
		(width 0.1016)
		(layer "F.Cu")
		(net "ETH40G_B2_SDA")
	)
	(via
		(at -109.3978 16.0274)
		(size 0.5588)
		(drill 0.254)
		(layers "F.Cu" "B.Cu")
		(net "ETH40G_B2_SDA")
	)
	(via
		(at -99.00158 32.31388)
		(size 0.5588)
		(drill 0.254)
		(layers "F.Cu" "B.Cu")
		(net "ETH40G_B2_SDA")
	)
	(segment
		(start -78.0034 45.974)
		(end -78.0034 40.896604)
		(width 0.12954)
		(layer "In2.Cu")
		(net "ETH40G_B2_SDA")
	)
	(segment
		(start -85.1408 46.7106)
		(end -78.74 46.7106)
		(width 0.12954)
		(layer "In2.Cu")
		(net "ETH40G_B2_SDA")
	)
	(segment
		(start -109.3978 16.0274)
		(end -108.819 16.0274)
		(width 0.12954)
		(layer "In2.Cu")
		(net "ETH40G_B2_SDA")
	)
	(segment
		(start -87.3125 37.6047)
		(end -87.3125 44.5389)
		(width 0.12954)
		(layer "In2.Cu")
		(net "ETH40G_B2_SDA")
	)
	(segment
		(start -99.00158 32.31388)
		(end -96.706624 34.608836)
		(width 0.12954)
		(layer "In2.Cu")
		(net "ETH40G_B2_SDA")
	)
	(segment
		(start -78.0034 40.896604)
		(end -79.040002 39.860002)
		(width 0.12954)
		(layer "In2.Cu")
		(net "ETH40G_B2_SDA")
	)
	(segment
		(start -95.766824 34.608836)
		(end -94.71406 35.6616)
		(width 0.12954)
		(layer "In2.Cu")
		(net "ETH40G_B2_SDA")
	)
	(segment
		(start -87.3125 44.5389)
		(end -85.1408 46.7106)
		(width 0.12954)
		(layer "In2.Cu")
		(net "ETH40G_B2_SDA")
	)
	(segment
		(start -89.2556 35.6616)
		(end -87.3125 37.6047)
		(width 0.12954)
		(layer "In2.Cu")
		(net "ETH40G_B2_SDA")
	)
	(segment
		(start -94.71406 35.6616)
		(end -89.2556 35.6616)
		(width 0.12954)
		(layer "In2.Cu")
		(net "ETH40G_B2_SDA")
	)
	(segment
		(start -78.74 46.7106)
		(end -78.0034 45.974)
		(width 0.12954)
		(layer "In2.Cu")
		(net "ETH40G_B2_SDA")
	)
	(segment
		(start -100.6402 30.67526)
		(end -99.00158 32.31388)
		(width 0.12954)
		(layer "In2.Cu")
		(net "ETH40G_B2_SDA")
	)
	(segment
		(start -108.819 16.0274)
		(end -100.6402 24.2062)
		(width 0.12954)
		(layer "In2.Cu")
		(net "ETH40G_B2_SDA")
	)
	(segment
		(start -100.6402 24.2062)
		(end -100.6402 30.67526)
		(width 0.12954)
		(layer "In2.Cu")
		(net "ETH40G_B2_SDA")
	)
	(segment
		(start -96.706624 34.608836)
		(end -95.766824 34.608836)
		(width 0.12954)
		(layer "In2.Cu")
		(net "ETH40G_B2_SDA")
	)
	(segment
		(start -97.2566 37.4904)
		(end -97.2566 33.20796)
		(width 0.1016)
		(layer "F.Cu")
		(net "ETH40G_B2_SCL")
	)
	(segment
		(start -108.966 14.6304)
		(end -110.195599 14.6304)
		(width 0.1016)
		(layer "F.Cu")
		(net "ETH40G_B2_SCL")
	)
	(segment
		(start -96.250001 41.340001)
		(end -96.250001 38.496999)
		(width 0.1016)
		(layer "F.Cu")
		(net "ETH40G_B2_SCL")
	)
	(segment
		(start -97.2566 33.20796)
		(end -98.9584 31.50616)
		(width 0.1016)
		(layer "F.Cu")
		(net "ETH40G_B2_SCL")
	)
	(segment
		(start -98.9584 31.50616)
		(end -98.9584 31.40456)
		(width 0.1016)
		(layer "F.Cu")
		(net "ETH40G_B2_SCL")
	)
	(segment
		(start -96.250001 38.496999)
		(end -97.2566 37.4904)
		(width 0.1016)
		(layer "F.Cu")
		(net "ETH40G_B2_SCL")
	)
	(via
		(at -108.966 14.6304)
		(size 0.5588)
		(drill 0.254)
		(layers "F.Cu" "B.Cu")
		(net "ETH40G_B2_SCL")
	)
	(via
		(at -98.9584 31.40456)
		(size 0.5588)
		(drill 0.254)
		(layers "F.Cu" "B.Cu")
		(net "ETH40G_B2_SCL")
	)
	(segment
		(start -86.0806 34.671)
		(end -88.5444 34.671)
		(width 0.12954)
		(layer "In2.Cu")
		(net "ETH40G_B2_SCL")
	)
	(segment
		(start -79.040002 38.460002)
		(end -80.0354 39.4554)
		(width 0.12954)
		(layer "In2.Cu")
		(net "ETH40G_B2_SCL")
	)
	(segment
		(start -88.5444 34.671)
		(end -89.23274 35.35934)
		(width 0.12954)
		(layer "In2.Cu")
		(net "ETH40G_B2_SCL")
	)
	(segment
		(start -108.966 14.6304)
		(end -108.8952 14.6304)
		(width 0.12954)
		(layer "In2.Cu")
		(net "ETH40G_B2_SCL")
	)
	(segment
		(start -80.0354 45.8978)
		(end -80.4926 46.355)
		(width 0.12954)
		(layer "In2.Cu")
		(net "ETH40G_B2_SCL")
	)
	(segment
		(start -93.46946 35.35934)
		(end -96.286335 32.542465)
		(width 0.12954)
		(layer "In2.Cu")
		(net "ETH40G_B2_SCL")
	)
	(segment
		(start -80.0354 39.4554)
		(end -80.0354 45.8978)
		(width 0.12954)
		(layer "In2.Cu")
		(net "ETH40G_B2_SCL")
	)
	(segment
		(start -84.22132 43.24604)
		(end -84.22132 36.53028)
		(width 0.12954)
		(layer "In2.Cu")
		(net "ETH40G_B2_SCL")
	)
	(segment
		(start -96.286335 32.542465)
		(end -97.820495 32.542465)
		(width 0.12954)
		(layer "In2.Cu")
		(net "ETH40G_B2_SCL")
	)
	(segment
		(start -80.4926 46.355)
		(end -84.709 46.355)
		(width 0.12954)
		(layer "In2.Cu")
		(net "ETH40G_B2_SCL")
	)
	(segment
		(start -89.23274 35.35934)
		(end -93.46946 35.35934)
		(width 0.12954)
		(layer "In2.Cu")
		(net "ETH40G_B2_SCL")
	)
	(segment
		(start -84.22132 36.53028)
		(end -86.0806 34.671)
		(width 0.12954)
		(layer "In2.Cu")
		(net "ETH40G_B2_SCL")
	)
	(segment
		(start -97.820495 32.542465)
		(end -98.9584 31.40456)
		(width 0.12954)
		(layer "In2.Cu")
		(net "ETH40G_B2_SCL")
	)
	(segment
		(start -99.506999 24.018601)
		(end -99.506999 30.855961)
		(width 0.12954)
		(layer "In2.Cu")
		(net "ETH40G_B2_SCL")
	)
	(segment
		(start -85.27542 44.30014)
		(end -84.22132 43.24604)
		(width 0.12954)
		(layer "In2.Cu")
		(net "ETH40G_B2_SCL")
	)
	(segment
		(start -99.506999 30.855961)
		(end -98.9584 31.40456)
		(width 0.12954)
		(layer "In2.Cu")
		(net "ETH40G_B2_SCL")
	)
	(segment
		(start -108.8952 14.6304)
		(end -99.506999 24.018601)
		(width 0.12954)
		(layer "In2.Cu")
		(net "ETH40G_B2_SCL")
	)
	(segment
		(start -84.709 46.355)
		(end -85.27542 45.78858)
		(width 0.12954)
		(layer "In2.Cu")
		(net "ETH40G_B2_SCL")
	)
	(segment
		(start -85.27542 45.78858)
		(end -85.27542 44.30014)
		(width 0.12954)
		(layer "In2.Cu")
		(net "ETH40G_B2_SCL")
	)
	(segment
		(start -98.2399 45.92066)
		(end -98.432828 46.113588)
		(width 0.10668)
		(layer "F.Cu")
		(net "ETH40G_B2_RX3P")
	)
	(segment
		(start -98.087388 48.04918)
		(end -97.44374 48.04918)
		(width 0.10668)
		(layer "F.Cu")
		(net "ETH40G_B2_RX3P")
	)
	(segment
		(start -96.94704 47.84344)
		(end -96.936814 47.833214)
		(width 0.10668)
		(layer "F.Cu")
		(net "ETH40G_B2_RX3P")
	)
	(segment
		(start -96.40348 47.6123)
		(end -95.867182 47.6123)
		(width 0.10668)
		(layer "F.Cu")
		(net "ETH40G_B2_RX3P")
	)
	(segment
		(start -98.249999 43.840001)
		(end -98.249999 44.865399)
		(width 0.10668)
		(layer "F.Cu")
		(net "ETH40G_B2_RX3P")
	)
	(segment
		(start -98.249999 44.865399)
		(end -98.432828 45.048228)
		(width 0.10668)
		(layer "F.Cu")
		(net "ETH40G_B2_RX3P")
	)
	(segment
		(start -98.432828 45.256508)
		(end -98.2399 45.449437)
		(width 0.10668)
		(layer "F.Cu")
		(net "ETH40G_B2_RX3P")
	)
	(segment
		(start -98.432828 45.048228)
		(end -98.432828 45.256508)
		(width 0.10668)
		(layer "F.Cu")
		(net "ETH40G_B2_RX3P")
	)
	(segment
		(start -98.2399 45.449437)
		(end -98.2399 45.92066)
		(width 0.10668)
		(layer "F.Cu")
		(net "ETH40G_B2_RX3P")
	)
	(segment
		(start -98.432828 46.113588)
		(end -98.432828 47.70374)
		(width 0.10668)
		(layer "F.Cu")
		(net "ETH40G_B2_RX3P")
	)
	(via
		(at -95.41034 47.42307)
		(size 0.5588)
		(drill 0.254)
		(layers "F.Cu" "B.Cu")
		(net "ETH40G_B2_RX3P")
	)
	(arc
		(start -98.432828 47.70374)
		(mid -98.331651 47.948003)
		(end -98.087388 48.04918)
		(width 0.10668)
		(layer "F.Cu")
		(net "ETH40G_B2_RX3P")
	)
	(arc
		(start -95.867182 47.6123)
		(mid -95.619941 47.563121)
		(end -95.41034 47.42307)
		(width 0.10668)
		(layer "F.Cu")
		(net "ETH40G_B2_RX3P")
	)
	(arc
		(start -96.936814 47.833214)
		(mid -96.692118 47.669714)
		(end -96.40348 47.6123)
		(width 0.10668)
		(layer "F.Cu")
		(net "ETH40G_B2_RX3P")
	)
	(arc
		(start -97.44374 48.04918)
		(mid -97.174928 47.99571)
		(end -96.94704 47.84344)
		(width 0.10668)
		(layer "F.Cu")
		(net "ETH40G_B2_RX3P")
	)
	(segment
		(start -89.120729 47.9425)
		(end -88.892129 48.1711)
		(width 0.11176)
		(layer "In5.Cu")
		(net "ETH40G_B2_RX3P")
	)
	(segment
		(start -76.413058 46.3677)
		(end -76.184458 46.1391)
		(width 0.11176)
		(layer "In5.Cu")
		(net "ETH40G_B2_RX3P")
	)
	(segment
		(start -89.765889 48.1711)
		(end -89.537289 47.9425)
		(width 0.11176)
		(layer "In5.Cu")
		(net "ETH40G_B2_RX3P")
	)
	(segment
		(start -84.817674 46.13656)
		(end -84.586534 46.3677)
		(width 0.11176)
		(layer "In5.Cu")
		(net "ETH40G_B2_RX3P")
	)
	(segment
		(start -80.106175 46.3677)
		(end -79.877575 46.1391)
		(width 0.11176)
		(layer "In5.Cu")
		(net "ETH40G_B2_RX3P")
	)
	(segment
		(start -82.287834 46.13656)
		(end -82.056694 46.3677)
		(width 0.11176)
		(layer "In5.Cu")
		(net "ETH40G_B2_RX3P")
	)
	(segment
		(start -76.184458 46.1391)
		(end -75.762818 46.1391)
		(width 0.11176)
		(layer "In5.Cu")
		(net "ETH40G_B2_RX3P")
	)
	(segment
		(start -83.552754 46.13656)
		(end -83.321614 46.3677)
		(width 0.11176)
		(layer "In5.Cu")
		(net "ETH40G_B2_RX3P")
	)
	(segment
		(start -93.566643 48.1711)
		(end -92.952575 48.1711)
		(width 0.11176)
		(layer "In5.Cu")
		(net "ETH40G_B2_RX3P")
	)
	(segment
		(start -82.056694 46.3677)
		(end -80.106175 46.3677)
		(width 0.11176)
		(layer "In5.Cu")
		(net "ETH40G_B2_RX3P")
	)
	(segment
		(start -78.170695 46.1391)
		(end -77.942095 46.3677)
		(width 0.11176)
		(layer "In5.Cu")
		(net "ETH40G_B2_RX3P")
	)
	(segment
		(start -90.411049 47.9425)
		(end -90.182449 48.1711)
		(width 0.11176)
		(layer "In5.Cu")
		(net "ETH40G_B2_RX3P")
	)
	(segment
		(start -90.182449 48.1711)
		(end -89.765889 48.1711)
		(width 0.11176)
		(layer "In5.Cu")
		(net "ETH40G_B2_RX3P")
	)
	(segment
		(start -95.41034 47.42307)
		(end -95.369337 47.464073)
		(width 0.11176)
		(layer "In5.Cu")
		(net "ETH40G_B2_RX3P")
	)
	(segment
		(start -85.203754 46.13656)
		(end -84.817674 46.13656)
		(width 0.11176)
		(layer "In5.Cu")
		(net "ETH40G_B2_RX3P")
	)
	(segment
		(start -92.480135 47.99838)
		(end -92.307415 48.1711)
		(width 0.11176)
		(layer "In5.Cu")
		(net "ETH40G_B2_RX3P")
	)
	(segment
		(start -85.676524 46.3677)
		(end -85.434894 46.3677)
		(width 0.11176)
		(layer "In5.Cu")
		(net "ETH40G_B2_RX3P")
	)
	(segment
		(start -82.905054 46.3677)
		(end -82.673914 46.13656)
		(width 0.11176)
		(layer "In5.Cu")
		(net "ETH40G_B2_RX3P")
	)
	(segment
		(start -94.9379 47.64278)
		(end -94.842119 47.64278)
		(width 0.11176)
		(layer "In5.Cu")
		(net "ETH40G_B2_RX3P")
	)
	(segment
		(start -83.938834 46.13656)
		(end -83.552754 46.13656)
		(width 0.11176)
		(layer "In5.Cu")
		(net "ETH40G_B2_RX3P")
	)
	(segment
		(start -75.762818 46.1391)
		(end -75.534218 46.3677)
		(width 0.11176)
		(layer "In5.Cu")
		(net "ETH40G_B2_RX3P")
	)
	(segment
		(start -78.587255 46.1391)
		(end -78.170695 46.1391)
		(width 0.11176)
		(layer "In5.Cu")
		(net "ETH40G_B2_RX3P")
	)
	(segment
		(start -92.307415 48.1711)
		(end -91.056209 48.1711)
		(width 0.11176)
		(layer "In5.Cu")
		(net "ETH40G_B2_RX3P")
	)
	(segment
		(start -77.942095 46.3677)
		(end -76.413058 46.3677)
		(width 0.11176)
		(layer "In5.Cu")
		(net "ETH40G_B2_RX3P")
	)
	(segment
		(start -84.586534 46.3677)
		(end -84.169974 46.3677)
		(width 0.11176)
		(layer "In5.Cu")
		(net "ETH40G_B2_RX3P")
	)
	(segment
		(start -92.952575 48.1711)
		(end -92.779855 47.99838)
		(width 0.11176)
		(layer "In5.Cu")
		(net "ETH40G_B2_RX3P")
	)
	(segment
		(start -84.169974 46.3677)
		(end -83.938834 46.13656)
		(width 0.11176)
		(layer "In5.Cu")
		(net "ETH40G_B2_RX3P")
	)
	(segment
		(start -90.827609 47.9425)
		(end -90.411049 47.9425)
		(width 0.11176)
		(layer "In5.Cu")
		(net "ETH40G_B2_RX3P")
	)
	(segment
		(start -75.040002 44.059302)
		(end -75.040002 44.060001)
		(width 0.11176)
		(layer "In5.Cu")
		(net "ETH40G_B2_RX3P")
	)
	(segment
		(start -92.779855 47.99838)
		(end -92.480135 47.99838)
		(width 0.11176)
		(layer "In5.Cu")
		(net "ETH40G_B2_RX3P")
	)
	(segment
		(start -82.673914 46.13656)
		(end -82.287834 46.13656)
		(width 0.11176)
		(layer "In5.Cu")
		(net "ETH40G_B2_RX3P")
	)
	(segment
		(start -91.056209 48.1711)
		(end -90.827609 47.9425)
		(width 0.11176)
		(layer "In5.Cu")
		(net "ETH40G_B2_RX3P")
	)
	(segment
		(start -83.321614 46.3677)
		(end -82.905054 46.3677)
		(width 0.11176)
		(layer "In5.Cu")
		(net "ETH40G_B2_RX3P")
	)
	(segment
		(start -89.537289 47.9425)
		(end -89.120729 47.9425)
		(width 0.11176)
		(layer "In5.Cu")
		(net "ETH40G_B2_RX3P")
	)
	(segment
		(start -87.66842 47.91202)
		(end -86.977309 47.220909)
		(width 0.11176)
		(layer "In5.Cu")
		(net "ETH40G_B2_RX3P")
	)
	(segment
		(start -85.434894 46.3677)
		(end -85.203754 46.13656)
		(width 0.11176)
		(layer "In5.Cu")
		(net "ETH40G_B2_RX3P")
	)
	(segment
		(start -79.877575 46.1391)
		(end -79.461015 46.1391)
		(width 0.11176)
		(layer "In5.Cu")
		(net "ETH40G_B2_RX3P")
	)
	(segment
		(start -79.461015 46.1391)
		(end -79.232415 46.3677)
		(width 0.11176)
		(layer "In5.Cu")
		(net "ETH40G_B2_RX3P")
	)
	(segment
		(start -75.534218 46.3677)
		(end -74.4728 46.3677)
		(width 0.11176)
		(layer "In5.Cu")
		(net "ETH40G_B2_RX3P")
	)
	(segment
		(start -74.2188 46.1137)
		(end -74.2188 43.8585)
		(width 0.11176)
		(layer "In5.Cu")
		(net "ETH40G_B2_RX3P")
	)
	(segment
		(start -88.892129 48.1711)
		(end -88.293895 48.1711)
		(width 0.11176)
		(layer "In5.Cu")
		(net "ETH40G_B2_RX3P")
	)
	(segment
		(start -86.977309 47.220909)
		(end -86.440589 46.684187)
		(width 0.11176)
		(layer "In5.Cu")
		(net "ETH40G_B2_RX3P")
	)
	(segment
		(start -78.815855 46.3677)
		(end -78.587255 46.1391)
		(width 0.11176)
		(layer "In5.Cu")
		(net "ETH40G_B2_RX3P")
	)
	(segment
		(start -79.232415 46.3677)
		(end -78.815855 46.3677)
		(width 0.11176)
		(layer "In5.Cu")
		(net "ETH40G_B2_RX3P")
	)
	(arc
		(start -88.293895 48.1711)
		(mid -87.95539 48.103767)
		(end -87.66842 47.91202)
		(width 0.11176)
		(layer "In5.Cu")
		(net "ETH40G_B2_RX3P")
	)
	(arc
		(start -86.440589 46.684187)
		(mid -86.090033 46.449953)
		(end -85.676524 46.3677)
		(width 0.11176)
		(layer "In5.Cu")
		(net "ETH40G_B2_RX3P")
	)
	(arc
		(start -74.4728 46.3677)
		(mid -74.293195 46.293305)
		(end -74.2188 46.1137)
		(width 0.11176)
		(layer "In5.Cu")
		(net "ETH40G_B2_RX3P")
	)
	(arc
		(start -74.529 43.5483)
		(mid -74.890333 43.697969)
		(end -75.040002 44.059302)
		(width 0.11176)
		(layer "In5.Cu")
		(net "ETH40G_B2_RX3P")
	)
	(arc
		(start -94.1124 47.94504)
		(mid -93.862005 48.112349)
		(end -93.566643 48.1711)
		(width 0.11176)
		(layer "In5.Cu")
		(net "ETH40G_B2_RX3P")
	)
	(arc
		(start -95.369337 47.464073)
		(mid -95.171392 47.596336)
		(end -94.9379 47.64278)
		(width 0.11176)
		(layer "In5.Cu")
		(net "ETH40G_B2_RX3P")
	)
	(arc
		(start -94.842119 47.64278)
		(mid -94.447198 47.721335)
		(end -94.1124 47.94504)
		(width 0.11176)
		(layer "In5.Cu")
		(net "ETH40G_B2_RX3P")
	)
	(arc
		(start -74.2188 43.8585)
		(mid -74.309655 43.639155)
		(end -74.529 43.5483)
		(width 0.11176)
		(layer "In5.Cu")
		(net "ETH40G_B2_RX3P")
	)
	(segment
		(start -96.639913 48.150567)
		(end -96.629687 48.140341)
		(width 0.10668)
		(layer "F.Cu")
		(net "ETH40G_B2_RX3N")
	)
	(segment
		(start -96.40348 48.04664)
		(end -95.867182 48.04664)
		(width 0.10668)
		(layer "F.Cu")
		(net "ETH40G_B2_RX3N")
	)
	(segment
		(start -98.087388 48.48352)
		(end -97.443737 48.48352)
		(width 0.10668)
		(layer "F.Cu")
		(net "ETH40G_B2_RX3N")
	)
	(segment
		(start -98.867168 45.048228)
		(end -98.867168 47.70374)
		(width 0.10668)
		(layer "F.Cu")
		(net "ETH40G_B2_RX3N")
	)
	(segment
		(start -99.05 44.865397)
		(end -98.867168 45.048228)
		(width 0.10668)
		(layer "F.Cu")
		(net "ETH40G_B2_RX3N")
	)
	(segment
		(start -99.05 43.840001)
		(end -99.05 44.865397)
		(width 0.10668)
		(layer "F.Cu")
		(net "ETH40G_B2_RX3N")
	)
	(via
		(at -95.41034 48.23587)
		(size 0.5588)
		(drill 0.254)
		(layers "F.Cu" "B.Cu")
		(net "ETH40G_B2_RX3N")
	)
	(arc
		(start -98.867168 47.70374)
		(mid -98.638776 48.255128)
		(end -98.087388 48.48352)
		(width 0.10668)
		(layer "F.Cu")
		(net "ETH40G_B2_RX3N")
	)
	(arc
		(start -96.629687 48.140341)
		(mid -96.525902 48.070994)
		(end -96.40348 48.04664)
		(width 0.10668)
		(layer "F.Cu")
		(net "ETH40G_B2_RX3N")
	)
	(arc
		(start -97.443737 48.48352)
		(mid -97.008711 48.396988)
		(end -96.639913 48.150567)
		(width 0.10668)
		(layer "F.Cu")
		(net "ETH40G_B2_RX3N")
	)
	(arc
		(start -95.867182 48.04664)
		(mid -95.619941 48.095819)
		(end -95.41034 48.23587)
		(width 0.10668)
		(layer "F.Cu")
		(net "ETH40G_B2_RX3N")
	)
	(segment
		(start -85.676522 46.7106)
		(end -74.4728 46.7106)
		(width 0.11176)
		(layer "In5.Cu")
		(net "ETH40G_B2_RX3N")
	)
	(segment
		(start -95.41034 48.23587)
		(end -95.238727 48.064257)
		(width 0.11176)
		(layer "In5.Cu")
		(net "ETH40G_B2_RX3N")
	)
	(segment
		(start -87.425952 48.154488)
		(end -86.198121 46.926655)
		(width 0.11176)
		(layer "In5.Cu")
		(net "ETH40G_B2_RX3N")
	)
	(segment
		(start -93.566645 48.514)
		(end -88.293898 48.514)
		(width 0.11176)
		(layer "In5.Cu")
		(net "ETH40G_B2_RX3N")
	)
	(segment
		(start -73.8759 46.1137)
		(end -73.8759 43.8585)
		(width 0.11176)
		(layer "In5.Cu")
		(net "ETH40G_B2_RX3N")
	)
	(segment
		(start -75.040002 42.694398)
		(end -75.040002 42.660001)
		(width 0.11176)
		(layer "In5.Cu")
		(net "ETH40G_B2_RX3N")
	)
	(segment
		(start -95.049025 47.98568)
		(end -94.842122 47.98568)
		(width 0.11176)
		(layer "In5.Cu")
		(net "ETH40G_B2_RX3N")
	)
	(arc
		(start -95.238727 48.064257)
		(mid -95.151691 48.006102)
		(end -95.049025 47.98568)
		(width 0.11176)
		(layer "In5.Cu")
		(net "ETH40G_B2_RX3N")
	)
	(arc
		(start -86.198121 46.926655)
		(mid -85.958809 46.766752)
		(end -85.676522 46.7106)
		(width 0.11176)
		(layer "In5.Cu")
		(net "ETH40G_B2_RX3N")
	)
	(arc
		(start -94.842122 47.98568)
		(mid -94.578422 48.038133)
		(end -94.354868 48.187508)
		(width 0.11176)
		(layer "In5.Cu")
		(net "ETH40G_B2_RX3N")
	)
	(arc
		(start -73.8759 43.8585)
		(mid -74.067189 43.396689)
		(end -74.529 43.2054)
		(width 0.11176)
		(layer "In5.Cu")
		(net "ETH40G_B2_RX3N")
	)
	(arc
		(start -88.293898 48.514)
		(mid -87.824169 48.420567)
		(end -87.425952 48.154488)
		(width 0.11176)
		(layer "In5.Cu")
		(net "ETH40G_B2_RX3N")
	)
	(arc
		(start -74.4728 46.7106)
		(mid -74.050728 46.535772)
		(end -73.8759 46.1137)
		(width 0.11176)
		(layer "In5.Cu")
		(net "ETH40G_B2_RX3N")
	)
	(arc
		(start -74.529 43.2054)
		(mid -74.890333 43.055731)
		(end -75.040002 42.694398)
		(width 0.11176)
		(layer "In5.Cu")
		(net "ETH40G_B2_RX3N")
	)
	(arc
		(start -94.354868 48.187508)
		(mid -93.993228 48.429148)
		(end -93.566645 48.514)
		(width 0.11176)
		(layer "In5.Cu")
		(net "ETH40G_B2_RX3N")
	)
	(segment
		(start -98.681248 40.283359)
		(end -98.801583 40.163024)
		(width 0.10668)
		(layer "F.Cu")
		(net "ETH40G_B2_RX2P")
	)
	(segment
		(start -98.83283 40.087588)
		(end -98.83283 37.151991)
		(width 0.10668)
		(layer "F.Cu")
		(net "ETH40G_B2_RX2P")
	)
	(segment
		(start -98.650001 41.340001)
		(end -98.650001 40.358794)
		(width 0.10668)
		(layer "F.Cu")
		(net "ETH40G_B2_RX2P")
	)
	(via
		(at -98.640054 36.686589)
		(size 0.5588)
		(drill 0.254)
		(layers "F.Cu" "B.Cu")
		(net "ETH40G_B2_RX2P")
	)
	(arc
		(start -98.801583 40.163024)
		(mid -98.82471 40.128414)
		(end -98.83283 40.087588)
		(width 0.10668)
		(layer "F.Cu")
		(net "ETH40G_B2_RX2P")
	)
	(arc
		(start -98.83283 37.151991)
		(mid -98.782729 36.900117)
		(end -98.640054 36.686589)
		(width 0.10668)
		(layer "F.Cu")
		(net "ETH40G_B2_RX2P")
	)
	(arc
		(start -98.650001 40.358794)
		(mid -98.658122 40.317969)
		(end -98.681248 40.283359)
		(width 0.10668)
		(layer "F.Cu")
		(net "ETH40G_B2_RX2P")
	)
	(segment
		(start -85.98694 31.01594)
		(end -86.34 31.01594)
		(width 0.10668)
		(layer "B.Cu")
		(net "ETH40G_B2_RX2P")
	)
	(segment
		(start -84.3842 31.0388)
		(end -84.66106 30.76194)
		(width 0.10668)
		(layer "B.Cu")
		(net "ETH40G_B2_RX2P")
	)
	(segment
		(start -97.672769 34.13506)
		(end -97.901369 33.90646)
		(width 0.10668)
		(layer "B.Cu")
		(net "ETH40G_B2_RX2P")
	)
	(segment
		(start -80.290754 30.76194)
		(end -83.673 30.76194)
		(width 0.10668)
		(layer "B.Cu")
		(net "ETH40G_B2_RX2P")
	)
	(segment
		(start -84.66106 30.76194)
		(end -85.73294 30.76194)
		(width 0.10668)
		(layer "B.Cu")
		(net "ETH40G_B2_RX2P")
	)
	(segment
		(start -98.74282 35.33648)
		(end -98.82156 35.41522)
		(width 0.10668)
		(layer "B.Cu")
		(net "ETH40G_B2_RX2P")
	)
	(segment
		(start -83.673 30.76194)
		(end -83.94986 31.0388)
		(width 0.10668)
		(layer "B.Cu")
		(net "ETH40G_B2_RX2P")
	)
	(segment
		(start -78.23994 44.2722)
		(end -78.23994 32.525386)
		(width 0.10668)
		(layer "B.Cu")
		(net "ETH40G_B2_RX2P")
	)
	(segment
		(start -98.74282 34.8234)
		(end -98.74282 35.33648)
		(width 0.10668)
		(layer "B.Cu")
		(net "ETH40G_B2_RX2P")
	)
	(segment
		(start -97.901369 33.90646)
		(end -98.19164 33.90646)
		(width 0.10668)
		(layer "B.Cu")
		(net "ETH40G_B2_RX2P")
	)
	(segment
		(start -97.032689 33.90646)
		(end -97.261289 34.13506)
		(width 0.10668)
		(layer "B.Cu")
		(net "ETH40G_B2_RX2P")
	)
	(segment
		(start -86.34 31.01594)
		(end -86.594 30.76194)
		(width 0.10668)
		(layer "B.Cu")
		(net "ETH40G_B2_RX2P")
	)
	(segment
		(start -77.040001 45.360001)
		(end -77.438908 44.961094)
		(width 0.10668)
		(layer "B.Cu")
		(net "ETH40G_B2_RX2P")
	)
	(segment
		(start -83.94986 31.0388)
		(end -84.3842 31.0388)
		(width 0.10668)
		(layer "B.Cu")
		(net "ETH40G_B2_RX2P")
	)
	(segment
		(start -98.82156 35.41522)
		(end -98.82156 36.31438)
		(width 0.10668)
		(layer "B.Cu")
		(net "ETH40G_B2_RX2P")
	)
	(segment
		(start -96.218941 33.90646)
		(end -97.032689 33.90646)
		(width 0.10668)
		(layer "B.Cu")
		(net "ETH40G_B2_RX2P")
	)
	(segment
		(start -98.82156 34.53638)
		(end -98.82156 34.74466)
		(width 0.10668)
		(layer "B.Cu")
		(net "ETH40G_B2_RX2P")
	)
	(segment
		(start -98.82156 34.74466)
		(end -98.74282 34.8234)
		(width 0.10668)
		(layer "B.Cu")
		(net "ETH40G_B2_RX2P")
	)
	(segment
		(start -86.594 30.76194)
		(end -88.6274 30.76194)
		(width 0.10668)
		(layer "B.Cu")
		(net "ETH40G_B2_RX2P")
	)
	(segment
		(start -97.261289 34.13506)
		(end -97.672769 34.13506)
		(width 0.10668)
		(layer "B.Cu")
		(net "ETH40G_B2_RX2P")
	)
	(segment
		(start -98.686711 36.639929)
		(end -98.640054 36.686589)
		(width 0.10668)
		(layer "B.Cu")
		(net "ETH40G_B2_RX2P")
	)
	(segment
		(start -85.73294 30.76194)
		(end -85.98694 31.01594)
		(width 0.10668)
		(layer "B.Cu")
		(net "ETH40G_B2_RX2P")
	)
	(arc
		(start -77.438908 44.961094)
		(mid -77.526738 44.902408)
		(end -77.63034 44.8818)
		(width 0.10668)
		(layer "B.Cu")
		(net "ETH40G_B2_RX2P")
	)
	(arc
		(start -98.19164 33.90646)
		(mid -98.637061 34.090959)
		(end -98.82156 34.53638)
		(width 0.10668)
		(layer "B.Cu")
		(net "ETH40G_B2_RX2P")
	)
	(arc
		(start -94.17082 33.0581)
		(mid -95.110506 33.685978)
		(end -96.218941 33.90646)
		(width 0.10668)
		(layer "B.Cu")
		(net "ETH40G_B2_RX2P")
	)
	(arc
		(start -78.23994 32.525386)
		(mid -78.358706 31.928307)
		(end -78.696924 31.422127)
		(width 0.10668)
		(layer "B.Cu")
		(net "ETH40G_B2_RX2P")
	)
	(arc
		(start -77.63034 44.8818)
		(mid -78.061392 44.703252)
		(end -78.23994 44.2722)
		(width 0.10668)
		(layer "B.Cu")
		(net "ETH40G_B2_RX2P")
	)
	(arc
		(start -78.696924 31.422127)
		(mid -79.428179 30.933516)
		(end -80.290754 30.76194)
		(width 0.10668)
		(layer "B.Cu")
		(net "ETH40G_B2_RX2P")
	)
	(arc
		(start -88.6274 30.76194)
		(mid -91.627477 31.358692)
		(end -94.17082 33.0581)
		(width 0.10668)
		(layer "B.Cu")
		(net "ETH40G_B2_RX2P")
	)
	(arc
		(start -98.82156 36.31438)
		(mid -98.786513 36.490566)
		(end -98.686711 36.639929)
		(width 0.10668)
		(layer "B.Cu")
		(net "ETH40G_B2_RX2P")
	)
	(segment
		(start -99.449999 41.340001)
		(end -99.449999 40.358794)
		(width 0.10668)
		(layer "F.Cu")
		(net "ETH40G_B2_RX2N")
	)
	(segment
		(start -99.418752 40.283359)
		(end -99.298417 40.163024)
		(width 0.10668)
		(layer "F.Cu")
		(net "ETH40G_B2_RX2N")
	)
	(segment
		(start -99.26717 40.087588)
		(end -99.26717 37.134871)
		(width 0.10668)
		(layer "F.Cu")
		(net "ETH40G_B2_RX2N")
	)
	(via
		(at -99.452854 36.686589)
		(size 0.5588)
		(drill 0.254)
		(layers "F.Cu" "B.Cu")
		(net "ETH40G_B2_RX2N")
	)
	(arc
		(start -99.26717 37.134871)
		(mid -99.315428 36.892263)
		(end -99.452854 36.686589)
		(width 0.10668)
		(layer "F.Cu")
		(net "ETH40G_B2_RX2N")
	)
	(arc
		(start -99.449999 40.358794)
		(mid -99.441878 40.317969)
		(end -99.418752 40.283359)
		(width 0.10668)
		(layer "F.Cu")
		(net "ETH40G_B2_RX2N")
	)
	(arc
		(start -99.298417 40.163024)
		(mid -99.27529 40.128414)
		(end -99.26717 40.087588)
		(width 0.10668)
		(layer "F.Cu")
		(net "ETH40G_B2_RX2N")
	)
	(segment
		(start -99.379824 36.613559)
		(end -99.452854 36.686589)
		(width 0.10668)
		(layer "B.Cu")
		(net "ETH40G_B2_RX2N")
	)
	(segment
		(start -77.8056 44.2722)
		(end -77.8056 32.525383)
		(width 0.10668)
		(layer "B.Cu")
		(net "ETH40G_B2_RX2N")
	)
	(segment
		(start -80.290751 30.3276)
		(end -88.627402 30.3276)
		(width 0.10668)
		(layer "B.Cu")
		(net "ETH40G_B2_RX2N")
	)
	(segment
		(start -99.2559 34.53638)
		(end -99.2559 36.31438)
		(width 0.10668)
		(layer "B.Cu")
		(net "ETH40G_B2_RX2N")
	)
	(segment
		(start -96.218944 33.47212)
		(end -98.19164 33.47212)
		(width 0.10668)
		(layer "B.Cu")
		(net "ETH40G_B2_RX2N")
	)
	(segment
		(start -77.040001 43.960001)
		(end -77.454714 44.374712)
		(width 0.10668)
		(layer "B.Cu")
		(net "ETH40G_B2_RX2N")
	)
	(arc
		(start -94.477947 32.750973)
		(mid -95.276723 33.2847)
		(end -96.218944 33.47212)
		(width 0.10668)
		(layer "B.Cu")
		(net "ETH40G_B2_RX2N")
	)
	(arc
		(start -78.3898 31.115)
		(mid -79.261964 30.532239)
		(end -80.290751 30.3276)
		(width 0.10668)
		(layer "B.Cu")
		(net "ETH40G_B2_RX2N")
	)
	(arc
		(start -88.627402 30.3276)
		(mid -91.793693 30.957414)
		(end -94.477947 32.750973)
		(width 0.10668)
		(layer "B.Cu")
		(net "ETH40G_B2_RX2N")
	)
	(arc
		(start -98.19164 33.47212)
		(mid -98.944185 33.783835)
		(end -99.2559 34.53638)
		(width 0.10668)
		(layer "B.Cu")
		(net "ETH40G_B2_RX2N")
	)
	(arc
		(start -99.2559 36.31438)
		(mid -99.288107 36.476295)
		(end -99.379824 36.613559)
		(width 0.10668)
		(layer "B.Cu")
		(net "ETH40G_B2_RX2N")
	)
	(arc
		(start -77.454714 44.374712)
		(mid -77.535292 44.428553)
		(end -77.63034 44.44746)
		(width 0.10668)
		(layer "B.Cu")
		(net "ETH40G_B2_RX2N")
	)
	(arc
		(start -77.63034 44.44746)
		(mid -77.754268 44.396128)
		(end -77.8056 44.2722)
		(width 0.10668)
		(layer "B.Cu")
		(net "ETH40G_B2_RX2N")
	)
	(arc
		(start -77.8056 32.525383)
		(mid -77.957429 31.762089)
		(end -78.3898 31.115)
		(width 0.10668)
		(layer "B.Cu")
		(net "ETH40G_B2_RX2N")
	)
	(segment
		(start -100.649999 43.840001)
		(end -100.649999 44.821208)
		(width 0.10668)
		(layer "F.Cu")
		(net "ETH40G_B2_RX1P")
	)
	(segment
		(start -100.681246 44.896644)
		(end -100.801581 45.016979)
		(width 0.10668)
		(layer "F.Cu")
		(net "ETH40G_B2_RX1P")
	)
	(segment
		(start -100.832829 46.454568)
		(end -100.643601 46.643795)
		(width 0.10668)
		(layer "F.Cu")
		(net "ETH40G_B2_RX1P")
	)
	(segment
		(start -100.832829 45.092414)
		(end -100.832829 46.454568)
		(width 0.10668)
		(layer "F.Cu")
		(net "ETH40G_B2_RX1P")
	)
	(via
		(at -100.643601 46.643795)
		(size 0.5588)
		(drill 0.254)
		(layers "F.Cu" "B.Cu")
		(net "ETH40G_B2_RX1P")
	)
	(arc
		(start -100.801581 45.016979)
		(mid -100.824707 45.051589)
		(end -100.832829 45.092414)
		(width 0.10668)
		(layer "F.Cu")
		(net "ETH40G_B2_RX1P")
	)
	(arc
		(start -100.649999 44.821208)
		(mid -100.65812 44.862034)
		(end -100.681246 44.896644)
		(width 0.10668)
		(layer "F.Cu")
		(net "ETH40G_B2_RX1P")
	)
	(segment
		(start -94.417744 43.46702)
		(end -94.554904 43.60418)
		(width 0.10668)
		(layer "B.Cu")
		(net "ETH40G_B2_RX1P")
	)
	(segment
		(start -94.966384 43.60418)
		(end -95.103544 43.46702)
		(width 0.10668)
		(layer "B.Cu")
		(net "ETH40G_B2_RX1P")
	)
	(segment
		(start -95.548033 43.46702)
		(end -95.776633 43.69562)
		(width 0.10668)
		(layer "B.Cu")
		(net "ETH40G_B2_RX1P")
	)
	(segment
		(start -81.04 45.360001)
		(end -81.491582 44.908419)
		(width 0.10668)
		(layer "B.Cu")
		(net "ETH40G_B2_RX1P")
	)
	(segment
		(start -95.103544 43.46702)
		(end -95.548033 43.46702)
		(width 0.10668)
		(layer "B.Cu")
		(net "ETH40G_B2_RX1P")
	)
	(segment
		(start -97.056793 43.69562)
		(end -97.468273 43.69562)
		(width 0.10668)
		(layer "B.Cu")
		(net "ETH40G_B2_RX1P")
	)
	(segment
		(start -82.7586 46.68774)
		(end -84.5236 46.68774)
		(width 0.10668)
		(layer "B.Cu")
		(net "ETH40G_B2_RX1P")
	)
	(segment
		(start -88.877165 43.46702)
		(end -94.417744 43.46702)
		(width 0.10668)
		(layer "B.Cu")
		(net "ETH40G_B2_RX1P")
	)
	(segment
		(start -98.108353 43.46702)
		(end -98.336953 43.69562)
		(width 0.10668)
		(layer "B.Cu")
		(net "ETH40G_B2_RX1P")
	)
	(segment
		(start -96.188113 43.69562)
		(end -96.416713 43.46702)
		(width 0.10668)
		(layer "B.Cu")
		(net "ETH40G_B2_RX1P")
	)
	(segment
		(start -98.336953 43.69562)
		(end -98.748433 43.69562)
		(width 0.10668)
		(layer "B.Cu")
		(net "ETH40G_B2_RX1P")
	)
	(segment
		(start -81.567017 44.877172)
		(end -81.7934 44.877172)
		(width 0.10668)
		(layer "B.Cu")
		(net "ETH40G_B2_RX1P")
	)
	(segment
		(start -97.468273 43.69562)
		(end -97.696873 43.46702)
		(width 0.10668)
		(layer "B.Cu")
		(net "ETH40G_B2_RX1P")
	)
	(segment
		(start -98.977033 43.46702)
		(end -100.078451 43.46702)
		(width 0.10668)
		(layer "B.Cu")
		(net "ETH40G_B2_RX1P")
	)
	(segment
		(start -94.554904 43.60418)
		(end -94.966384 43.60418)
		(width 0.10668)
		(layer "B.Cu")
		(net "ETH40G_B2_RX1P")
	)
	(segment
		(start -96.416713 43.46702)
		(end -96.828193 43.46702)
		(width 0.10668)
		(layer "B.Cu")
		(net "ETH40G_B2_RX1P")
	)
	(segment
		(start -95.776633 43.69562)
		(end -96.188113 43.69562)
		(width 0.10668)
		(layer "B.Cu")
		(net "ETH40G_B2_RX1P")
	)
	(segment
		(start -97.696873 43.46702)
		(end -98.108353 43.46702)
		(width 0.10668)
		(layer "B.Cu")
		(net "ETH40G_B2_RX1P")
	)
	(segment
		(start -85.992757 46.079197)
		(end -88.412432 43.659522)
		(width 0.10668)
		(layer "B.Cu")
		(net "ETH40G_B2_RX1P")
	)
	(segment
		(start -98.748433 43.69562)
		(end -98.977033 43.46702)
		(width 0.10668)
		(layer "B.Cu")
		(net "ETH40G_B2_RX1P")
	)
	(segment
		(start -100.832831 44.2214)
		(end -100.832831 46.186954)
		(width 0.10668)
		(layer "B.Cu")
		(net "ETH40G_B2_RX1P")
	)
	(segment
		(start -81.91786 45.001632)
		(end -81.91786 45.847)
		(width 0.10668)
		(layer "B.Cu")
		(net "ETH40G_B2_RX1P")
	)
	(segment
		(start -96.828193 43.46702)
		(end -97.056793 43.69562)
		(width 0.10668)
		(layer "B.Cu")
		(net "ETH40G_B2_RX1P")
	)
	(arc
		(start -88.412432 43.659522)
		(mid -88.625653 43.517051)
		(end -88.877165 43.46702)
		(width 0.10668)
		(layer "B.Cu")
		(net "ETH40G_B2_RX1P")
	)
	(arc
		(start -81.7934 44.877172)
		(mid -81.881407 44.913625)
		(end -81.91786 45.001632)
		(width 0.10668)
		(layer "B.Cu")
		(net "ETH40G_B2_RX1P")
	)
	(arc
		(start -100.832831 46.186954)
		(mid -100.783652 46.434195)
		(end -100.643601 46.643795)
		(width 0.10668)
		(layer "B.Cu")
		(net "ETH40G_B2_RX1P")
	)
	(arc
		(start -84.5236 46.68774)
		(mid -85.318701 46.529585)
		(end -85.992757 46.079197)
		(width 0.10668)
		(layer "B.Cu")
		(net "ETH40G_B2_RX1P")
	)
	(arc
		(start -81.491582 44.908419)
		(mid -81.526192 44.885293)
		(end -81.567017 44.877172)
		(width 0.10668)
		(layer "B.Cu")
		(net "ETH40G_B2_RX1P")
	)
	(arc
		(start -81.91786 45.847)
		(mid -82.164107 46.441493)
		(end -82.7586 46.68774)
		(width 0.10668)
		(layer "B.Cu")
		(net "ETH40G_B2_RX1P")
	)
	(arc
		(start -100.078451 43.46702)
		(mid -100.611878 43.687973)
		(end -100.832831 44.2214)
		(width 0.10668)
		(layer "B.Cu")
		(net "ETH40G_B2_RX1P")
	)
	(segment
		(start -101.267169 46.454563)
		(end -101.456401 46.643795)
		(width 0.10668)
		(layer "F.Cu")
		(net "ETH40G_B2_RX1N")
	)
	(segment
		(start -101.45 43.840001)
		(end -101.45 44.821208)
		(width 0.10668)
		(layer "F.Cu")
		(net "ETH40G_B2_RX1N")
	)
	(segment
		(start -101.418753 44.896644)
		(end -101.298416 45.016981)
		(width 0.10668)
		(layer "F.Cu")
		(net "ETH40G_B2_RX1N")
	)
	(segment
		(start -101.267169 45.092417)
		(end -101.267169 46.454563)
		(width 0.10668)
		(layer "F.Cu")
		(net "ETH40G_B2_RX1N")
	)
	(via
		(at -101.456401 46.643795)
		(size 0.5588)
		(drill 0.254)
		(layers "F.Cu" "B.Cu")
		(net "ETH40G_B2_RX1N")
	)
	(arc
		(start -101.45 44.821208)
		(mid -101.441879 44.862034)
		(end -101.418753 44.896644)
		(width 0.10668)
		(layer "F.Cu")
		(net "ETH40G_B2_RX1N")
	)
	(arc
		(start -101.298416 45.016981)
		(mid -101.275289 45.051591)
		(end -101.267169 45.092417)
		(width 0.10668)
		(layer "F.Cu")
		(net "ETH40G_B2_RX1N")
	)
	(segment
		(start -85.68563 45.77207)
		(end -88.105305 43.352395)
		(width 0.10668)
		(layer "B.Cu")
		(net "ETH40G_B2_RX1N")
	)
	(segment
		(start -81.04 43.960001)
		(end -81.491585 44.411585)
		(width 0.10668)
		(layer "B.Cu")
		(net "ETH40G_B2_RX1N")
	)
	(segment
		(start -81.56702 44.442832)
		(end -81.7934 44.442832)
		(width 0.10668)
		(layer "B.Cu")
		(net "ETH40G_B2_RX1N")
	)
	(segment
		(start -101.267171 44.2214)
		(end -101.267171 46.186954)
		(width 0.10668)
		(layer "B.Cu")
		(net "ETH40G_B2_RX1N")
	)
	(segment
		(start -82.7586 46.2534)
		(end -84.523598 46.2534)
		(width 0.10668)
		(layer "B.Cu")
		(net "ETH40G_B2_RX1N")
	)
	(segment
		(start -88.877165 43.03268)
		(end -100.078451 43.03268)
		(width 0.10668)
		(layer "B.Cu")
		(net "ETH40G_B2_RX1N")
	)
	(segment
		(start -82.3522 45.001632)
		(end -82.3522 45.847)
		(width 0.10668)
		(layer "B.Cu")
		(net "ETH40G_B2_RX1N")
	)
	(arc
		(start -101.267171 46.186954)
		(mid -101.31635 46.434195)
		(end -101.456401 46.643795)
		(width 0.10668)
		(layer "B.Cu")
		(net "ETH40G_B2_RX1N")
	)
	(arc
		(start -81.7934 44.442832)
		(mid -82.188531 44.606501)
		(end -82.3522 45.001632)
		(width 0.10668)
		(layer "B.Cu")
		(net "ETH40G_B2_RX1N")
	)
	(arc
		(start -100.078451 43.03268)
		(mid -100.919003 43.380848)
		(end -101.267171 44.2214)
		(width 0.10668)
		(layer "B.Cu")
		(net "ETH40G_B2_RX1N")
	)
	(arc
		(start -81.491585 44.411585)
		(mid -81.526195 44.434711)
		(end -81.56702 44.442832)
		(width 0.10668)
		(layer "B.Cu")
		(net "ETH40G_B2_RX1N")
	)
	(arc
		(start -82.3522 45.847)
		(mid -82.471232 46.134368)
		(end -82.7586 46.2534)
		(width 0.10668)
		(layer "B.Cu")
		(net "ETH40G_B2_RX1N")
	)
	(arc
		(start -84.523598 46.2534)
		(mid -85.152485 46.128307)
		(end -85.68563 45.77207)
		(width 0.10668)
		(layer "B.Cu")
		(net "ETH40G_B2_RX1N")
	)
	(arc
		(start -88.105305 43.352395)
		(mid -88.459437 43.115771)
		(end -88.877165 43.03268)
		(width 0.10668)
		(layer "B.Cu")
		(net "ETH40G_B2_RX1N")
	)
	(segment
		(start -101.23283 40.087588)
		(end -101.23283 39.008962)
		(width 0.10668)
		(layer "F.Cu")
		(net "ETH40G_B2_RX0P")
	)
	(segment
		(start -101.081248 40.283359)
		(end -101.201583 40.163024)
		(width 0.10668)
		(layer "F.Cu")
		(net "ETH40G_B2_RX0P")
	)
	(segment
		(start -101.050001 41.340001)
		(end -101.050001 40.358794)
		(width 0.10668)
		(layer "F.Cu")
		(net "ETH40G_B2_RX0P")
	)
	(via
		(at -101.0436 38.55212)
		(size 0.5588)
		(drill 0.254)
		(layers "F.Cu" "B.Cu")
		(net "ETH40G_B2_RX0P")
	)
	(arc
		(start -101.23283 39.008962)
		(mid -101.183651 38.761721)
		(end -101.0436 38.55212)
		(width 0.10668)
		(layer "F.Cu")
		(net "ETH40G_B2_RX0P")
	)
	(arc
		(start -101.201583 40.163024)
		(mid -101.22471 40.128414)
		(end -101.23283 40.087588)
		(width 0.10668)
		(layer "F.Cu")
		(net "ETH40G_B2_RX0P")
	)
	(arc
		(start -101.050001 40.358794)
		(mid -101.058122 40.317969)
		(end -101.081248 40.283359)
		(width 0.10668)
		(layer "F.Cu")
		(net "ETH40G_B2_RX0P")
	)
	(segment
		(start -101.23283 39.9923)
		(end -101.23283 39.008962)
		(width 0.10668)
		(layer "B.Cu")
		(net "ETH40G_B2_RX0P")
	)
	(segment
		(start -83.040002 39.860002)
		(end -82.58842 39.40842)
		(width 0.10668)
		(layer "B.Cu")
		(net "ETH40G_B2_RX0P")
	)
	(segment
		(start -84.900186 32.33166)
		(end -87.014086 32.33166)
		(width 0.10668)
		(layer "B.Cu")
		(net "ETH40G_B2_RX0P")
	)
	(segment
		(start -81.83626 38.807131)
		(end -81.83626 32.825667)
		(width 0.10668)
		(layer "B.Cu")
		(net "ETH40G_B2_RX0P")
	)
	(segment
		(start -82.512985 39.377173)
		(end -82.406302 39.377173)
		(width 0.10668)
		(layer "B.Cu")
		(net "ETH40G_B2_RX0P")
	)
	(segment
		(start -88.394327 32.903373)
		(end -94.305003 38.81405)
		(width 0.10668)
		(layer "B.Cu")
		(net "ETH40G_B2_RX0P")
	)
	(segment
		(start -99.59626 41.00576)
		(end -100.21937 41.00576)
		(width 0.10668)
		(layer "B.Cu")
		(net "ETH40G_B2_RX0P")
	)
	(arc
		(start -94.305003 38.81405)
		(mid -96.732652 40.436153)
		(end -99.59626 41.00576)
		(width 0.10668)
		(layer "B.Cu")
		(net "ETH40G_B2_RX0P")
	)
	(arc
		(start -100.21937 41.00576)
		(mid -100.935994 40.708924)
		(end -101.23283 39.9923)
		(width 0.10668)
		(layer "B.Cu")
		(net "ETH40G_B2_RX0P")
	)
	(arc
		(start -82.406302 39.377173)
		(mid -82.003221 39.210212)
		(end -81.83626 38.807131)
		(width 0.10668)
		(layer "B.Cu")
		(net "ETH40G_B2_RX0P")
	)
	(arc
		(start -82.58842 39.40842)
		(mid -82.55381 39.385294)
		(end -82.512985 39.377173)
		(width 0.10668)
		(layer "B.Cu")
		(net "ETH40G_B2_RX0P")
	)
	(arc
		(start -87.014086 32.33166)
		(mid -87.761067 32.480243)
		(end -88.394327 32.903373)
		(width 0.10668)
		(layer "B.Cu")
		(net "ETH40G_B2_RX0P")
	)
	(arc
		(start -81.83626 32.825667)
		(mid -81.938635 32.310993)
		(end -82.230173 31.874673)
		(width 0.10668)
		(layer "B.Cu")
		(net "ETH40G_B2_RX0P")
	)
	(arc
		(start -82.230173 31.874673)
		(mid -83.01355 31.550188)
		(end -83.796927 31.874673)
		(width 0.10668)
		(layer "B.Cu")
		(net "ETH40G_B2_RX0P")
	)
	(arc
		(start -83.796927 31.874673)
		(mid -84.303106 32.212892)
		(end -84.900186 32.33166)
		(width 0.10668)
		(layer "B.Cu")
		(net "ETH40G_B2_RX0P")
	)
	(arc
		(start -101.23283 39.008962)
		(mid -101.183651 38.761721)
		(end -101.0436 38.55212)
		(width 0.10668)
		(layer "B.Cu")
		(net "ETH40G_B2_RX0P")
	)
	(segment
		(start -101.818752 40.283359)
		(end -101.698417 40.163024)
		(width 0.10668)
		(layer "F.Cu")
		(net "ETH40G_B2_RX0N")
	)
	(segment
		(start -101.66717 40.087588)
		(end -101.66717 39.008962)
		(width 0.10668)
		(layer "F.Cu")
		(net "ETH40G_B2_RX0N")
	)
	(segment
		(start -101.85 41.340001)
		(end -101.85 40.358794)
		(width 0.10668)
		(layer "F.Cu")
		(net "ETH40G_B2_RX0N")
	)
	(via
		(at -101.8564 38.55212)
		(size 0.5588)
		(drill 0.254)
		(layers "F.Cu" "B.Cu")
		(net "ETH40G_B2_RX0N")
	)
	(arc
		(start -101.698417 40.163024)
		(mid -101.67529 40.128414)
		(end -101.66717 40.087588)
		(width 0.10668)
		(layer "F.Cu")
		(net "ETH40G_B2_RX0N")
	)
	(arc
		(start -101.85 40.358794)
		(mid -101.841879 40.317968)
		(end -101.818752 40.283359)
		(width 0.10668)
		(layer "F.Cu")
		(net "ETH40G_B2_RX0N")
	)
	(arc
		(start -101.66717 39.008962)
		(mid -101.716349 38.761721)
		(end -101.8564 38.55212)
		(width 0.10668)
		(layer "F.Cu")
		(net "ETH40G_B2_RX0N")
	)
	(segment
		(start -88.543963 33.959363)
		(end -88.836063 33.959363)
		(width 0.10668)
		(layer "B.Cu")
		(net "ETH40G_B2_RX0N")
	)
	(segment
		(start -84.900183 32.766)
		(end -87.014083 32.766)
		(width 0.10668)
		(layer "B.Cu")
		(net "ETH40G_B2_RX0N")
	)
	(segment
		(start -89.710082 34.833382)
		(end -90.001042 35.124342)
		(width 0.10668)
		(layer "B.Cu")
		(net "ETH40G_B2_RX0N")
	)
	(segment
		(start -88.253004 33.376304)
		(end -88.253004 33.668404)
		(width 0.10668)
		(layer "B.Cu")
		(net "ETH40G_B2_RX0N")
	)
	(segment
		(start -89.127023 34.542423)
		(end -89.417982 34.833382)
		(width 0.10668)
		(layer "B.Cu")
		(net "ETH40G_B2_RX0N")
	)
	(segment
		(start -89.417982 34.833382)
		(end -89.710082 34.833382)
		(width 0.10668)
		(layer "B.Cu")
		(net "ETH40G_B2_RX0N")
	)
	(segment
		(start -88.253004 33.668404)
		(end -88.543963 33.959363)
		(width 0.10668)
		(layer "B.Cu")
		(net "ETH40G_B2_RX0N")
	)
	(segment
		(start -101.66717 39.9923)
		(end -101.66717 39.008962)
		(width 0.10668)
		(layer "B.Cu")
		(net "ETH40G_B2_RX0N")
	)
	(segment
		(start -90.875061 36.290461)
		(end -91.16602 36.58142)
		(width 0.10668)
		(layer "B.Cu")
		(net "ETH40G_B2_RX0N")
	)
	(segment
		(start -90.001042 35.416442)
		(end -90.292001 35.707401)
		(width 0.10668)
		(layer "B.Cu")
		(net "ETH40G_B2_RX0N")
	)
	(segment
		(start -83.040002 38.460002)
		(end -82.588418 38.911586)
		(width 0.10668)
		(layer "B.Cu")
		(net "ETH40G_B2_RX0N")
	)
	(segment
		(start -91.45812 36.58142)
		(end -93.997877 39.121177)
		(width 0.10668)
		(layer "B.Cu")
		(net "ETH40G_B2_RX0N")
	)
	(segment
		(start -82.512982 38.942833)
		(end -82.406302 38.942833)
		(width 0.10668)
		(layer "B.Cu")
		(net "ETH40G_B2_RX0N")
	)
	(segment
		(start -99.59626 41.4401)
		(end -100.21937 41.4401)
		(width 0.10668)
		(layer "B.Cu")
		(net "ETH40G_B2_RX0N")
	)
	(segment
		(start -90.875061 35.998361)
		(end -90.875061 36.290461)
		(width 0.10668)
		(layer "B.Cu")
		(net "ETH40G_B2_RX0N")
	)
	(segment
		(start -90.001042 35.124342)
		(end -90.001042 35.416442)
		(width 0.10668)
		(layer "B.Cu")
		(net "ETH40G_B2_RX0N")
	)
	(segment
		(start -91.16602 36.58142)
		(end -91.45812 36.58142)
		(width 0.10668)
		(layer "B.Cu")
		(net "ETH40G_B2_RX0N")
	)
	(segment
		(start -82.2706 38.807131)
		(end -82.2706 32.82567)
		(width 0.10668)
		(layer "B.Cu")
		(net "ETH40G_B2_RX0N")
	)
	(segment
		(start -90.584101 35.707401)
		(end -90.875061 35.998361)
		(width 0.10668)
		(layer "B.Cu")
		(net "ETH40G_B2_RX0N")
	)
	(segment
		(start -88.836063 33.959363)
		(end -89.127023 34.250323)
		(width 0.10668)
		(layer "B.Cu")
		(net "ETH40G_B2_RX0N")
	)
	(segment
		(start -90.292001 35.707401)
		(end -90.584101 35.707401)
		(width 0.10668)
		(layer "B.Cu")
		(net "ETH40G_B2_RX0N")
	)
	(segment
		(start -88.0872 33.2105)
		(end -88.253004 33.376304)
		(width 0.10668)
		(layer "B.Cu")
		(net "ETH40G_B2_RX0N")
	)
	(segment
		(start -89.127023 34.250323)
		(end -89.127023 34.542423)
		(width 0.10668)
		(layer "B.Cu")
		(net "ETH40G_B2_RX0N")
	)
	(arc
		(start -82.2706 32.82567)
		(mid -82.339913 32.47721)
		(end -82.5373 32.1818)
		(width 0.10668)
		(layer "B.Cu")
		(net "ETH40G_B2_RX0N")
	)
	(arc
		(start -100.21937 41.4401)
		(mid -101.243119 41.016049)
		(end -101.66717 39.9923)
		(width 0.10668)
		(layer "B.Cu")
		(net "ETH40G_B2_RX0N")
	)
	(arc
		(start -93.997877 39.121177)
		(mid -96.566437 40.837432)
		(end -99.59626 41.4401)
		(width 0.10668)
		(layer "B.Cu")
		(net "ETH40G_B2_RX0N")
	)
	(arc
		(start -83.4898 32.1818)
		(mid -84.136889 32.614171)
		(end -84.900183 32.766)
		(width 0.10668)
		(layer "B.Cu")
		(net "ETH40G_B2_RX0N")
	)
	(arc
		(start -82.406302 38.942833)
		(mid -82.310346 38.903087)
		(end -82.2706 38.807131)
		(width 0.10668)
		(layer "B.Cu")
		(net "ETH40G_B2_RX0N")
	)
	(arc
		(start -82.588418 38.911586)
		(mid -82.553808 38.934713)
		(end -82.512982 38.942833)
		(width 0.10668)
		(layer "B.Cu")
		(net "ETH40G_B2_RX0N")
	)
	(arc
		(start -101.66717 39.008962)
		(mid -101.716349 38.761721)
		(end -101.8564 38.55212)
		(width 0.10668)
		(layer "B.Cu")
		(net "ETH40G_B2_RX0N")
	)
	(arc
		(start -82.5373 32.1818)
		(mid -83.01355 31.984531)
		(end -83.4898 32.1818)
		(width 0.10668)
		(layer "B.Cu")
		(net "ETH40G_B2_RX0N")
	)
	(arc
		(start -87.014083 32.766)
		(mid -87.59485 32.881522)
		(end -88.0872 33.2105)
		(width 0.10668)
		(layer "B.Cu")
		(net "ETH40G_B2_RX0N")
	)
	(segment
		(start -111.495601 17.4244)
		(end -112.257601 17.4244)
		(width 0.1016)
		(layer "F.Cu")
		(net "ETH40G_B2_RESET_N")
	)
	(segment
		(start -94.650001 41.340001)
		(end -94.650001 38.852399)
		(width 0.1016)
		(layer "F.Cu")
		(net "ETH40G_B2_RESET_N")
	)
	(segment
		(start -110.195599 10.4394)
		(end -109.0676 10.4394)
		(width 0.1016)
		(layer "F.Cu")
		(net "ETH40G_B2_RESET_N")
	)
	(segment
		(start -95.8088 37.6936)
		(end -96.2714 37.6936)
		(width 0.1016)
		(layer "F.Cu")
		(net "ETH40G_B2_RESET_N")
	)
	(segment
		(start -94.650001 38.852399)
		(end -95.8088 37.6936)
		(width 0.1016)
		(layer "F.Cu")
		(net "ETH40G_B2_RESET_N")
	)
	(segment
		(start -96.2714 37.6936)
		(end -96.627 37.338)
		(width 0.1016)
		(layer "F.Cu")
		(net "ETH40G_B2_RESET_N")
	)
	(via
		(at -109.0676 10.4394)
		(size 0.5588)
		(drill 0.254)
		(layers "F.Cu" "B.Cu")
		(net "ETH40G_B2_RESET_N")
	)
	(via
		(at -96.627 37.338)
		(size 0.5588)
		(drill 0.254)
		(layers "F.Cu" "B.Cu")
		(net "ETH40G_B2_RESET_N")
	)
	(via
		(at -112.257601 17.4244)
		(size 0.5588)
		(drill 0.254)
		(layers "F.Cu" "B.Cu")
		(net "ETH40G_B2_RESET_N")
	)
	(segment
		(start -96.627 37.338)
		(end -96.627 36.3093)
		(width 0.12954)
		(layer "In2.Cu")
		(net "ETH40G_B2_RESET_N")
	)
	(segment
		(start -99.43846 35.40252)
		(end -101.6254 33.21558)
		(width 0.12954)
		(layer "In2.Cu")
		(net "ETH40G_B2_RESET_N")
	)
	(segment
		(start -101.6762 24.2062)
		(end -103.187624 22.694776)
		(width 0.12954)
		(layer "In2.Cu")
		(net "ETH40G_B2_RESET_N")
	)
	(segment
		(start -108.5596 13.335)
		(end -109.07268 13.84808)
		(width 0.12954)
		(layer "In2.Cu")
		(net "ETH40G_B2_RESET_N")
	)
	(segment
		(start -109.07268 13.84808)
		(end -109.50448 13.84808)
		(width 0.12954)
		(layer "In2.Cu")
		(net "ETH40G_B2_RESET_N")
	)
	(segment
		(start -97.53378 35.40252)
		(end -99.43846 35.40252)
		(width 0.12954)
		(layer "In2.Cu")
		(net "ETH40G_B2_RESET_N")
	)
	(segment
		(start -111.0742 16.2052)
		(end -112.257601 17.388601)
		(width 0.12954)
		(layer "In2.Cu")
		(net "ETH40G_B2_RESET_N")
	)
	(segment
		(start -101.6762 29.0884)
		(end -101.6762 24.2062)
		(width 0.12954)
		(layer "In2.Cu")
		(net "ETH40G_B2_RESET_N")
	)
	(segment
		(start -110.9726 21.6408)
		(end -110.9726 18.709401)
		(width 0.12954)
		(layer "In2.Cu")
		(net "ETH40G_B2_RESET_N")
	)
	(segment
		(start -109.0676 10.4394)
		(end -108.5596 10.9474)
		(width 0.12954)
		(layer "In2.Cu")
		(net "ETH40G_B2_RESET_N")
	)
	(segment
		(start -103.187624 22.694776)
		(end -109.918624 22.694776)
		(width 0.12954)
		(layer "In2.Cu")
		(net "ETH40G_B2_RESET_N")
	)
	(segment
		(start -96.627 36.3093)
		(end -97.53378 35.40252)
		(width 0.12954)
		(layer "In2.Cu")
		(net "ETH40G_B2_RESET_N")
	)
	(segment
		(start -111.0742 15.4178)
		(end -111.0742 16.2052)
		(width 0.12954)
		(layer "In2.Cu")
		(net "ETH40G_B2_RESET_N")
	)
	(segment
		(start -109.50448 13.84808)
		(end -111.0742 15.4178)
		(width 0.12954)
		(layer "In2.Cu")
		(net "ETH40G_B2_RESET_N")
	)
	(segment
		(start -101.6254 29.1392)
		(end -101.6762 29.0884)
		(width 0.12954)
		(layer "In2.Cu")
		(net "ETH40G_B2_RESET_N")
	)
	(segment
		(start -110.9726 18.709401)
		(end -112.257601 17.4244)
		(width 0.12954)
		(layer "In2.Cu")
		(net "ETH40G_B2_RESET_N")
	)
	(segment
		(start -109.918624 22.694776)
		(end -110.9726 21.6408)
		(width 0.12954)
		(layer "In2.Cu")
		(net "ETH40G_B2_RESET_N")
	)
	(segment
		(start -101.6254 33.21558)
		(end -101.6254 29.1392)
		(width 0.12954)
		(layer "In2.Cu")
		(net "ETH40G_B2_RESET_N")
	)
	(segment
		(start -112.257601 17.388601)
		(end -112.257601 17.4244)
		(width 0.12954)
		(layer "In2.Cu")
		(net "ETH40G_B2_RESET_N")
	)
	(segment
		(start -108.5596 10.9474)
		(end -108.5596 13.335)
		(width 0.12954)
		(layer "In2.Cu")
		(net "ETH40G_B2_RESET_N")
	)
	(segment
		(start -79.486999 12.065)
		(end -78.6384 12.065)
		(width 0.1016)
		(layer "F.Cu")
		(net "ETH40G_B2_PRES_N")
	)
	(segment
		(start -78.6384 12.065)
		(end -78.5876 12.1158)
		(width 0.1016)
		(layer "F.Cu")
		(net "ETH40G_B2_PRES_N")
	)
	(via
		(at -78.5876 12.1158)
		(size 0.5588)
		(drill 0.254)
		(layers "F.Cu" "B.Cu")
		(net "ETH40G_B2_PRES_N")
	)
	(segment
		(start -78.5876 12.1158)
		(end -80.2132 12.1158)
		(width 0.12954)
		(layer "In2.Cu")
		(net "ETH40G_B2_PRES_N")
	)
	(segment
		(start -80.0862 31.7754)
		(end -80.0862 34.6062)
		(width 0.12954)
		(layer "In2.Cu")
		(net "ETH40G_B2_PRES_N")
	)
	(segment
		(start -83.5914 15.494)
		(end -83.5914 28.2702)
		(width 0.12954)
		(layer "In2.Cu")
		(net "ETH40G_B2_PRES_N")
	)
	(segment
		(start -80.0862 34.6062)
		(end -81.04 35.56)
		(width 0.12954)
		(layer "In2.Cu")
		(net "ETH40G_B2_PRES_N")
	)
	(segment
		(start -83.5914 28.2702)
		(end -80.0862 31.7754)
		(width 0.12954)
		(layer "In2.Cu")
		(net "ETH40G_B2_PRES_N")
	)
	(segment
		(start -80.2132 12.1158)
		(end -83.5914 15.494)
		(width 0.12954)
		(layer "In2.Cu")
		(net "ETH40G_B2_PRES_N")
	)
	(segment
		(start -93.85 41.340001)
		(end -93.85 38.8282)
		(width 0.1016)
		(layer "F.Cu")
		(net "ETH40G_B2_MODSEL_N")
	)
	(segment
		(start -93.071 36.088)
		(end -94.89948 34.25952)
		(width 0.1016)
		(layer "F.Cu")
		(net "ETH40G_B2_MODSEL_N")
	)
	(segment
		(start -109.3216 9.0424)
		(end -110.195599 9.0424)
		(width 0.1016)
		(layer "F.Cu")
		(net "ETH40G_B2_MODSEL_N")
	)
	(segment
		(start -93.071 38.0492)
		(end -93.071 36.088)
		(width 0.1016)
		(layer "F.Cu")
		(net "ETH40G_B2_MODSEL_N")
	)
	(segment
		(start -110.195599 9.0424)
		(end -110.195599 7.493)
		(width 0.1016)
		(layer "F.Cu")
		(net "ETH40G_B2_MODSEL_N")
	)
	(segment
		(start -94.89948 34.25952)
		(end -94.89948 31.60522)
		(width 0.1016)
		(layer "F.Cu")
		(net "ETH40G_B2_MODSEL_N")
	)
	(segment
		(start -93.85 38.8282)
		(end -93.071 38.0492)
		(width 0.1016)
		(layer "F.Cu")
		(net "ETH40G_B2_MODSEL_N")
	)
	(via
		(at -94.89948 31.60522)
		(size 0.5588)
		(drill 0.254)
		(layers "F.Cu" "B.Cu")
		(net "ETH40G_B2_MODSEL_N")
	)
	(via
		(at -109.3216 9.0424)
		(size 0.5588)
		(drill 0.254)
		(layers "F.Cu" "B.Cu")
		(net "ETH40G_B2_MODSEL_N")
	)
	(segment
		(start -98.412732 23.736188)
		(end -106.78176 15.36716)
		(width 0.12954)
		(layer "In2.Cu")
		(net "ETH40G_B2_MODSEL_N")
	)
	(segment
		(start -106.78176 10.84564)
		(end -108.585 9.0424)
		(width 0.12954)
		(layer "In2.Cu")
		(net "ETH40G_B2_MODSEL_N")
	)
	(segment
		(start -95.95898 31.60522)
		(end -98.412732 29.151468)
		(width 0.12954)
		(layer "In2.Cu")
		(net "ETH40G_B2_MODSEL_N")
	)
	(segment
		(start -94.89948 31.60522)
		(end -95.95898 31.60522)
		(width 0.12954)
		(layer "In2.Cu")
		(net "ETH40G_B2_MODSEL_N")
	)
	(segment
		(start -108.585 9.0424)
		(end -109.3216 9.0424)
		(width 0.12954)
		(layer "In2.Cu")
		(net "ETH40G_B2_MODSEL_N")
	)
	(segment
		(start -98.412732 29.151468)
		(end -98.412732 23.736188)
		(width 0.12954)
		(layer "In2.Cu")
		(net "ETH40G_B2_MODSEL_N")
	)
	(segment
		(start -106.78176 15.36716)
		(end -106.78176 10.84564)
		(width 0.12954)
		(layer "In2.Cu")
		(net "ETH40G_B2_MODSEL_N")
	)
	(segment
		(start -96.65 45.7478)
		(end -96.3984 45.9994)
		(width 0.1016)
		(layer "F.Cu")
		(net "ETH40G_B2_MODPRS_N")
	)
	(segment
		(start -96.65 43.840001)
		(end -96.65 45.7478)
		(width 0.1016)
		(layer "F.Cu")
		(net "ETH40G_B2_MODPRS_N")
	)
	(segment
		(start -80.787001 12.065)
		(end -81.661 12.065)
		(width 0.1016)
		(layer "F.Cu")
		(net "ETH40G_B2_MODPRS_N")
	)
	(segment
		(start -94.081557 47.975563)
		(end -94.081557 46.616663)
		(width 0.1016)
		(layer "F.Cu")
		(net "ETH40G_B2_MODPRS_N")
	)
	(segment
		(start -94.69882 45.9994)
		(end -96.3984 45.9994)
		(width 0.1016)
		(layer "F.Cu")
		(net "ETH40G_B2_MODPRS_N")
	)
	(segment
		(start -94.081557 46.616663)
		(end -94.69882 45.9994)
		(width 0.1016)
		(layer "F.Cu")
		(net "ETH40G_B2_MODPRS_N")
	)
	(segment
		(start -89.98458 48.45558)
		(end -93.60154 48.45558)
		(width 0.1016)
		(layer "F.Cu")
		(net "ETH40G_B2_MODPRS_N")
	)
	(segment
		(start -93.60154 48.45558)
		(end -94.081557 47.975563)
		(width 0.1016)
		(layer "F.Cu")
		(net "ETH40G_B2_MODPRS_N")
	)
	(segment
		(start -88.55964 47.03064)
		(end -89.98458 48.45558)
		(width 0.1016)
		(layer "F.Cu")
		(net "ETH40G_B2_MODPRS_N")
	)
	(segment
		(start -84.6963 45.3136)
		(end -86.41334 47.03064)
		(width 0.1016)
		(layer "F.Cu")
		(net "ETH40G_B2_MODPRS_N")
	)
	(segment
		(start -86.41334 47.03064)
		(end -88.55964 47.03064)
		(width 0.1016)
		(layer "F.Cu")
		(net "ETH40G_B2_MODPRS_N")
	)
	(segment
		(start -84.6963 44.4373)
		(end -84.6963 45.3136)
		(width 0.1016)
		(layer "F.Cu")
		(net "ETH40G_B2_MODPRS_N")
	)
	(via
		(at -84.6963 44.4373)
		(size 0.5588)
		(drill 0.254)
		(layers "F.Cu" "B.Cu")
		(net "ETH40G_B2_MODPRS_N")
	)
	(via
		(at -81.661 12.065)
		(size 0.5588)
		(drill 0.254)
		(layers "F.Cu" "B.Cu")
		(net "ETH40G_B2_MODPRS_N")
	)
	(via
		(at -96.3984 45.9994)
		(size 0.5588)
		(drill 0.254)
		(layers "F.Cu" "B.Cu")
		(net "ETH40G_B2_MODPRS_N")
	)
	(segment
		(start -87.5538 29.5148)
		(end -83.7692 33.2994)
		(width 0.12954)
		(layer "In2.Cu")
		(net "ETH40G_B2_MODPRS_N")
	)
	(segment
		(start -87.5538 14.7828)
		(end -87.5538 29.5148)
		(width 0.12954)
		(layer "In2.Cu")
		(net "ETH40G_B2_MODPRS_N")
	)
	(segment
		(start -81.1276 10.1092)
		(end -82.8802 10.1092)
		(width 0.12954)
		(layer "In2.Cu")
		(net "ETH40G_B2_MODPRS_N")
	)
	(segment
		(start -81.661 12.065)
		(end -80.7974 11.2014)
		(width 0.12954)
		(layer "In2.Cu")
		(net "ETH40G_B2_MODPRS_N")
	)
	(segment
		(start -83.7692 33.2994)
		(end -83.7692 43.5102)
		(width 0.12954)
		(layer "In2.Cu")
		(net "ETH40G_B2_MODPRS_N")
	)
	(segment
		(start -82.8802 10.1092)
		(end -87.5538 14.7828)
		(width 0.12954)
		(layer "In2.Cu")
		(net "ETH40G_B2_MODPRS_N")
	)
	(segment
		(start -80.7974 10.4394)
		(end -81.1276 10.1092)
		(width 0.12954)
		(layer "In2.Cu")
		(net "ETH40G_B2_MODPRS_N")
	)
	(segment
		(start -80.7974 11.2014)
		(end -80.7974 10.4394)
		(width 0.12954)
		(layer "In2.Cu")
		(net "ETH40G_B2_MODPRS_N")
	)
	(segment
		(start -83.7692 43.5102)
		(end -84.6963 44.4373)
		(width 0.12954)
		(layer "In2.Cu")
		(net "ETH40G_B2_MODPRS_N")
	)
	(segment
		(start -93.450001 45.6819)
		(end -93.450001 43.840001)
		(width 0.1016)
		(layer "F.Cu")
		(net "ETH40G_B2_LPMODE")
	)
	(segment
		(start -111.495601 11.8364)
		(end -112.4712 11.8364)
		(width 0.1016)
		(layer "F.Cu")
		(net "ETH40G_B2_LPMODE")
	)
	(segment
		(start -114.081799 17.526)
		(end -114.0714 17.515601)
		(width 0.1016)
		(layer "F.Cu")
		(net "ETH40G_B2_LPMODE")
	)
	(segment
		(start -114.9858 17.526)
		(end -114.081799 17.526)
		(width 0.1016)
		(layer "F.Cu")
		(net "ETH40G_B2_LPMODE")
	)
	(via
		(at -112.4712 11.8364)
		(size 0.5588)
		(drill 0.254)
		(layers "F.Cu" "B.Cu")
		(net "ETH40G_B2_LPMODE")
	)
	(via
		(at -93.450001 45.6819)
		(size 0.5588)
		(drill 0.254)
		(layers "F.Cu" "B.Cu")
		(net "ETH40G_B2_LPMODE")
	)
	(via
		(at -103.00716 46.50232)
		(size 0.5588)
		(drill 0.254)
		(layers "F.Cu" "B.Cu")
		(net "ETH40G_B2_LPMODE")
	)
	(via
		(at -114.9858 17.526)
		(size 0.5588)
		(drill 0.254)
		(layers "F.Cu" "B.Cu")
		(net "ETH40G_B2_LPMODE")
	)
	(segment
		(start -106.0196 36.4236)
		(end -106.0196 44.5008)
		(width 0.12954)
		(layer "In2.Cu")
		(net "ETH40G_B2_LPMODE")
	)
	(segment
		(start -113.6142 20.6502)
		(end -112.559953 21.704447)
		(width 0.12954)
		(layer "In2.Cu")
		(net "ETH40G_B2_LPMODE")
	)
	(segment
		(start -113.8428 11.8364)
		(end -114.7826 12.7762)
		(width 0.12954)
		(layer "In2.Cu")
		(net "ETH40G_B2_LPMODE")
	)
	(segment
		(start -104.14 46.3804)
		(end -103.12908 46.3804)
		(width 0.12954)
		(layer "In2.Cu")
		(net "ETH40G_B2_LPMODE")
	)
	(segment
		(start -110.1852 25.019)
		(end -107.041 25.019)
		(width 0.12954)
		(layer "In2.Cu")
		(net "ETH40G_B2_LPMODE")
	)
	(segment
		(start -104.3686 25.8826)
		(end -103.124 27.1272)
		(width 0.12954)
		(layer "In2.Cu")
		(net "ETH40G_B2_LPMODE")
	)
	(segment
		(start -112.559953 22.644247)
		(end -110.1852 25.019)
		(width 0.12954)
		(layer "In2.Cu")
		(net "ETH40G_B2_LPMODE")
	)
	(segment
		(start -107.041 25.019)
		(end -106.1774 25.8826)
		(width 0.12954)
		(layer "In2.Cu")
		(net "ETH40G_B2_LPMODE")
	)
	(segment
		(start -113.6142 18.8976)
		(end -113.6142 20.6502)
		(width 0.12954)
		(layer "In2.Cu")
		(net "ETH40G_B2_LPMODE")
	)
	(segment
		(start -103.124 27.1272)
		(end -103.124 33.528)
		(width 0.12954)
		(layer "In2.Cu")
		(net "ETH40G_B2_LPMODE")
	)
	(segment
		(start -103.124 33.528)
		(end -106.0196 36.4236)
		(width 0.12954)
		(layer "In2.Cu")
		(net "ETH40G_B2_LPMODE")
	)
	(segment
		(start -112.559953 21.704447)
		(end -112.559953 22.644247)
		(width 0.12954)
		(layer "In2.Cu")
		(net "ETH40G_B2_LPMODE")
	)
	(segment
		(start -106.0196 44.5008)
		(end -104.14 46.3804)
		(width 0.12954)
		(layer "In2.Cu")
		(net "ETH40G_B2_LPMODE")
	)
	(segment
		(start -103.12908 46.3804)
		(end -103.00716 46.50232)
		(width 0.12954)
		(layer "In2.Cu")
		(net "ETH40G_B2_LPMODE")
	)
	(segment
		(start -114.9858 17.526)
		(end -113.6142 18.8976)
		(width 0.12954)
		(layer "In2.Cu")
		(net "ETH40G_B2_LPMODE")
	)
	(segment
		(start -106.1774 25.8826)
		(end -104.3686 25.8826)
		(width 0.12954)
		(layer "In2.Cu")
		(net "ETH40G_B2_LPMODE")
	)
	(segment
		(start -114.7826 17.3228)
		(end -114.9858 17.526)
		(width 0.12954)
		(layer "In2.Cu")
		(net "ETH40G_B2_LPMODE")
	)
	(segment
		(start -114.7826 12.7762)
		(end -114.7826 17.3228)
		(width 0.12954)
		(layer "In2.Cu")
		(net "ETH40G_B2_LPMODE")
	)
	(segment
		(start -112.4712 11.8364)
		(end -113.8428 11.8364)
		(width 0.12954)
		(layer "In2.Cu")
		(net "ETH40G_B2_LPMODE")
	)
	(segment
		(start -102.84968 42.78376)
		(end -102.84968 44.64304)
		(width 0.12954)
		(layer "In5.Cu")
		(net "ETH40G_B2_LPMODE")
	)
	(segment
		(start -93.82506 44.79544)
		(end -93.82506 43.03268)
		(width 0.12954)
		(layer "In5.Cu")
		(net "ETH40G_B2_LPMODE")
	)
	(segment
		(start -103.00716 46.48962)
		(end -103.00716 46.50232)
		(width 0.12954)
		(layer "In5.Cu")
		(net "ETH40G_B2_LPMODE")
	)
	(segment
		(start -93.450001 45.6819)
		(end -93.450001 45.170499)
		(width 0.12954)
		(layer "In5.Cu")
		(net "ETH40G_B2_LPMODE")
	)
	(segment
		(start -103.62438 45.41774)
		(end -103.62438 45.8724)
		(width 0.12954)
		(layer "In5.Cu")
		(net "ETH40G_B2_LPMODE")
	)
	(segment
		(start -102.84968 44.64304)
		(end -103.62438 45.41774)
		(width 0.12954)
		(layer "In5.Cu")
		(net "ETH40G_B2_LPMODE")
	)
	(segment
		(start -94.41688 42.44086)
		(end -102.50678 42.44086)
		(width 0.12954)
		(layer "In5.Cu")
		(net "ETH40G_B2_LPMODE")
	)
	(segment
		(start -93.82506 43.03268)
		(end -94.41688 42.44086)
		(width 0.12954)
		(layer "In5.Cu")
		(net "ETH40G_B2_LPMODE")
	)
	(segment
		(start -102.50678 42.44086)
		(end -102.84968 42.78376)
		(width 0.12954)
		(layer "In5.Cu")
		(net "ETH40G_B2_LPMODE")
	)
	(segment
		(start -93.450001 45.170499)
		(end -93.82506 44.79544)
		(width 0.12954)
		(layer "In5.Cu")
		(net "ETH40G_B2_LPMODE")
	)
	(segment
		(start -103.62438 45.8724)
		(end -103.00716 46.48962)
		(width 0.12954)
		(layer "In5.Cu")
		(net "ETH40G_B2_LPMODE")
	)
	(segment
		(start -95.849999 45.058414)
		(end -95.986567 45.194982)
		(width 0.1016)
		(layer "F.Cu")
		(net "ETH40G_B2_INT_N")
	)
	(segment
		(start -109.26572 13.2334)
		(end -110.195599 13.2334)
		(width 0.1016)
		(layer "F.Cu")
		(net "ETH40G_B2_INT_N")
	)
	(segment
		(start -95.849999 43.840001)
		(end -95.849999 45.058414)
		(width 0.1016)
		(layer "F.Cu")
		(net "ETH40G_B2_INT_N")
	)
	(via
		(at -95.986567 45.194982)
		(size 0.5588)
		(drill 0.254)
		(layers "F.Cu" "B.Cu")
		(net "ETH40G_B2_INT_N")
	)
	(via
		(at -103.00716 45.62602)
		(size 0.5588)
		(drill 0.254)
		(layers "F.Cu" "B.Cu")
		(net "ETH40G_B2_INT_N")
	)
	(via
		(at -109.26572 13.2334)
		(size 0.5588)
		(drill 0.254)
		(layers "F.Cu" "B.Cu")
		(net "ETH40G_B2_INT_N")
	)
	(segment
		(start -112.1156 21.2598)
		(end -112.1156 20.2692)
		(width 0.12954)
		(layer "In2.Cu")
		(net "ETH40G_B2_INT_N")
	)
	(segment
		(start -105.3592 25.4254)
		(end -106.1466 24.638)
		(width 0.12954)
		(layer "In2.Cu")
		(net "ETH40G_B2_INT_N")
	)
	(segment
		(start -103.4288 45.11326)
		(end -103.4288 38.01364)
		(width 0.12954)
		(layer "In2.Cu")
		(net "ETH40G_B2_INT_N")
	)
	(segment
		(start -113.0046 14.478)
		(end -112.4966 13.97)
		(width 0.12954)
		(layer "In2.Cu")
		(net "ETH40G_B2_INT_N")
	)
	(segment
		(start -103.6066 25.4254)
		(end -105.3592 25.4254)
		(width 0.12954)
		(layer "In2.Cu")
		(net "ETH40G_B2_INT_N")
	)
	(segment
		(start -102.362 26.67)
		(end -103.6066 25.4254)
		(width 0.12954)
		(layer "In2.Cu")
		(net "ETH40G_B2_INT_N")
	)
	(segment
		(start -109.7534 13.2334)
		(end -109.26572 13.2334)
		(width 0.12954)
		(layer "In2.Cu")
		(net "ETH40G_B2_INT_N")
	)
	(segment
		(start -103.4288 38.01364)
		(end -102.362 36.94684)
		(width 0.12954)
		(layer "In2.Cu")
		(net "ETH40G_B2_INT_N")
	)
	(segment
		(start -102.362 36.94684)
		(end -102.362 26.67)
		(width 0.12954)
		(layer "In2.Cu")
		(net "ETH40G_B2_INT_N")
	)
	(segment
		(start -112.4966 13.97)
		(end -110.49 13.97)
		(width 0.12954)
		(layer "In2.Cu")
		(net "ETH40G_B2_INT_N")
	)
	(segment
		(start -112.1156 20.2692)
		(end -113.0046 19.3802)
		(width 0.12954)
		(layer "In2.Cu")
		(net "ETH40G_B2_INT_N")
	)
	(segment
		(start -103.00716 45.62602)
		(end -103.00716 45.5349)
		(width 0.12954)
		(layer "In2.Cu")
		(net "ETH40G_B2_INT_N")
	)
	(segment
		(start -103.00716 45.5349)
		(end -103.4288 45.11326)
		(width 0.12954)
		(layer "In2.Cu")
		(net "ETH40G_B2_INT_N")
	)
	(segment
		(start -106.1466 24.638)
		(end -108.7374 24.638)
		(width 0.12954)
		(layer "In2.Cu")
		(net "ETH40G_B2_INT_N")
	)
	(segment
		(start -110.49 13.97)
		(end -109.7534 13.2334)
		(width 0.12954)
		(layer "In2.Cu")
		(net "ETH40G_B2_INT_N")
	)
	(segment
		(start -113.0046 19.3802)
		(end -113.0046 14.478)
		(width 0.12954)
		(layer "In2.Cu")
		(net "ETH40G_B2_INT_N")
	)
	(segment
		(start -108.7374 24.638)
		(end -112.1156 21.2598)
		(width 0.12954)
		(layer "In2.Cu")
		(net "ETH40G_B2_INT_N")
	)
	(segment
		(start -103.00716 45.62602)
		(end -103.00716 45.25264)
		(width 0.12954)
		(layer "In5.Cu")
		(net "ETH40G_B2_INT_N")
	)
	(segment
		(start -96.24822 44.933329)
		(end -95.986567 45.194982)
		(width 0.12954)
		(layer "In5.Cu")
		(net "ETH40G_B2_INT_N")
	)
	(segment
		(start -96.24822 42.95902)
		(end -96.24822 44.933329)
		(width 0.12954)
		(layer "In5.Cu")
		(net "ETH40G_B2_INT_N")
	)
	(segment
		(start -96.46666 42.74058)
		(end -96.24822 42.95902)
		(width 0.12954)
		(layer "In5.Cu")
		(net "ETH40G_B2_INT_N")
	)
	(segment
		(start -102.35946 42.74058)
		(end -96.46666 42.74058)
		(width 0.12954)
		(layer "In5.Cu")
		(net "ETH40G_B2_INT_N")
	)
	(segment
		(start -103.00716 45.25264)
		(end -102.5652 44.81068)
		(width 0.12954)
		(layer "In5.Cu")
		(net "ETH40G_B2_INT_N")
	)
	(segment
		(start -102.5652 44.81068)
		(end -102.5652 42.94632)
		(width 0.12954)
		(layer "In5.Cu")
		(net "ETH40G_B2_INT_N")
	)
	(segment
		(start -102.5652 42.94632)
		(end -102.35946 42.74058)
		(width 0.12954)
		(layer "In5.Cu")
		(net "ETH40G_B2_INT_N")
	)
	(segment
		(start -313.250001 41.340001)
		(end -313.250001 40.358794)
		(width 0.10668)
		(layer "F.Cu")
		(net "ETH40G_B1_TX3P")
	)
	(segment
		(start -313.218754 40.283359)
		(end -313.098416 40.163021)
		(width 0.10668)
		(layer "F.Cu")
		(net "ETH40G_B1_TX3P")
	)
	(segment
		(start -313.067169 40.087586)
		(end -313.067169 34.581747)
		(width 0.10668)
		(layer "F.Cu")
		(net "ETH40G_B1_TX3P")
	)
	(via
		(at -313.256402 34.1249)
		(size 0.5588)
		(drill 0.254)
		(layers "F.Cu" "B.Cu")
		(net "ETH40G_B1_TX3P")
	)
	(arc
		(start -313.098416 40.163021)
		(mid -313.07529 40.128411)
		(end -313.067169 40.087586)
		(width 0.10668)
		(layer "F.Cu")
		(net "ETH40G_B1_TX3P")
	)
	(arc
		(start -313.250001 40.358794)
		(mid -313.24188 40.317969)
		(end -313.218754 40.283359)
		(width 0.10668)
		(layer "F.Cu")
		(net "ETH40G_B1_TX3P")
	)
	(arc
		(start -313.067169 34.581747)
		(mid -313.116349 34.334503)
		(end -313.256402 34.1249)
		(width 0.10668)
		(layer "F.Cu")
		(net "ETH40G_B1_TX3P")
	)
	(segment
		(start -293.511453 44.831452)
		(end -293.39969 44.831452)
		(width 0.11176)
		(layer "In5.Cu")
		(net "ETH40G_B1_TX3P")
	)
	(segment
		(start -296.460088 30.2895)
		(end -309.377057 30.2895)
		(width 0.11176)
		(layer "In5.Cu")
		(net "ETH40G_B1_TX3P")
	)
	(segment
		(start -312.37428 32.32404)
		(end -312.863027 32.812784)
		(width 0.11176)
		(layer "In5.Cu")
		(net "ETH40G_B1_TX3P")
	)
	(segment
		(start -292.987987 33.298077)
		(end -295.668802 30.617262)
		(width 0.11176)
		(layer "In5.Cu")
		(net "ETH40G_B1_TX3P")
	)
	(segment
		(start -294.040001 45.360001)
		(end -293.511453 44.831452)
		(width 0.11176)
		(layer "In5.Cu")
		(net "ETH40G_B1_TX3P")
	)
	(segment
		(start -292.5064 43.938162)
		(end -292.5064 34.460729)
		(width 0.11176)
		(layer "In5.Cu")
		(net "ETH40G_B1_TX3P")
	)
	(segment
		(start -313.021452 33.19526)
		(end -313.021452 33.55768)
		(width 0.11176)
		(layer "In5.Cu")
		(net "ETH40G_B1_TX3P")
	)
	(segment
		(start -311.02046 30.97022)
		(end -312.37428 32.32404)
		(width 0.11176)
		(layer "In5.Cu")
		(net "ETH40G_B1_TX3P")
	)
	(arc
		(start -295.668802 30.617262)
		(mid -296.031847 30.374683)
		(end -296.460088 30.2895)
		(width 0.11176)
		(layer "In5.Cu")
		(net "ETH40G_B1_TX3P")
	)
	(arc
		(start -292.5064 34.460729)
		(mid -292.63156 33.831506)
		(end -292.987987 33.298077)
		(width 0.11176)
		(layer "In5.Cu")
		(net "ETH40G_B1_TX3P")
	)
	(arc
		(start -309.377057 30.2895)
		(mid -310.26646 30.466413)
		(end -311.02046 30.97022)
		(width 0.11176)
		(layer "In5.Cu")
		(net "ETH40G_B1_TX3P")
	)
	(arc
		(start -293.39969 44.831452)
		(mid -292.768039 44.569813)
		(end -292.5064 43.938162)
		(width 0.11176)
		(layer "In5.Cu")
		(net "ETH40G_B1_TX3P")
	)
	(arc
		(start -312.863027 32.812784)
		(mid -312.980279 32.988266)
		(end -313.021452 33.19526)
		(width 0.11176)
		(layer "In5.Cu")
		(net "ETH40G_B1_TX3P")
	)
	(arc
		(start -313.021452 33.55768)
		(mid -313.082514 33.864657)
		(end -313.256402 34.1249)
		(width 0.11176)
		(layer "In5.Cu")
		(net "ETH40G_B1_TX3P")
	)
	(segment
		(start -312.45 41.340001)
		(end -312.45 40.358794)
		(width 0.10668)
		(layer "F.Cu")
		(net "ETH40G_B1_TX3N")
	)
	(segment
		(start -312.481247 40.283359)
		(end -312.601582 40.163024)
		(width 0.10668)
		(layer "F.Cu")
		(net "ETH40G_B1_TX3N")
	)
	(segment
		(start -312.632829 40.087588)
		(end -312.632829 34.581734)
		(width 0.10668)
		(layer "F.Cu")
		(net "ETH40G_B1_TX3N")
	)
	(via
		(at -312.443602 34.1249)
		(size 0.5588)
		(drill 0.254)
		(layers "F.Cu" "B.Cu")
		(net "ETH40G_B1_TX3N")
	)
	(arc
		(start -312.601582 40.163024)
		(mid -312.624709 40.128414)
		(end -312.632829 40.087588)
		(width 0.10668)
		(layer "F.Cu")
		(net "ETH40G_B1_TX3N")
	)
	(arc
		(start -312.45 40.358794)
		(mid -312.458121 40.317969)
		(end -312.481247 40.283359)
		(width 0.10668)
		(layer "F.Cu")
		(net "ETH40G_B1_TX3N")
	)
	(arc
		(start -312.632829 34.581734)
		(mid -312.583651 34.334497)
		(end -312.443602 34.1249)
		(width 0.10668)
		(layer "F.Cu")
		(net "ETH40G_B1_TX3N")
	)
	(segment
		(start -293.08044 41.23944)
		(end -292.8493 41.0083)
		(width 0.11176)
		(layer "In5.Cu")
		(net "ETH40G_B1_TX3N")
	)
	(segment
		(start -308.02883 30.6324)
		(end -308.25743 30.861)
		(width 0.11176)
		(layer "In5.Cu")
		(net "ETH40G_B1_TX3N")
	)
	(segment
		(start -306.4151 30.861)
		(end -306.83166 30.861)
		(width 0.11176)
		(layer "In5.Cu")
		(net "ETH40G_B1_TX3N")
	)
	(segment
		(start -312.678552 33.195257)
		(end -312.678552 33.55768)
		(width 0.11176)
		(layer "In5.Cu")
		(net "ETH40G_B1_TX3N")
	)
	(segment
		(start -293.08044 41.720864)
		(end -293.08044 41.23944)
		(width 0.11176)
		(layer "In5.Cu")
		(net "ETH40G_B1_TX3N")
	)
	(segment
		(start -292.8493 39.422461)
		(end -293.08044 39.191321)
		(width 0.11176)
		(layer "In5.Cu")
		(net "ETH40G_B1_TX3N")
	)
	(segment
		(start -310.777992 31.212688)
		(end -311.405925 31.84062)
		(width 0.11176)
		(layer "In5.Cu")
		(net "ETH40G_B1_TX3N")
	)
	(segment
		(start -293.230455 33.540545)
		(end -295.91127 30.85973)
		(width 0.11176)
		(layer "In5.Cu")
		(net "ETH40G_B1_TX3N")
	)
	(segment
		(start -303.812786 30.86354)
		(end -304.043926 30.6324)
		(width 0.11176)
		(layer "In5.Cu")
		(net "ETH40G_B1_TX3N")
	)
	(segment
		(start -312.678549 33.19526)
		(end -312.678552 33.195257)
		(width 0.11176)
		(layer "In5.Cu")
		(net "ETH40G_B1_TX3N")
	)
	(segment
		(start -292.8493 38.523301)
		(end -292.8493 38.106741)
		(width 0.11176)
		(layer "In5.Cu")
		(net "ETH40G_B1_TX3N")
	)
	(segment
		(start -297.688 30.6324)
		(end -297.91914 30.86354)
		(width 0.11176)
		(layer "In5.Cu")
		(net "ETH40G_B1_TX3N")
	)
	(segment
		(start -293.08044 38.754441)
		(end -292.8493 38.523301)
		(width 0.11176)
		(layer "In5.Cu")
		(net "ETH40G_B1_TX3N")
	)
	(segment
		(start -311.405923 31.993223)
		(end -311.708094 32.295394)
		(width 0.11176)
		(layer "In5.Cu")
		(net "ETH40G_B1_TX3N")
	)
	(segment
		(start -292.8493 43.938162)
		(end -292.8493 43.650411)
		(width 0.11176)
		(layer "In5.Cu")
		(net "ETH40G_B1_TX3N")
	)
	(segment
		(start -308.25743 30.861)
		(end -308.67399 30.861)
		(width 0.11176)
		(layer "In5.Cu")
		(net "ETH40G_B1_TX3N")
	)
	(segment
		(start -292.8493 43.650411)
		(end -293.08044 43.419271)
		(width 0.11176)
		(layer "In5.Cu")
		(net "ETH40G_B1_TX3N")
	)
	(segment
		(start -307.06026 30.6324)
		(end -308.02883 30.6324)
		(width 0.11176)
		(layer "In5.Cu")
		(net "ETH40G_B1_TX3N")
	)
	(segment
		(start -292.8493 42.672)
		(end -292.8493 41.952004)
		(width 0.11176)
		(layer "In5.Cu")
		(net "ETH40G_B1_TX3N")
	)
	(segment
		(start -306.1865 30.6324)
		(end -306.4151 30.861)
		(width 0.11176)
		(layer "In5.Cu")
		(net "ETH40G_B1_TX3N")
	)
	(segment
		(start -311.8607 32.295394)
		(end -312.620558 33.05525)
		(width 0.11176)
		(layer "In5.Cu")
		(net "ETH40G_B1_TX3N")
	)
	(segment
		(start -303.022 30.6324)
		(end -303.25314 30.86354)
		(width 0.11176)
		(layer "In5.Cu")
		(net "ETH40G_B1_TX3N")
	)
	(segment
		(start -292.8493 41.952004)
		(end -293.08044 41.720864)
		(width 0.11176)
		(layer "In5.Cu")
		(net "ETH40G_B1_TX3N")
	)
	(segment
		(start -297.91914 30.86354)
		(end -298.442245 30.86354)
		(width 0.11176)
		(layer "In5.Cu")
		(net "ETH40G_B1_TX3N")
	)
	(segment
		(start -306.83166 30.861)
		(end -307.06026 30.6324)
		(width 0.11176)
		(layer "In5.Cu")
		(net "ETH40G_B1_TX3N")
	)
	(segment
		(start -298.673385 30.6324)
		(end -303.022 30.6324)
		(width 0.11176)
		(layer "In5.Cu")
		(net "ETH40G_B1_TX3N")
	)
	(segment
		(start -304.043926 30.6324)
		(end -306.1865 30.6324)
		(width 0.11176)
		(layer "In5.Cu")
		(net "ETH40G_B1_TX3N")
	)
	(segment
		(start -308.90259 30.6324)
		(end -309.377055 30.6324)
		(width 0.11176)
		(layer "In5.Cu")
		(net "ETH40G_B1_TX3N")
	)
	(segment
		(start -303.25314 30.86354)
		(end -303.812786 30.86354)
		(width 0.11176)
		(layer "In5.Cu")
		(net "ETH40G_B1_TX3N")
	)
	(segment
		(start -311.708094 32.295394)
		(end -311.8607 32.295394)
		(width 0.11176)
		(layer "In5.Cu")
		(net "ETH40G_B1_TX3N")
	)
	(segment
		(start -293.08044 42.90314)
		(end -292.8493 42.672)
		(width 0.11176)
		(layer "In5.Cu")
		(net "ETH40G_B1_TX3N")
	)
	(segment
		(start -298.442245 30.86354)
		(end -298.673385 30.6324)
		(width 0.11176)
		(layer "In5.Cu")
		(net "ETH40G_B1_TX3N")
	)
	(segment
		(start -296.46009 30.6324)
		(end -297.688 30.6324)
		(width 0.11176)
		(layer "In5.Cu")
		(net "ETH40G_B1_TX3N")
	)
	(segment
		(start -311.405923 31.920729)
		(end -311.405923 31.993223)
		(width 0.11176)
		(layer "In5.Cu")
		(net "ETH40G_B1_TX3N")
	)
	(segment
		(start -292.8493 41.0083)
		(end -292.8493 39.422461)
		(width 0.11176)
		(layer "In5.Cu")
		(net "ETH40G_B1_TX3N")
	)
	(segment
		(start -293.08044 39.191321)
		(end -293.08044 38.754441)
		(width 0.11176)
		(layer "In5.Cu")
		(net "ETH40G_B1_TX3N")
	)
	(segment
		(start -293.08044 37.438721)
		(end -292.8493 37.207581)
		(width 0.11176)
		(layer "In5.Cu")
		(net "ETH40G_B1_TX3N")
	)
	(segment
		(start -293.08044 43.419271)
		(end -293.08044 42.90314)
		(width 0.11176)
		(layer "In5.Cu")
		(net "ETH40G_B1_TX3N")
	)
	(segment
		(start -292.8493 38.106741)
		(end -293.08044 37.875601)
		(width 0.11176)
		(layer "In5.Cu")
		(net "ETH40G_B1_TX3N")
	)
	(segment
		(start -293.08044 37.875601)
		(end -293.08044 37.438721)
		(width 0.11176)
		(layer "In5.Cu")
		(net "ETH40G_B1_TX3N")
	)
	(segment
		(start -311.405925 31.84062)
		(end -311.405923 31.920729)
		(width 0.11176)
		(layer "In5.Cu")
		(net "ETH40G_B1_TX3N")
	)
	(segment
		(start -294.040001 43.960001)
		(end -293.51145 44.488552)
		(width 0.11176)
		(layer "In5.Cu")
		(net "ETH40G_B1_TX3N")
	)
	(segment
		(start -293.51145 44.488552)
		(end -293.39969 44.488552)
		(width 0.11176)
		(layer "In5.Cu")
		(net "ETH40G_B1_TX3N")
	)
	(segment
		(start -292.8493 37.207581)
		(end -292.8493 34.460731)
		(width 0.11176)
		(layer "In5.Cu")
		(net "ETH40G_B1_TX3N")
	)
	(segment
		(start -308.67399 30.861)
		(end -308.90259 30.6324)
		(width 0.11176)
		(layer "In5.Cu")
		(net "ETH40G_B1_TX3N")
	)
	(arc
		(start -312.620558 33.05525)
		(mid -312.663478 33.119487)
		(end -312.678549 33.19526)
		(width 0.11176)
		(layer "In5.Cu")
		(net "ETH40G_B1_TX3N")
	)
	(arc
		(start -295.91127 30.85973)
		(mid -296.163071 30.691482)
		(end -296.46009 30.6324)
		(width 0.11176)
		(layer "In5.Cu")
		(net "ETH40G_B1_TX3N")
	)
	(arc
		(start -309.377055 30.6324)
		(mid -310.135237 30.783212)
		(end -310.777992 31.212688)
		(width 0.11176)
		(layer "In5.Cu")
		(net "ETH40G_B1_TX3N")
	)
	(arc
		(start -292.8493 34.460731)
		(mid -292.948359 33.962729)
		(end -293.230455 33.540545)
		(width 0.11176)
		(layer "In5.Cu")
		(net "ETH40G_B1_TX3N")
	)
	(arc
		(start -312.678552 33.55768)
		(mid -312.61749 33.864657)
		(end -312.443602 34.1249)
		(width 0.11176)
		(layer "In5.Cu")
		(net "ETH40G_B1_TX3N")
	)
	(arc
		(start -293.39969 44.488552)
		(mid -293.010505 44.327347)
		(end -292.8493 43.938162)
		(width 0.11176)
		(layer "In5.Cu")
		(net "ETH40G_B1_TX3N")
	)
	(segment
		(start -313.64174 46.46168)
		(end -313.64174 46.638875)
		(width 0.10668)
		(layer "F.Cu")
		(net "ETH40G_B1_TX2P")
	)
	(segment
		(start -312.849999 43.840001)
		(end -312.849999 44.865397)
		(width 0.10668)
		(layer "F.Cu")
		(net "ETH40G_B1_TX2P")
	)
	(segment
		(start -312.849999 44.865397)
		(end -312.66717 45.048226)
		(width 0.10668)
		(layer "F.Cu")
		(net "ETH40G_B1_TX2P")
	)
	(segment
		(start -312.66717 45.23565)
		(end -313.24296 45.81144)
		(width 0.10668)
		(layer "F.Cu")
		(net "ETH40G_B1_TX2P")
	)
	(segment
		(start -312.66717 45.048226)
		(end -312.66717 45.23565)
		(width 0.10668)
		(layer "F.Cu")
		(net "ETH40G_B1_TX2P")
	)
	(segment
		(start -313.24296 45.81144)
		(end -313.463932 46.03241)
		(width 0.10668)
		(layer "F.Cu")
		(net "ETH40G_B1_TX2P")
	)
	(via
		(at -313.82716 47.08652)
		(size 0.5588)
		(drill 0.254)
		(layers "F.Cu" "B.Cu")
		(net "ETH40G_B1_TX2P")
	)
	(arc
		(start -313.463932 46.03241)
		(mid -313.595529 46.229361)
		(end -313.64174 46.46168)
		(width 0.10668)
		(layer "F.Cu")
		(net "ETH40G_B1_TX2P")
	)
	(arc
		(start -313.64174 46.638875)
		(mid -313.689929 46.881138)
		(end -313.82716 47.08652)
		(width 0.10668)
		(layer "F.Cu")
		(net "ETH40G_B1_TX2P")
	)
	(segment
		(start -305.938766 32.574332)
		(end -305.517116 32.152679)
		(width 0.11176)
		(layer "In5.Cu")
		(net "ETH40G_B1_TX2P")
	)
	(segment
		(start -308.458768 37.946434)
		(end -308.366673 37.854341)
		(width 0.11176)
		(layer "In5.Cu")
		(net "ETH40G_B1_TX2P")
	)
	(segment
		(start -313.82716 47.08652)
		(end -313.74286 47.00222)
		(width 0.11176)
		(layer "In5.Cu")
		(net "ETH40G_B1_TX2P")
	)
	(segment
		(start -306.133221 32.768784)
		(end -305.938766 32.574332)
		(width 0.11176)
		(layer "In5.Cu")
		(net "ETH40G_B1_TX2P")
	)
	(segment
		(start -298.8564 32.9438)
		(end -298.8564 42.9768)
		(width 0.11176)
		(layer "In5.Cu")
		(net "ETH40G_B1_TX2P")
	)
	(segment
		(start -308.6735 42.8498)
		(end -308.6735 38.464851)
		(width 0.11176)
		(layer "In5.Cu")
		(net "ETH40G_B1_TX2P")
	)
	(segment
		(start -311.9882 43.561)
		(end -309.3847 43.561)
		(width 0.11176)
		(layer "In5.Cu")
		(net "ETH40G_B1_TX2P")
	)
	(segment
		(start -300.040002 44.033402)
		(end -300.040002 44.060001)
		(width 0.11176)
		(layer "In5.Cu")
		(net "ETH40G_B1_TX2P")
	)
	(segment
		(start -313.182493 45.649373)
		(end -312.827325 45.294205)
		(width 0.11176)
		(layer "In5.Cu")
		(net "ETH40G_B1_TX2P")
	)
	(segment
		(start -306.5218 36.595997)
		(end -306.5218 33.7069)
		(width 0.11176)
		(layer "In5.Cu")
		(net "ETH40G_B1_TX2P")
	)
	(segment
		(start -299.4152 43.5356)
		(end -299.5422 43.5356)
		(width 0.11176)
		(layer "In5.Cu")
		(net "ETH40G_B1_TX2P")
	)
	(segment
		(start -304.6676 31.8008)
		(end -299.9994 31.8008)
		(width 0.11176)
		(layer "In5.Cu")
		(net "ETH40G_B1_TX2P")
	)
	(segment
		(start -312.62145 44.79718)
		(end -312.62145 44.19425)
		(width 0.11176)
		(layer "In5.Cu")
		(net "ETH40G_B1_TX2P")
	)
	(arc
		(start -313.74286 47.00222)
		(mid -313.628543 46.831132)
		(end -313.5884 46.62932)
		(width 0.11176)
		(layer "In5.Cu")
		(net "ETH40G_B1_TX2P")
	)
	(arc
		(start -308.6735 38.464851)
		(mid -308.617694 38.184286)
		(end -308.458768 37.946434)
		(width 0.11176)
		(layer "In5.Cu")
		(net "ETH40G_B1_TX2P")
	)
	(arc
		(start -309.3847 43.561)
		(mid -308.881806 43.352694)
		(end -308.6735 42.8498)
		(width 0.11176)
		(layer "In5.Cu")
		(net "ETH40G_B1_TX2P")
	)
	(arc
		(start -298.8564 42.9768)
		(mid -299.020069 43.371931)
		(end -299.4152 43.5356)
		(width 0.11176)
		(layer "In5.Cu")
		(net "ETH40G_B1_TX2P")
	)
	(arc
		(start -306.5218 33.7069)
		(mid -306.420812 33.199195)
		(end -306.133221 32.768784)
		(width 0.11176)
		(layer "In5.Cu")
		(net "ETH40G_B1_TX2P")
	)
	(arc
		(start -307.365403 37.4396)
		(mid -306.768886 37.192514)
		(end -306.5218 36.595997)
		(width 0.11176)
		(layer "In5.Cu")
		(net "ETH40G_B1_TX2P")
	)
	(arc
		(start -299.9994 31.8008)
		(mid -299.191177 32.135577)
		(end -298.8564 32.9438)
		(width 0.11176)
		(layer "In5.Cu")
		(net "ETH40G_B1_TX2P")
	)
	(arc
		(start -313.5884 46.62932)
		(mid -313.482908 46.098977)
		(end -313.182493 45.649373)
		(width 0.11176)
		(layer "In5.Cu")
		(net "ETH40G_B1_TX2P")
	)
	(arc
		(start -305.517116 32.152679)
		(mid -305.127355 31.89225)
		(end -304.6676 31.8008)
		(width 0.11176)
		(layer "In5.Cu")
		(net "ETH40G_B1_TX2P")
	)
	(arc
		(start -312.62145 44.19425)
		(mid -312.435975 43.746475)
		(end -311.9882 43.561)
		(width 0.11176)
		(layer "In5.Cu")
		(net "ETH40G_B1_TX2P")
	)
	(arc
		(start -312.827325 45.294205)
		(mid -312.674955 45.066168)
		(end -312.62145 44.79718)
		(width 0.11176)
		(layer "In5.Cu")
		(net "ETH40G_B1_TX2P")
	)
	(arc
		(start -299.5422 43.5356)
		(mid -299.894199 43.681403)
		(end -300.040002 44.033402)
		(width 0.11176)
		(layer "In5.Cu")
		(net "ETH40G_B1_TX2P")
	)
	(arc
		(start -308.366673 37.854341)
		(mid -307.907286 37.547388)
		(end -307.365403 37.4396)
		(width 0.11176)
		(layer "In5.Cu")
		(net "ETH40G_B1_TX2P")
	)
	(segment
		(start -313.2074 46.461677)
		(end -313.2074 46.620481)
		(width 0.10668)
		(layer "F.Cu")
		(net "ETH40G_B1_TX2N")
	)
	(segment
		(start -312.050001 44.865397)
		(end -312.23283 45.048226)
		(width 0.10668)
		(layer "F.Cu")
		(net "ETH40G_B1_TX2N")
	)
	(segment
		(start -312.23283 45.415561)
		(end -313.156806 46.339536)
		(width 0.10668)
		(layer "F.Cu")
		(net "ETH40G_B1_TX2N")
	)
	(segment
		(start -312.050001 43.840001)
		(end -312.050001 44.865397)
		(width 0.10668)
		(layer "F.Cu")
		(net "ETH40G_B1_TX2N")
	)
	(segment
		(start -312.23283 45.048226)
		(end -312.23283 45.415561)
		(width 0.10668)
		(layer "F.Cu")
		(net "ETH40G_B1_TX2N")
	)
	(via
		(at -313.01436 47.08652)
		(size 0.5588)
		(drill 0.254)
		(layers "F.Cu" "B.Cu")
		(net "ETH40G_B1_TX2N")
	)
	(arc
		(start -313.2074 46.620481)
		(mid -313.157231 46.8727)
		(end -313.01436 47.08652)
		(width 0.10668)
		(layer "F.Cu")
		(net "ETH40G_B1_TX2N")
	)
	(arc
		(start -313.156806 46.339536)
		(mid -313.19425 46.395575)
		(end -313.2074 46.461677)
		(width 0.10668)
		(layer "F.Cu")
		(net "ETH40G_B1_TX2N")
	)
	(segment
		(start -308.2163 38.188903)
		(end -308.124207 38.09681)
		(width 0.11176)
		(layer "In5.Cu")
		(net "ETH40G_B1_TX2N")
	)
	(segment
		(start -306.1789 36.595997)
		(end -306.1789 35.93194)
		(width 0.11176)
		(layer "In5.Cu")
		(net "ETH40G_B1_TX2N")
	)
	(segment
		(start -310.370134 44.0944)
		(end -309.953574 44.0944)
		(width 0.11176)
		(layer "In5.Cu")
		(net "ETH40G_B1_TX2N")
	)
	(segment
		(start -311.9882 43.9039)
		(end -311.774754 43.9039)
		(width 0.11176)
		(layer "In5.Cu")
		(net "ETH40G_B1_TX2N")
	)
	(segment
		(start -305.9884 35.74144)
		(end -305.9884 35.32488)
		(width 0.11176)
		(layer "In5.Cu")
		(net "ETH40G_B1_TX2N")
	)
	(segment
		(start -312.27855 44.79718)
		(end -312.27855 44.19425)
		(width 0.11176)
		(layer "In5.Cu")
		(net "ETH40G_B1_TX2N")
	)
	(segment
		(start -310.977194 43.9039)
		(end -310.560634 43.9039)
		(width 0.11176)
		(layer "In5.Cu")
		(net "ETH40G_B1_TX2N")
	)
	(segment
		(start -308.10168 40.40632)
		(end -308.10168 40.11168)
		(width 0.11176)
		(layer "In5.Cu")
		(net "ETH40G_B1_TX2N")
	)
	(segment
		(start -303.262563 32.1437)
		(end -303.031423 32.37484)
		(width 0.11176)
		(layer "In5.Cu")
		(net "ETH40G_B1_TX2N")
	)
	(segment
		(start -305.94776 34.48668)
		(end -305.94776 34.1514)
		(width 0.11176)
		(layer "In5.Cu")
		(net "ETH40G_B1_TX2N")
	)
	(segment
		(start -305.6963 32.8168)
		(end -305.274647 32.395147)
		(width 0.11176)
		(layer "In5.Cu")
		(net "ETH40G_B1_TX2N")
	)
	(segment
		(start -308.16296 41.364218)
		(end -308.16296 41.034018)
		(width 0.11176)
		(layer "In5.Cu")
		(net "ETH40G_B1_TX2N")
	)
	(segment
		(start -305.9884 35.32488)
		(end -306.1789 35.13438)
		(width 0.11176)
		(layer "In5.Cu")
		(net "ETH40G_B1_TX2N")
	)
	(segment
		(start -306.1789 34.71782)
		(end -305.94776 34.48668)
		(width 0.11176)
		(layer "In5.Cu")
		(net "ETH40G_B1_TX2N")
	)
	(segment
		(start -304.6676 32.1437)
		(end -303.262563 32.1437)
		(width 0.11176)
		(layer "In5.Cu")
		(net "ETH40G_B1_TX2N")
	)
	(segment
		(start -308.10168 39.01472)
		(end -308.3306 38.7858)
		(width 0.11176)
		(layer "In5.Cu")
		(net "ETH40G_B1_TX2N")
	)
	(segment
		(start -308.10168 40.11168)
		(end -308.3306 39.88276)
		(width 0.11176)
		(layer "In5.Cu")
		(net "ETH40G_B1_TX2N")
	)
	(segment
		(start -302.236403 32.1437)
		(end -301.819843 32.1437)
		(width 0.11176)
		(layer "In5.Cu")
		(net "ETH40G_B1_TX2N")
	)
	(segment
		(start -301.819843 32.1437)
		(end -301.588703 32.37484)
		(width 0.11176)
		(layer "In5.Cu")
		(net "ETH40G_B1_TX2N")
	)
	(segment
		(start -300.040002 42.694898)
		(end -300.040002 42.660001)
		(width 0.11176)
		(layer "In5.Cu")
		(net "ETH40G_B1_TX2N")
	)
	(segment
		(start -313.01436 47.08652)
		(end -313.08565 47.015227)
		(width 0.11176)
		(layer "In5.Cu")
		(net "ETH40G_B1_TX2N")
	)
	(segment
		(start -308.3306 42.07478)
		(end -308.3306 41.531858)
		(width 0.11176)
		(layer "In5.Cu")
		(net "ETH40G_B1_TX2N")
	)
	(segment
		(start -301.588703 32.37484)
		(end -301.024823 32.37484)
		(width 0.11176)
		(layer "In5.Cu")
		(net "ETH40G_B1_TX2N")
	)
	(segment
		(start -308.3306 39.56844)
		(end -308.10168 39.33952)
		(width 0.11176)
		(layer "In5.Cu")
		(net "ETH40G_B1_TX2N")
	)
	(segment
		(start -308.3306 40.63524)
		(end -308.10168 40.40632)
		(width 0.11176)
		(layer "In5.Cu")
		(net "ETH40G_B1_TX2N")
	)
	(segment
		(start -308.32806 42.84726)
		(end -308.32806 42.07732)
		(width 0.11176)
		(layer "In5.Cu")
		(net "ETH40G_B1_TX2N")
	)
	(segment
		(start -309.953574 44.0944)
		(end -309.763074 43.9039)
		(width 0.11176)
		(layer "In5.Cu")
		(net "ETH40G_B1_TX2N")
	)
	(segment
		(start -308.3306 42.8498)
		(end -308.32806 42.84726)
		(width 0.11176)
		(layer "In5.Cu")
		(net "ETH40G_B1_TX2N")
	)
	(segment
		(start -299.1993 32.9438)
		(end -299.1993 42.9768)
		(width 0.11176)
		(layer "In5.Cu")
		(net "ETH40G_B1_TX2N")
	)
	(segment
		(start -308.3306 40.866378)
		(end -308.3306 40.63524)
		(width 0.11176)
		(layer "In5.Cu")
		(net "ETH40G_B1_TX2N")
	)
	(segment
		(start -308.10168 39.33952)
		(end -308.10168 39.01472)
		(width 0.11176)
		(layer "In5.Cu")
		(net "ETH40G_B1_TX2N")
	)
	(segment
		(start -302.467543 32.37484)
		(end -302.236403 32.1437)
		(width 0.11176)
		(layer "In5.Cu")
		(net "ETH40G_B1_TX2N")
	)
	(segment
		(start -306.1789 35.13438)
		(end -306.1789 34.71782)
		(width 0.11176)
		(layer "In5.Cu")
		(net "ETH40G_B1_TX2N")
	)
	(segment
		(start -305.94776 34.1514)
		(end -306.1789 33.92026)
		(width 0.11176)
		(layer "In5.Cu")
		(net "ETH40G_B1_TX2N")
	)
	(segment
		(start -310.560634 43.9039)
		(end -310.370134 44.0944)
		(width 0.11176)
		(layer "In5.Cu")
		(net "ETH40G_B1_TX2N")
	)
	(segment
		(start -311.774754 43.9039)
		(end -311.558854 44.1198)
		(width 0.11176)
		(layer "In5.Cu")
		(net "ETH40G_B1_TX2N")
	)
	(segment
		(start -308.3306 38.7858)
		(end -308.3306 38.464848)
		(width 0.11176)
		(layer "In5.Cu")
		(net "ETH40G_B1_TX2N")
	)
	(segment
		(start -303.031423 32.37484)
		(end -302.467543 32.37484)
		(width 0.11176)
		(layer "In5.Cu")
		(net "ETH40G_B1_TX2N")
	)
	(segment
		(start -312.940024 45.891841)
		(end -312.584856 45.536673)
		(width 0.11176)
		(layer "In5.Cu")
		(net "ETH40G_B1_TX2N")
	)
	(segment
		(start -308.16296 41.034018)
		(end -308.3306 40.866378)
		(width 0.11176)
		(layer "In5.Cu")
		(net "ETH40G_B1_TX2N")
	)
	(segment
		(start -311.558854 44.1198)
		(end -311.193094 44.1198)
		(width 0.11176)
		(layer "In5.Cu")
		(net "ETH40G_B1_TX2N")
	)
	(segment
		(start -308.3306 39.88276)
		(end -308.3306 39.56844)
		(width 0.11176)
		(layer "In5.Cu")
		(net "ETH40G_B1_TX2N")
	)
	(segment
		(start -306.1789 33.92026)
		(end -306.1789 33.7069)
		(width 0.11176)
		(layer "In5.Cu")
		(net "ETH40G_B1_TX2N")
	)
	(segment
		(start -309.763074 43.9039)
		(end -309.3847 43.9039)
		(width 0.11176)
		(layer "In5.Cu")
		(net "ETH40G_B1_TX2N")
	)
	(segment
		(start -308.32806 42.07732)
		(end -308.3306 42.07478)
		(width 0.11176)
		(layer "In5.Cu")
		(net "ETH40G_B1_TX2N")
	)
	(segment
		(start -299.4152 43.1927)
		(end -299.5422 43.1927)
		(width 0.11176)
		(layer "In5.Cu")
		(net "ETH40G_B1_TX2N")
	)
	(segment
		(start -301.024823 32.37484)
		(end -300.793683 32.1437)
		(width 0.11176)
		(layer "In5.Cu")
		(net "ETH40G_B1_TX2N")
	)
	(segment
		(start -308.3306 41.531858)
		(end -308.16296 41.364218)
		(width 0.11176)
		(layer "In5.Cu")
		(net "ETH40G_B1_TX2N")
	)
	(segment
		(start -306.1789 35.93194)
		(end -305.9884 35.74144)
		(width 0.11176)
		(layer "In5.Cu")
		(net "ETH40G_B1_TX2N")
	)
	(segment
		(start -300.793683 32.1437)
		(end -299.9994 32.1437)
		(width 0.11176)
		(layer "In5.Cu")
		(net "ETH40G_B1_TX2N")
	)
	(segment
		(start -311.193094 44.1198)
		(end -310.977194 43.9039)
		(width 0.11176)
		(layer "In5.Cu")
		(net "ETH40G_B1_TX2N")
	)
	(segment
		(start -305.890755 33.011252)
		(end -305.6963 32.8168)
		(width 0.11176)
		(layer "In5.Cu")
		(net "ETH40G_B1_TX2N")
	)
	(arc
		(start -305.274647 32.395147)
		(mid -304.996131 32.209049)
		(end -304.6676 32.1437)
		(width 0.11176)
		(layer "In5.Cu")
		(net "ETH40G_B1_TX2N")
	)
	(arc
		(start -308.3306 38.464848)
		(mid -308.300894 38.315508)
		(end -308.2163 38.188903)
		(width 0.11176)
		(layer "In5.Cu")
		(net "ETH40G_B1_TX2N")
	)
	(arc
		(start -313.2455 46.62932)
		(mid -313.166109 46.230199)
		(end -312.940024 45.891841)
		(width 0.11176)
		(layer "In5.Cu")
		(net "ETH40G_B1_TX2N")
	)
	(arc
		(start -313.08565 47.015227)
		(mid -313.203956 46.838172)
		(end -313.2455 46.62932)
		(width 0.11176)
		(layer "In5.Cu")
		(net "ETH40G_B1_TX2N")
	)
	(arc
		(start -299.1993 42.9768)
		(mid -299.262536 43.129464)
		(end -299.4152 43.1927)
		(width 0.11176)
		(layer "In5.Cu")
		(net "ETH40G_B1_TX2N")
	)
	(arc
		(start -306.1789 33.7069)
		(mid -306.104014 33.330418)
		(end -305.890755 33.011252)
		(width 0.11176)
		(layer "In5.Cu")
		(net "ETH40G_B1_TX2N")
	)
	(arc
		(start -312.27855 44.19425)
		(mid -312.193508 43.988942)
		(end -311.9882 43.9039)
		(width 0.11176)
		(layer "In5.Cu")
		(net "ETH40G_B1_TX2N")
	)
	(arc
		(start -309.3847 43.9039)
		(mid -308.639339 43.595161)
		(end -308.3306 42.8498)
		(width 0.11176)
		(layer "In5.Cu")
		(net "ETH40G_B1_TX2N")
	)
	(arc
		(start -299.5422 43.1927)
		(mid -299.894199 43.046897)
		(end -300.040002 42.694898)
		(width 0.11176)
		(layer "In5.Cu")
		(net "ETH40G_B1_TX2N")
	)
	(arc
		(start -299.9994 32.1437)
		(mid -299.433644 32.378044)
		(end -299.1993 32.9438)
		(width 0.11176)
		(layer "In5.Cu")
		(net "ETH40G_B1_TX2N")
	)
	(arc
		(start -308.124207 38.09681)
		(mid -307.776063 37.864188)
		(end -307.3654 37.782503)
		(width 0.11176)
		(layer "In5.Cu")
		(net "ETH40G_B1_TX2N")
	)
	(arc
		(start -312.584856 45.536673)
		(mid -312.358155 45.197391)
		(end -312.27855 44.79718)
		(width 0.11176)
		(layer "In5.Cu")
		(net "ETH40G_B1_TX2N")
	)
	(arc
		(start -307.3654 37.782503)
		(mid -306.526417 37.434982)
		(end -306.1789 36.595997)
		(width 0.11176)
		(layer "In5.Cu")
		(net "ETH40G_B1_TX2N")
	)
	(segment
		(start -310.818754 40.283359)
		(end -310.698416 40.163021)
		(width 0.10668)
		(layer "F.Cu")
		(net "ETH40G_B1_TX1P")
	)
	(segment
		(start -310.667169 40.087586)
		(end -310.667169 38.498211)
		(width 0.10668)
		(layer "F.Cu")
		(net "ETH40G_B1_TX1P")
	)
	(segment
		(start -310.850001 41.340001)
		(end -310.850001 40.358794)
		(width 0.10668)
		(layer "F.Cu")
		(net "ETH40G_B1_TX1P")
	)
	(via
		(at -310.842635 38.0746)
		(size 0.5588)
		(drill 0.254)
		(layers "F.Cu" "B.Cu")
		(net "ETH40G_B1_TX1P")
	)
	(arc
		(start -310.850001 40.358794)
		(mid -310.84188 40.317969)
		(end -310.818754 40.283359)
		(width 0.10668)
		(layer "F.Cu")
		(net "ETH40G_B1_TX1P")
	)
	(arc
		(start -310.667169 38.498211)
		(mid -310.712771 38.268954)
		(end -310.842635 38.0746)
		(width 0.10668)
		(layer "F.Cu")
		(net "ETH40G_B1_TX1P")
	)
	(arc
		(start -310.698416 40.163021)
		(mid -310.67529 40.128411)
		(end -310.667169 40.087586)
		(width 0.10668)
		(layer "F.Cu")
		(net "ETH40G_B1_TX1P")
	)
	(segment
		(start -310.653405 40.386)
		(end -310.653405 38.531442)
		(width 0.10668)
		(layer "B.Cu")
		(net "ETH40G_B1_TX1P")
	)
	(segment
		(start -304.040002 44.060001)
		(end -304.491583 43.608419)
		(width 0.10668)
		(layer "B.Cu")
		(net "ETH40G_B1_TX1P")
	)
	(segment
		(start -305.476341 41.23436)
		(end -309.805045 41.23436)
		(width 0.10668)
		(layer "B.Cu")
		(net "ETH40G_B1_TX1P")
	)
	(segment
		(start -304.567019 43.577172)
		(end -304.673701 43.577172)
		(width 0.10668)
		(layer "B.Cu")
		(net "ETH40G_B1_TX1P")
	)
	(segment
		(start -305.214721 43.036152)
		(end -305.214721 41.49598)
		(width 0.10668)
		(layer "B.Cu")
		(net "ETH40G_B1_TX1P")
	)
	(arc
		(start -304.673701 43.577172)
		(mid -305.05626 43.418711)
		(end -305.214721 43.036152)
		(width 0.10668)
		(layer "B.Cu")
		(net "ETH40G_B1_TX1P")
	)
	(arc
		(start -304.491583 43.608419)
		(mid -304.526193 43.585292)
		(end -304.567019 43.577172)
		(width 0.10668)
		(layer "B.Cu")
		(net "ETH40G_B1_TX1P")
	)
	(arc
		(start -305.214721 41.49598)
		(mid -305.291348 41.310987)
		(end -305.476341 41.23436)
		(width 0.10668)
		(layer "B.Cu")
		(net "ETH40G_B1_TX1P")
	)
	(arc
		(start -309.805045 41.23436)
		(mid -310.404926 40.985881)
		(end -310.653405 40.386)
		(width 0.10668)
		(layer "B.Cu")
		(net "ETH40G_B1_TX1P")
	)
	(arc
		(start -310.653405 38.531442)
		(mid -310.702584 38.284201)
		(end -310.842635 38.0746)
		(width 0.10668)
		(layer "B.Cu")
		(net "ETH40G_B1_TX1P")
	)
	(segment
		(start -310.232829 40.087588)
		(end -310.232829 38.564673)
		(width 0.10668)
		(layer "F.Cu")
		(net "ETH40G_B1_TX1N")
	)
	(segment
		(start -310.081247 40.283359)
		(end -310.201582 40.163024)
		(width 0.10668)
		(layer "F.Cu")
		(net "ETH40G_B1_TX1N")
	)
	(segment
		(start -310.05 41.340001)
		(end -310.05 40.358794)
		(width 0.10668)
		(layer "F.Cu")
		(net "ETH40G_B1_TX1N")
	)
	(via
		(at -310.029835 38.0746)
		(size 0.5588)
		(drill 0.254)
		(layers "F.Cu" "B.Cu")
		(net "ETH40G_B1_TX1N")
	)
	(arc
		(start -310.232829 38.564673)
		(mid -310.180073 38.299448)
		(end -310.029835 38.0746)
		(width 0.10668)
		(layer "F.Cu")
		(net "ETH40G_B1_TX1N")
	)
	(arc
		(start -310.201582 40.163024)
		(mid -310.224709 40.128414)
		(end -310.232829 40.087588)
		(width 0.10668)
		(layer "F.Cu")
		(net "ETH40G_B1_TX1N")
	)
	(arc
		(start -310.05 40.358794)
		(mid -310.058121 40.317969)
		(end -310.081247 40.283359)
		(width 0.10668)
		(layer "F.Cu")
		(net "ETH40G_B1_TX1N")
	)
	(segment
		(start -310.219065 39.105822)
		(end -310.08828 39.236607)
		(width 0.10668)
		(layer "B.Cu")
		(net "ETH40G_B1_TX1N")
	)
	(segment
		(start -306.175448 40.57142)
		(end -305.946848 40.80002)
		(width 0.10668)
		(layer "B.Cu")
		(net "ETH40G_B1_TX1N")
	)
	(segment
		(start -310.08828 39.719847)
		(end -310.219065 39.850632)
		(width 0.10668)
		(layer "B.Cu")
		(net "ETH40G_B1_TX1N")
	)
	(segment
		(start -310.08828 39.236607)
		(end -310.08828 39.719847)
		(width 0.10668)
		(layer "B.Cu")
		(net "ETH40G_B1_TX1N")
	)
	(segment
		(start -310.219065 38.531442)
		(end -310.219065 39.105822)
		(width 0.10668)
		(layer "B.Cu")
		(net "ETH40G_B1_TX1N")
	)
	(segment
		(start -308.735768 40.57142)
		(end -308.507168 40.80002)
		(width 0.10668)
		(layer "B.Cu")
		(net "ETH40G_B1_TX1N")
	)
	(segment
		(start -304.780381 41.49598)
		(end -304.780381 43.036152)
		(width 0.10668)
		(layer "B.Cu")
		(net "ETH40G_B1_TX1N")
	)
	(segment
		(start -309.147248 40.57142)
		(end -308.735768 40.57142)
		(width 0.10668)
		(layer "B.Cu")
		(net "ETH40G_B1_TX1N")
	)
	(segment
		(start -307.455608 40.57142)
		(end -307.227008 40.80002)
		(width 0.10668)
		(layer "B.Cu")
		(net "ETH40G_B1_TX1N")
	)
	(segment
		(start -308.507168 40.80002)
		(end -308.095688 40.80002)
		(width 0.10668)
		(layer "B.Cu")
		(net "ETH40G_B1_TX1N")
	)
	(segment
		(start -304.673701 43.142832)
		(end -304.567021 43.142832)
		(width 0.10668)
		(layer "B.Cu")
		(net "ETH40G_B1_TX1N")
	)
	(segment
		(start -309.375848 40.80002)
		(end -309.147248 40.57142)
		(width 0.10668)
		(layer "B.Cu")
		(net "ETH40G_B1_TX1N")
	)
	(segment
		(start -306.586928 40.57142)
		(end -306.175448 40.57142)
		(width 0.10668)
		(layer "B.Cu")
		(net "ETH40G_B1_TX1N")
	)
	(segment
		(start -307.867088 40.57142)
		(end -307.455608 40.57142)
		(width 0.10668)
		(layer "B.Cu")
		(net "ETH40G_B1_TX1N")
	)
	(segment
		(start -310.219065 39.850632)
		(end -310.219065 40.386)
		(width 0.10668)
		(layer "B.Cu")
		(net "ETH40G_B1_TX1N")
	)
	(segment
		(start -306.815528 40.80002)
		(end -306.586928 40.57142)
		(width 0.10668)
		(layer "B.Cu")
		(net "ETH40G_B1_TX1N")
	)
	(segment
		(start -307.227008 40.80002)
		(end -306.815528 40.80002)
		(width 0.10668)
		(layer "B.Cu")
		(net "ETH40G_B1_TX1N")
	)
	(segment
		(start -305.946848 40.80002)
		(end -305.476341 40.80002)
		(width 0.10668)
		(layer "B.Cu")
		(net "ETH40G_B1_TX1N")
	)
	(segment
		(start -309.805045 40.80002)
		(end -309.375848 40.80002)
		(width 0.10668)
		(layer "B.Cu")
		(net "ETH40G_B1_TX1N")
	)
	(segment
		(start -308.095688 40.80002)
		(end -307.867088 40.57142)
		(width 0.10668)
		(layer "B.Cu")
		(net "ETH40G_B1_TX1N")
	)
	(segment
		(start -304.491586 43.111585)
		(end -304.040002 42.660001)
		(width 0.10668)
		(layer "B.Cu")
		(net "ETH40G_B1_TX1N")
	)
	(arc
		(start -305.476341 40.80002)
		(mid -304.984223 41.003862)
		(end -304.780381 41.49598)
		(width 0.10668)
		(layer "B.Cu")
		(net "ETH40G_B1_TX1N")
	)
	(arc
		(start -310.029835 38.0746)
		(mid -310.169886 38.284201)
		(end -310.219065 38.531442)
		(width 0.10668)
		(layer "B.Cu")
		(net "ETH40G_B1_TX1N")
	)
	(arc
		(start -304.567021 43.142832)
		(mid -304.526196 43.134711)
		(end -304.491586 43.111585)
		(width 0.10668)
		(layer "B.Cu")
		(net "ETH40G_B1_TX1N")
	)
	(arc
		(start -304.780381 43.036152)
		(mid -304.749135 43.111586)
		(end -304.673701 43.142832)
		(width 0.10668)
		(layer "B.Cu")
		(net "ETH40G_B1_TX1N")
	)
	(arc
		(start -310.219065 40.386)
		(mid -310.097801 40.678756)
		(end -309.805045 40.80002)
		(width 0.10668)
		(layer "B.Cu")
		(net "ETH40G_B1_TX1N")
	)
	(segment
		(start -310.26717 45.092414)
		(end -310.26717 45.63872)
		(width 0.10668)
		(layer "F.Cu")
		(net "ETH40G_B1_TX0P")
	)
	(segment
		(start -310.449999 43.840001)
		(end -310.449999 44.821208)
		(width 0.10668)
		(layer "F.Cu")
		(net "ETH40G_B1_TX0P")
	)
	(segment
		(start -309.62455 46.28134)
		(end -308.51348 46.28134)
		(width 0.10668)
		(layer "F.Cu")
		(net "ETH40G_B1_TX0P")
	)
	(segment
		(start -306.54752 44.31538)
		(end -306.54752 42.914159)
		(width 0.10668)
		(layer "F.Cu")
		(net "ETH40G_B1_TX0P")
	)
	(segment
		(start -310.418752 44.896644)
		(end -310.298417 45.016979)
		(width 0.10668)
		(layer "F.Cu")
		(net "ETH40G_B1_TX0P")
	)
	(via
		(at -306.37988 42.50944)
		(size 0.5588)
		(drill 0.254)
		(layers "F.Cu" "B.Cu")
		(net "ETH40G_B1_TX0P")
	)
	(arc
		(start -308.51348 46.28134)
		(mid -307.123336 45.705524)
		(end -306.54752 44.31538)
		(width 0.10668)
		(layer "F.Cu")
		(net "ETH40G_B1_TX0P")
	)
	(arc
		(start -306.54752 42.914159)
		(mid -306.503952 42.695127)
		(end -306.37988 42.50944)
		(width 0.10668)
		(layer "F.Cu")
		(net "ETH40G_B1_TX0P")
	)
	(arc
		(start -310.26717 45.63872)
		(mid -310.078951 46.093121)
		(end -309.62455 46.28134)
		(width 0.10668)
		(layer "F.Cu")
		(net "ETH40G_B1_TX0P")
	)
	(arc
		(start -310.449999 44.821208)
		(mid -310.441878 44.862034)
		(end -310.418752 44.896644)
		(width 0.10668)
		(layer "F.Cu")
		(net "ETH40G_B1_TX0P")
	)
	(arc
		(start -310.298417 45.016979)
		(mid -310.275291 45.051589)
		(end -310.26717 45.092414)
		(width 0.10668)
		(layer "F.Cu")
		(net "ETH40G_B1_TX0P")
	)
	(segment
		(start -304.9216 39.22268)
		(end -304.9216 35.6108)
		(width 0.11176)
		(layer "In5.Cu")
		(net "ETH40G_B1_TX0P")
	)
	(segment
		(start -306.232522 40.967419)
		(end -305.228351 39.963247)
		(width 0.11176)
		(layer "In5.Cu")
		(net "ETH40G_B1_TX0P")
	)
	(segment
		(start -306.60086 41.975946)
		(end -306.60086 41.85666)
		(width 0.11176)
		(layer "In5.Cu")
		(net "ETH40G_B1_TX0P")
	)
	(segment
		(start -304.040002 35.577998)
		(end -304.040002 35.66)
		(width 0.11176)
		(layer "In5.Cu")
		(net "ETH40G_B1_TX0P")
	)
	(arc
		(start -306.60086 41.85666)
		(mid -306.505132 41.375406)
		(end -306.232522 40.967419)
		(width 0.11176)
		(layer "In5.Cu")
		(net "ETH40G_B1_TX0P")
	)
	(arc
		(start -304.4644 35.1536)
		(mid -304.164305 35.277903)
		(end -304.040002 35.577998)
		(width 0.11176)
		(layer "In5.Cu")
		(net "ETH40G_B1_TX0P")
	)
	(arc
		(start -306.37988 42.50944)
		(mid -306.54343 42.264671)
		(end -306.60086 41.975946)
		(width 0.11176)
		(layer "In5.Cu")
		(net "ETH40G_B1_TX0P")
	)
	(arc
		(start -304.9216 35.6108)
		(mid -304.787689 35.287511)
		(end -304.4644 35.1536)
		(width 0.11176)
		(layer "In5.Cu")
		(net "ETH40G_B1_TX0P")
	)
	(arc
		(start -305.228351 39.963247)
		(mid -305.001322 39.623472)
		(end -304.9216 39.22268)
		(width 0.11176)
		(layer "In5.Cu")
		(net "ETH40G_B1_TX0P")
	)
	(segment
		(start -309.62455 45.847)
		(end -309.41627 45.847)
		(width 0.10668)
		(layer "F.Cu")
		(net "ETH40G_B1_TX0N")
	)
	(segment
		(start -309.681248 44.896644)
		(end -309.801583 45.016979)
		(width 0.10668)
		(layer "F.Cu")
		(net "ETH40G_B1_TX0N")
	)
	(segment
		(start -308.93367 45.67428)
		(end -308.76095 45.847)
		(width 0.10668)
		(layer "F.Cu")
		(net "ETH40G_B1_TX0N")
	)
	(segment
		(start -307.27396 43.90644)
		(end -307.27396 43.518785)
		(width 0.10668)
		(layer "F.Cu")
		(net "ETH40G_B1_TX0N")
	)
	(segment
		(start -309.24355 45.67428)
		(end -308.93367 45.67428)
		(width 0.10668)
		(layer "F.Cu")
		(net "ETH40G_B1_TX0N")
	)
	(segment
		(start -308.76095 45.847)
		(end -308.51348 45.847)
		(width 0.10668)
		(layer "F.Cu")
		(net "ETH40G_B1_TX0N")
	)
	(segment
		(start -309.65 43.840001)
		(end -309.65 44.821208)
		(width 0.10668)
		(layer "F.Cu")
		(net "ETH40G_B1_TX0N")
	)
	(segment
		(start -306.98186 44.31538)
		(end -306.98186 44.19854)
		(width 0.10668)
		(layer "F.Cu")
		(net "ETH40G_B1_TX0N")
	)
	(segment
		(start -309.41627 45.847)
		(end -309.24355 45.67428)
		(width 0.10668)
		(layer "F.Cu")
		(net "ETH40G_B1_TX0N")
	)
	(segment
		(start -306.98186 43.226685)
		(end -306.98186 43.018405)
		(width 0.10668)
		(layer "F.Cu")
		(net "ETH40G_B1_TX0N")
	)
	(segment
		(start -309.83283 45.092414)
		(end -309.83283 45.63872)
		(width 0.10668)
		(layer "F.Cu")
		(net "ETH40G_B1_TX0N")
	)
	(segment
		(start -306.98186 44.19854)
		(end -307.27396 43.90644)
		(width 0.10668)
		(layer "F.Cu")
		(net "ETH40G_B1_TX0N")
	)
	(segment
		(start -307.27396 43.518785)
		(end -306.98186 43.226685)
		(width 0.10668)
		(layer "F.Cu")
		(net "ETH40G_B1_TX0N")
	)
	(via
		(at -307.19268 42.50944)
		(size 0.5588)
		(drill 0.254)
		(layers "F.Cu" "B.Cu")
		(net "ETH40G_B1_TX0N")
	)
	(arc
		(start -309.801583 45.016979)
		(mid -309.824709 45.051589)
		(end -309.83283 45.092414)
		(width 0.10668)
		(layer "F.Cu")
		(net "ETH40G_B1_TX0N")
	)
	(arc
		(start -309.65 44.821208)
		(mid -309.658121 44.862034)
		(end -309.681248 44.896644)
		(width 0.10668)
		(layer "F.Cu")
		(net "ETH40G_B1_TX0N")
	)
	(arc
		(start -306.98186 43.018405)
		(mid -307.03665 42.742955)
		(end -307.19268 42.50944)
		(width 0.10668)
		(layer "F.Cu")
		(net "ETH40G_B1_TX0N")
	)
	(arc
		(start -309.83283 45.63872)
		(mid -309.771826 45.785996)
		(end -309.62455 45.847)
		(width 0.10668)
		(layer "F.Cu")
		(net "ETH40G_B1_TX0N")
	)
	(arc
		(start -308.51348 45.847)
		(mid -307.430461 45.398399)
		(end -306.98186 44.31538)
		(width 0.10668)
		(layer "F.Cu")
		(net "ETH40G_B1_TX0N")
	)
	(segment
		(start -305.49564 38.77818)
		(end -305.49564 38.3667)
		(width 0.11176)
		(layer "In5.Cu")
		(net "ETH40G_B1_TX0N")
	)
	(segment
		(start -305.2645 39.00932)
		(end -305.49564 38.77818)
		(width 0.11176)
		(layer "In5.Cu")
		(net "ETH40G_B1_TX0N")
	)
	(segment
		(start -304.040002 34.386302)
		(end -304.040002 34.26)
		(width 0.11176)
		(layer "In5.Cu")
		(net "ETH40G_B1_TX0N")
	)
	(segment
		(start -305.2645 36.926931)
		(end -305.2645 35.6108)
		(width 0.11176)
		(layer "In5.Cu")
		(net "ETH40G_B1_TX0N")
	)
	(segment
		(start -306.94376 41.908494)
		(end -306.94376 41.85666)
		(width 0.11176)
		(layer "In5.Cu")
		(net "ETH40G_B1_TX0N")
	)
	(segment
		(start -306.47499 40.72495)
		(end -305.470819 39.720779)
		(width 0.11176)
		(layer "In5.Cu")
		(net "ETH40G_B1_TX0N")
	)
	(segment
		(start -305.2645 38.13556)
		(end -305.2645 37.729571)
		(width 0.11176)
		(layer "In5.Cu")
		(net "ETH40G_B1_TX0N")
	)
	(segment
		(start -305.49564 38.3667)
		(end -305.2645 38.13556)
		(width 0.11176)
		(layer "In5.Cu")
		(net "ETH40G_B1_TX0N")
	)
	(segment
		(start -305.2645 39.22268)
		(end -305.2645 39.00932)
		(width 0.11176)
		(layer "In5.Cu")
		(net "ETH40G_B1_TX0N")
	)
	(segment
		(start -305.2645 37.729571)
		(end -305.49088 37.503191)
		(width 0.11176)
		(layer "In5.Cu")
		(net "ETH40G_B1_TX0N")
	)
	(segment
		(start -305.49088 37.153312)
		(end -305.2645 36.926931)
		(width 0.11176)
		(layer "In5.Cu")
		(net "ETH40G_B1_TX0N")
	)
	(segment
		(start -305.49088 37.503191)
		(end -305.49088 37.153312)
		(width 0.11176)
		(layer "In5.Cu")
		(net "ETH40G_B1_TX0N")
	)
	(arc
		(start -305.2645 35.6108)
		(mid -305.030156 35.045044)
		(end -304.4644 34.8107)
		(width 0.11176)
		(layer "In5.Cu")
		(net "ETH40G_B1_TX0N")
	)
	(arc
		(start -307.19268 42.50944)
		(mid -307.008452 42.233724)
		(end -306.94376 41.908494)
		(width 0.11176)
		(layer "In5.Cu")
		(net "ETH40G_B1_TX0N")
	)
	(arc
		(start -306.94376 41.85666)
		(mid -306.821931 41.244183)
		(end -306.47499 40.72495)
		(width 0.11176)
		(layer "In5.Cu")
		(net "ETH40G_B1_TX0N")
	)
	(arc
		(start -304.4644 34.8107)
		(mid -304.164305 34.686397)
		(end -304.040002 34.386302)
		(width 0.11176)
		(layer "In5.Cu")
		(net "ETH40G_B1_TX0N")
	)
	(arc
		(start -305.470819 39.720779)
		(mid -305.31812 39.492249)
		(end -305.2645 39.22268)
		(width 0.11176)
		(layer "In5.Cu")
		(net "ETH40G_B1_TX0N")
	)
	(segment
		(start -318.15278 39.254519)
		(end -318.15278 36.75126)
		(width 0.1016)
		(layer "F.Cu")
		(net "ETH40G_B1_SDA")
	)
	(segment
		(start -318.049999 39.3573)
		(end -318.15278 39.254519)
		(width 0.1016)
		(layer "F.Cu")
		(net "ETH40G_B1_SDA")
	)
	(segment
		(start -317.66764 36.26612)
		(end -317.66764 35.68192)
		(width 0.1016)
		(layer "F.Cu")
		(net "ETH40G_B1_SDA")
	)
	(segment
		(start -330.819999 16.0528)
		(end -329.7936 16.0528)
		(width 0.1016)
		(layer "F.Cu")
		(net "ETH40G_B1_SDA")
	)
	(segment
		(start -318.049999 41.340001)
		(end -318.049999 39.3573)
		(width 0.1016)
		(layer "F.Cu")
		(net "ETH40G_B1_SDA")
	)
	(segment
		(start -318.15278 36.75126)
		(end -317.66764 36.26612)
		(width 0.1016)
		(layer "F.Cu")
		(net "ETH40G_B1_SDA")
	)
	(via
		(at -329.7936 16.0528)
		(size 0.5588)
		(drill 0.254)
		(layers "F.Cu" "B.Cu")
		(net "ETH40G_B1_SDA")
	)
	(via
		(at -317.66764 35.68192)
		(size 0.5588)
		(drill 0.254)
		(layers "F.Cu" "B.Cu")
		(net "ETH40G_B1_SDA")
	)
	(segment
		(start -317.881 37.06368)
		(end -317.881 35.89528)
		(width 0.12954)
		(layer "In2.Cu")
		(net "ETH40G_B1_SDA")
	)
	(segment
		(start -316.20714 36.89096)
		(end -316.82436 37.50818)
		(width 0.12954)
		(layer "In2.Cu")
		(net "ETH40G_B1_SDA")
	)
	(segment
		(start -317.66764 30.96768)
		(end -324.2056 24.42972)
		(width 0.12954)
		(layer "In2.Cu")
		(net "ETH40G_B1_SDA")
	)
	(segment
		(start -300.040002 39.860002)
		(end -300.8757 40.6957)
		(width 0.12954)
		(layer "In2.Cu")
		(net "ETH40G_B1_SDA")
	)
	(segment
		(start -306.35448 44.54652)
		(end -305.17592 43.36796)
		(width 0.12954)
		(layer "In2.Cu")
		(net "ETH40G_B1_SDA")
	)
	(segment
		(start -317.881 35.89528)
		(end -317.66764 35.68192)
		(width 0.12954)
		(layer "In2.Cu")
		(net "ETH40G_B1_SDA")
	)
	(segment
		(start -317.4365 37.50818)
		(end -317.881 37.06368)
		(width 0.12954)
		(layer "In2.Cu")
		(net "ETH40G_B1_SDA")
	)
	(segment
		(start -306.35448 45.3771)
		(end -306.35448 44.54652)
		(width 0.12954)
		(layer "In2.Cu")
		(net "ETH40G_B1_SDA")
	)
	(segment
		(start -305.17592 43.36796)
		(end -305.17592 38.9128)
		(width 0.12954)
		(layer "In2.Cu")
		(net "ETH40G_B1_SDA")
	)
	(segment
		(start -308.43474 37.79266)
		(end -309.33644 36.89096)
		(width 0.12954)
		(layer "In2.Cu")
		(net "ETH40G_B1_SDA")
	)
	(segment
		(start -301.22622 46.79442)
		(end -304.93716 46.79442)
		(width 0.12954)
		(layer "In2.Cu")
		(net "ETH40G_B1_SDA")
	)
	(segment
		(start -317.66764 35.68192)
		(end -317.66764 30.96768)
		(width 0.12954)
		(layer "In2.Cu")
		(net "ETH40G_B1_SDA")
	)
	(segment
		(start -300.8757 46.4439)
		(end -301.22622 46.79442)
		(width 0.12954)
		(layer "In2.Cu")
		(net "ETH40G_B1_SDA")
	)
	(segment
		(start -306.29606 37.79266)
		(end -308.43474 37.79266)
		(width 0.12954)
		(layer "In2.Cu")
		(net "ETH40G_B1_SDA")
	)
	(segment
		(start -324.2056 21.6408)
		(end -329.7936 16.0528)
		(width 0.12954)
		(layer "In2.Cu")
		(net "ETH40G_B1_SDA")
	)
	(segment
		(start -300.8757 40.6957)
		(end -300.8757 46.4439)
		(width 0.12954)
		(layer "In2.Cu")
		(net "ETH40G_B1_SDA")
	)
	(segment
		(start -324.2056 24.42972)
		(end -324.2056 21.6408)
		(width 0.12954)
		(layer "In2.Cu")
		(net "ETH40G_B1_SDA")
	)
	(segment
		(start -316.82436 37.50818)
		(end -317.4365 37.50818)
		(width 0.12954)
		(layer "In2.Cu")
		(net "ETH40G_B1_SDA")
	)
	(segment
		(start -305.17592 38.9128)
		(end -306.29606 37.79266)
		(width 0.12954)
		(layer "In2.Cu")
		(net "ETH40G_B1_SDA")
	)
	(segment
		(start -304.93716 46.79442)
		(end -306.35448 45.3771)
		(width 0.12954)
		(layer "In2.Cu")
		(net "ETH40G_B1_SDA")
	)
	(segment
		(start -309.33644 36.89096)
		(end -316.20714 36.89096)
		(width 0.12954)
		(layer "In2.Cu")
		(net "ETH40G_B1_SDA")
	)
	(segment
		(start -317.250001 41.340001)
		(end -317.26378 41.326222)
		(width 0.1016)
		(layer "F.Cu")
		(net "ETH40G_B1_SCL")
	)
	(segment
		(start -317.26378 39.16426)
		(end -317.79718 38.63086)
		(width 0.1016)
		(layer "F.Cu")
		(net "ETH40G_B1_SCL")
	)
	(segment
		(start -317.250001 37.222621)
		(end -317.250001 36.7792)
		(width 0.1016)
		(layer "F.Cu")
		(net "ETH40G_B1_SCL")
	)
	(segment
		(start -330.819999 14.6558)
		(end -329.8698 14.6558)
		(width 0.1016)
		(layer "F.Cu")
		(net "ETH40G_B1_SCL")
	)
	(segment
		(start -329.8698 14.6558)
		(end -329.690776 14.834824)
		(width 0.1016)
		(layer "F.Cu")
		(net "ETH40G_B1_SCL")
	)
	(segment
		(start -317.26378 41.326222)
		(end -317.26378 39.16426)
		(width 0.1016)
		(layer "F.Cu")
		(net "ETH40G_B1_SCL")
	)
	(segment
		(start -317.79718 38.63086)
		(end -317.79718 37.7698)
		(width 0.1016)
		(layer "F.Cu")
		(net "ETH40G_B1_SCL")
	)
	(segment
		(start -317.79718 37.7698)
		(end -317.250001 37.222621)
		(width 0.1016)
		(layer "F.Cu")
		(net "ETH40G_B1_SCL")
	)
	(via
		(at -329.690776 14.834824)
		(size 0.5588)
		(drill 0.254)
		(layers "F.Cu" "B.Cu")
		(net "ETH40G_B1_SCL")
	)
	(via
		(at -317.250001 36.7792)
		(size 0.5588)
		(drill 0.254)
		(layers "F.Cu" "B.Cu")
		(net "ETH40G_B1_SCL")
	)
	(segment
		(start -301.53864 46.49724)
		(end -304.69332 46.49724)
		(width 0.12954)
		(layer "In2.Cu")
		(net "ETH40G_B1_SCL")
	)
	(segment
		(start -306.10048 37.465)
		(end -308.28488 37.465)
		(width 0.12954)
		(layer "In2.Cu")
		(net "ETH40G_B1_SCL")
	)
	(segment
		(start -306.070076 45.120484)
		(end -306.070076 44.681216)
		(width 0.12954)
		(layer "In2.Cu")
		(net "ETH40G_B1_SCL")
	)
	(segment
		(start -306.070076 44.681216)
		(end -304.85588 43.46702)
		(width 0.12954)
		(layer "In2.Cu")
		(net "ETH40G_B1_SCL")
	)
	(segment
		(start -301.2186 46.1772)
		(end -301.53864 46.49724)
		(width 0.12954)
		(layer "In2.Cu")
		(net "ETH40G_B1_SCL")
	)
	(segment
		(start -316.89548 36.42468)
		(end -316.89548 30.60954)
		(width 0.12954)
		(layer "In2.Cu")
		(net "ETH40G_B1_SCL")
	)
	(segment
		(start -316.89548 30.60954)
		(end -323.7992 23.70582)
		(width 0.12954)
		(layer "In2.Cu")
		(net "ETH40G_B1_SCL")
	)
	(segment
		(start -309.31612 36.43376)
		(end -316.3443 36.43376)
		(width 0.12954)
		(layer "In2.Cu")
		(net "ETH40G_B1_SCL")
	)
	(segment
		(start -323.7992 20.7264)
		(end -329.690776 14.834824)
		(width 0.12954)
		(layer "In2.Cu")
		(net "ETH40G_B1_SCL")
	)
	(segment
		(start -304.85588 43.46702)
		(end -304.85588 38.7096)
		(width 0.12954)
		(layer "In2.Cu")
		(net "ETH40G_B1_SCL")
	)
	(segment
		(start -316.3443 36.43376)
		(end -316.68974 36.7792)
		(width 0.12954)
		(layer "In2.Cu")
		(net "ETH40G_B1_SCL")
	)
	(segment
		(start -304.85588 38.7096)
		(end -306.10048 37.465)
		(width 0.12954)
		(layer "In2.Cu")
		(net "ETH40G_B1_SCL")
	)
	(segment
		(start -300.040002 38.460002)
		(end -301.2186 39.6386)
		(width 0.12954)
		(layer "In2.Cu")
		(net "ETH40G_B1_SCL")
	)
	(segment
		(start -304.69332 46.49724)
		(end -306.070076 45.120484)
		(width 0.12954)
		(layer "In2.Cu")
		(net "ETH40G_B1_SCL")
	)
	(segment
		(start -317.250001 36.7792)
		(end -316.89548 36.42468)
		(width 0.12954)
		(layer "In2.Cu")
		(net "ETH40G_B1_SCL")
	)
	(segment
		(start -316.68974 36.7792)
		(end -317.250001 36.7792)
		(width 0.12954)
		(layer "In2.Cu")
		(net "ETH40G_B1_SCL")
	)
	(segment
		(start -308.28488 37.465)
		(end -309.31612 36.43376)
		(width 0.12954)
		(layer "In2.Cu")
		(net "ETH40G_B1_SCL")
	)
	(segment
		(start -301.2186 39.6386)
		(end -301.2186 46.1772)
		(width 0.12954)
		(layer "In2.Cu")
		(net "ETH40G_B1_SCL")
	)
	(segment
		(start -323.7992 23.70582)
		(end -323.7992 20.7264)
		(width 0.12954)
		(layer "In2.Cu")
		(net "ETH40G_B1_SCL")
	)
	(segment
		(start -319.249999 43.840001)
		(end -319.249999 44.865399)
		(width 0.10668)
		(layer "F.Cu")
		(net "ETH40G_B1_RX3P")
	)
	(segment
		(start -319.087388 48.04918)
		(end -318.44374 48.04918)
		(width 0.10668)
		(layer "F.Cu")
		(net "ETH40G_B1_RX3P")
	)
	(segment
		(start -319.432828 46.113588)
		(end -319.432828 47.70374)
		(width 0.10668)
		(layer "F.Cu")
		(net "ETH40G_B1_RX3P")
	)
	(segment
		(start -317.40348 47.6123)
		(end -316.867182 47.6123)
		(width 0.10668)
		(layer "F.Cu")
		(net "ETH40G_B1_RX3P")
	)
	(segment
		(start -319.2399 45.449437)
		(end -319.2399 45.92066)
		(width 0.10668)
		(layer "F.Cu")
		(net "ETH40G_B1_RX3P")
	)
	(segment
		(start -319.432828 45.256508)
		(end -319.2399 45.449437)
		(width 0.10668)
		(layer "F.Cu")
		(net "ETH40G_B1_RX3P")
	)
	(segment
		(start -319.2399 45.92066)
		(end -319.432828 46.113588)
		(width 0.10668)
		(layer "F.Cu")
		(net "ETH40G_B1_RX3P")
	)
	(segment
		(start -319.432828 45.048228)
		(end -319.432828 45.256508)
		(width 0.10668)
		(layer "F.Cu")
		(net "ETH40G_B1_RX3P")
	)
	(segment
		(start -317.94704 47.84344)
		(end -317.936814 47.833214)
		(width 0.10668)
		(layer "F.Cu")
		(net "ETH40G_B1_RX3P")
	)
	(segment
		(start -319.249999 44.865399)
		(end -319.432828 45.048228)
		(width 0.10668)
		(layer "F.Cu")
		(net "ETH40G_B1_RX3P")
	)
	(via
		(at -316.41034 47.42307)
		(size 0.5588)
		(drill 0.254)
		(layers "F.Cu" "B.Cu")
		(net "ETH40G_B1_RX3P")
	)
	(arc
		(start -318.44374 48.04918)
		(mid -318.174928 47.99571)
		(end -317.94704 47.84344)
		(width 0.10668)
		(layer "F.Cu")
		(net "ETH40G_B1_RX3P")
	)
	(arc
		(start -316.867182 47.6123)
		(mid -316.619941 47.563121)
		(end -316.41034 47.42307)
		(width 0.10668)
		(layer "F.Cu")
		(net "ETH40G_B1_RX3P")
	)
	(arc
		(start -319.432828 47.70374)
		(mid -319.331651 47.948003)
		(end -319.087388 48.04918)
		(width 0.10668)
		(layer "F.Cu")
		(net "ETH40G_B1_RX3P")
	)
	(arc
		(start -317.936814 47.833214)
		(mid -317.692118 47.669714)
		(end -317.40348 47.6123)
		(width 0.10668)
		(layer "F.Cu")
		(net "ETH40G_B1_RX3P")
	)
	(segment
		(start -298.942095 46.3677)
		(end -297.413058 46.3677)
		(width 0.11176)
		(layer "In5.Cu")
		(net "ETH40G_B1_RX3P")
	)
	(segment
		(start -300.232415 46.3677)
		(end -299.815855 46.3677)
		(width 0.11176)
		(layer "In5.Cu")
		(net "ETH40G_B1_RX3P")
	)
	(segment
		(start -316.41034 47.42307)
		(end -316.369337 47.464073)
		(width 0.11176)
		(layer "In5.Cu")
		(net "ETH40G_B1_RX3P")
	)
	(segment
		(start -306.676524 46.3677)
		(end -306.434894 46.3677)
		(width 0.11176)
		(layer "In5.Cu")
		(net "ETH40G_B1_RX3P")
	)
	(segment
		(start -304.938834 46.13656)
		(end -304.552754 46.13656)
		(width 0.11176)
		(layer "In5.Cu")
		(net "ETH40G_B1_RX3P")
	)
	(segment
		(start -303.905054 46.3677)
		(end -303.673914 46.13656)
		(width 0.11176)
		(layer "In5.Cu")
		(net "ETH40G_B1_RX3P")
	)
	(segment
		(start -313.307415 48.1711)
		(end -312.056209 48.1711)
		(width 0.11176)
		(layer "In5.Cu")
		(net "ETH40G_B1_RX3P")
	)
	(segment
		(start -297.184458 46.1391)
		(end -296.762818 46.1391)
		(width 0.11176)
		(layer "In5.Cu")
		(net "ETH40G_B1_RX3P")
	)
	(segment
		(start -307.977309 47.220909)
		(end -307.440589 46.684187)
		(width 0.11176)
		(layer "In5.Cu")
		(net "ETH40G_B1_RX3P")
	)
	(segment
		(start -306.203754 46.13656)
		(end -305.817674 46.13656)
		(width 0.11176)
		(layer "In5.Cu")
		(net "ETH40G_B1_RX3P")
	)
	(segment
		(start -296.040002 44.059302)
		(end -296.040002 44.060001)
		(width 0.11176)
		(layer "In5.Cu")
		(net "ETH40G_B1_RX3P")
	)
	(segment
		(start -311.827609 47.9425)
		(end -311.411049 47.9425)
		(width 0.11176)
		(layer "In5.Cu")
		(net "ETH40G_B1_RX3P")
	)
	(segment
		(start -313.480135 47.99838)
		(end -313.307415 48.1711)
		(width 0.11176)
		(layer "In5.Cu")
		(net "ETH40G_B1_RX3P")
	)
	(segment
		(start -303.056694 46.3677)
		(end -301.106175 46.3677)
		(width 0.11176)
		(layer "In5.Cu")
		(net "ETH40G_B1_RX3P")
	)
	(segment
		(start -308.66842 47.91202)
		(end -307.977309 47.220909)
		(width 0.11176)
		(layer "In5.Cu")
		(net "ETH40G_B1_RX3P")
	)
	(segment
		(start -310.120729 47.9425)
		(end -309.892129 48.1711)
		(width 0.11176)
		(layer "In5.Cu")
		(net "ETH40G_B1_RX3P")
	)
	(segment
		(start -303.673914 46.13656)
		(end -303.287834 46.13656)
		(width 0.11176)
		(layer "In5.Cu")
		(net "ETH40G_B1_RX3P")
	)
	(segment
		(start -296.534218 46.3677)
		(end -295.4728 46.3677)
		(width 0.11176)
		(layer "In5.Cu")
		(net "ETH40G_B1_RX3P")
	)
	(segment
		(start -310.537289 47.9425)
		(end -310.120729 47.9425)
		(width 0.11176)
		(layer "In5.Cu")
		(net "ETH40G_B1_RX3P")
	)
	(segment
		(start -299.170695 46.1391)
		(end -298.942095 46.3677)
		(width 0.11176)
		(layer "In5.Cu")
		(net "ETH40G_B1_RX3P")
	)
	(segment
		(start -299.587255 46.1391)
		(end -299.170695 46.1391)
		(width 0.11176)
		(layer "In5.Cu")
		(net "ETH40G_B1_RX3P")
	)
	(segment
		(start -304.321614 46.3677)
		(end -303.905054 46.3677)
		(width 0.11176)
		(layer "In5.Cu")
		(net "ETH40G_B1_RX3P")
	)
	(segment
		(start -297.413058 46.3677)
		(end -297.184458 46.1391)
		(width 0.11176)
		(layer "In5.Cu")
		(net "ETH40G_B1_RX3P")
	)
	(segment
		(start -313.952575 48.1711)
		(end -313.779855 47.99838)
		(width 0.11176)
		(layer "In5.Cu")
		(net "ETH40G_B1_RX3P")
	)
	(segment
		(start -315.9379 47.64278)
		(end -315.842119 47.64278)
		(width 0.11176)
		(layer "In5.Cu")
		(net "ETH40G_B1_RX3P")
	)
	(segment
		(start -301.106175 46.3677)
		(end -300.877575 46.1391)
		(width 0.11176)
		(layer "In5.Cu")
		(net "ETH40G_B1_RX3P")
	)
	(segment
		(start -305.169974 46.3677)
		(end -304.938834 46.13656)
		(width 0.11176)
		(layer "In5.Cu")
		(net "ETH40G_B1_RX3P")
	)
	(segment
		(start -300.877575 46.1391)
		(end -300.461015 46.1391)
		(width 0.11176)
		(layer "In5.Cu")
		(net "ETH40G_B1_RX3P")
	)
	(segment
		(start -305.586534 46.3677)
		(end -305.169974 46.3677)
		(width 0.11176)
		(layer "In5.Cu")
		(net "ETH40G_B1_RX3P")
	)
	(segment
		(start -311.182449 48.1711)
		(end -310.765889 48.1711)
		(width 0.11176)
		(layer "In5.Cu")
		(net "ETH40G_B1_RX3P")
	)
	(segment
		(start -312.056209 48.1711)
		(end -311.827609 47.9425)
		(width 0.11176)
		(layer "In5.Cu")
		(net "ETH40G_B1_RX3P")
	)
	(segment
		(start -304.552754 46.13656)
		(end -304.321614 46.3677)
		(width 0.11176)
		(layer "In5.Cu")
		(net "ETH40G_B1_RX3P")
	)
	(segment
		(start -296.762818 46.1391)
		(end -296.534218 46.3677)
		(width 0.11176)
		(layer "In5.Cu")
		(net "ETH40G_B1_RX3P")
	)
	(segment
		(start -303.287834 46.13656)
		(end -303.056694 46.3677)
		(width 0.11176)
		(layer "In5.Cu")
		(net "ETH40G_B1_RX3P")
	)
	(segment
		(start -311.411049 47.9425)
		(end -311.182449 48.1711)
		(width 0.11176)
		(layer "In5.Cu")
		(net "ETH40G_B1_RX3P")
	)
	(segment
		(start -309.892129 48.1711)
		(end -309.293895 48.1711)
		(width 0.11176)
		(layer "In5.Cu")
		(net "ETH40G_B1_RX3P")
	)
	(segment
		(start -299.815855 46.3677)
		(end -299.587255 46.1391)
		(width 0.11176)
		(layer "In5.Cu")
		(net "ETH40G_B1_RX3P")
	)
	(segment
		(start -314.566643 48.1711)
		(end -313.952575 48.1711)
		(width 0.11176)
		(layer "In5.Cu")
		(net "ETH40G_B1_RX3P")
	)
	(segment
		(start -300.461015 46.1391)
		(end -300.232415 46.3677)
		(width 0.11176)
		(layer "In5.Cu")
		(net "ETH40G_B1_RX3P")
	)
	(segment
		(start -305.817674 46.13656)
		(end -305.586534 46.3677)
		(width 0.11176)
		(layer "In5.Cu")
		(net "ETH40G_B1_RX3P")
	)
	(segment
		(start -313.779855 47.99838)
		(end -313.480135 47.99838)
		(width 0.11176)
		(layer "In5.Cu")
		(net "ETH40G_B1_RX3P")
	)
	(segment
		(start -295.2188 46.1137)
		(end -295.2188 43.8585)
		(width 0.11176)
		(layer "In5.Cu")
		(net "ETH40G_B1_RX3P")
	)
	(segment
		(start -306.434894 46.3677)
		(end -306.203754 46.13656)
		(width 0.11176)
		(layer "In5.Cu")
		(net "ETH40G_B1_RX3P")
	)
	(segment
		(start -310.765889 48.1711)
		(end -310.537289 47.9425)
		(width 0.11176)
		(layer "In5.Cu")
		(net "ETH40G_B1_RX3P")
	)
	(arc
		(start -315.1124 47.94504)
		(mid -314.862005 48.112349)
		(end -314.566643 48.1711)
		(width 0.11176)
		(layer "In5.Cu")
		(net "ETH40G_B1_RX3P")
	)
	(arc
		(start -295.529 43.5483)
		(mid -295.890333 43.697969)
		(end -296.040002 44.059302)
		(width 0.11176)
		(layer "In5.Cu")
		(net "ETH40G_B1_RX3P")
	)
	(arc
		(start -315.842119 47.64278)
		(mid -315.447198 47.721335)
		(end -315.1124 47.94504)
		(width 0.11176)
		(layer "In5.Cu")
		(net "ETH40G_B1_RX3P")
	)
	(arc
		(start -307.440589 46.684187)
		(mid -307.090033 46.449953)
		(end -306.676524 46.3677)
		(width 0.11176)
		(layer "In5.Cu")
		(net "ETH40G_B1_RX3P")
	)
	(arc
		(start -295.2188 43.8585)
		(mid -295.309655 43.639155)
		(end -295.529 43.5483)
		(width 0.11176)
		(layer "In5.Cu")
		(net "ETH40G_B1_RX3P")
	)
	(arc
		(start -316.369337 47.464073)
		(mid -316.171392 47.596336)
		(end -315.9379 47.64278)
		(width 0.11176)
		(layer "In5.Cu")
		(net "ETH40G_B1_RX3P")
	)
	(arc
		(start -309.293895 48.1711)
		(mid -308.95539 48.103767)
		(end -308.66842 47.91202)
		(width 0.11176)
		(layer "In5.Cu")
		(net "ETH40G_B1_RX3P")
	)
	(arc
		(start -295.4728 46.3677)
		(mid -295.293195 46.293305)
		(end -295.2188 46.1137)
		(width 0.11176)
		(layer "In5.Cu")
		(net "ETH40G_B1_RX3P")
	)
	(segment
		(start -317.40348 48.04664)
		(end -316.867182 48.04664)
		(width 0.10668)
		(layer "F.Cu")
		(net "ETH40G_B1_RX3N")
	)
	(segment
		(start -319.867168 45.048228)
		(end -319.867168 47.70374)
		(width 0.10668)
		(layer "F.Cu")
		(net "ETH40G_B1_RX3N")
	)
	(segment
		(start -317.639913 48.150567)
		(end -317.629687 48.140341)
		(width 0.10668)
		(layer "F.Cu")
		(net "ETH40G_B1_RX3N")
	)
	(segment
		(start -319.087388 48.48352)
		(end -318.443737 48.48352)
		(width 0.10668)
		(layer "F.Cu")
		(net "ETH40G_B1_RX3N")
	)
	(segment
		(start -320.05 44.865397)
		(end -319.867168 45.048228)
		(width 0.10668)
		(layer "F.Cu")
		(net "ETH40G_B1_RX3N")
	)
	(segment
		(start -320.05 43.840001)
		(end -320.05 44.865397)
		(width 0.10668)
		(layer "F.Cu")
		(net "ETH40G_B1_RX3N")
	)
	(via
		(at -316.41034 48.23587)
		(size 0.5588)
		(drill 0.254)
		(layers "F.Cu" "B.Cu")
		(net "ETH40G_B1_RX3N")
	)
	(arc
		(start -317.629687 48.140341)
		(mid -317.525903 48.070993)
		(end -317.40348 48.04664)
		(width 0.10668)
		(layer "F.Cu")
		(net "ETH40G_B1_RX3N")
	)
	(arc
		(start -318.443737 48.48352)
		(mid -318.008711 48.396988)
		(end -317.639913 48.150567)
		(width 0.10668)
		(layer "F.Cu")
		(net "ETH40G_B1_RX3N")
	)
	(arc
		(start -316.867182 48.04664)
		(mid -316.619941 48.095819)
		(end -316.41034 48.23587)
		(width 0.10668)
		(layer "F.Cu")
		(net "ETH40G_B1_RX3N")
	)
	(arc
		(start -319.867168 47.70374)
		(mid -319.638776 48.255128)
		(end -319.087388 48.48352)
		(width 0.10668)
		(layer "F.Cu")
		(net "ETH40G_B1_RX3N")
	)
	(segment
		(start -316.049025 47.98568)
		(end -315.842122 47.98568)
		(width 0.11176)
		(layer "In5.Cu")
		(net "ETH40G_B1_RX3N")
	)
	(segment
		(start -316.41034 48.23587)
		(end -316.238727 48.064257)
		(width 0.11176)
		(layer "In5.Cu")
		(net "ETH40G_B1_RX3N")
	)
	(segment
		(start -314.566645 48.514)
		(end -309.293898 48.514)
		(width 0.11176)
		(layer "In5.Cu")
		(net "ETH40G_B1_RX3N")
	)
	(segment
		(start -308.425952 48.154488)
		(end -307.198121 46.926655)
		(width 0.11176)
		(layer "In5.Cu")
		(net "ETH40G_B1_RX3N")
	)
	(segment
		(start -306.676522 46.7106)
		(end -295.4728 46.7106)
		(width 0.11176)
		(layer "In5.Cu")
		(net "ETH40G_B1_RX3N")
	)
	(segment
		(start -294.8759 46.1137)
		(end -294.8759 43.8585)
		(width 0.11176)
		(layer "In5.Cu")
		(net "ETH40G_B1_RX3N")
	)
	(segment
		(start -296.040002 42.694398)
		(end -296.040002 42.660001)
		(width 0.11176)
		(layer "In5.Cu")
		(net "ETH40G_B1_RX3N")
	)
	(arc
		(start -315.354868 48.187508)
		(mid -314.993228 48.429148)
		(end -314.566645 48.514)
		(width 0.11176)
		(layer "In5.Cu")
		(net "ETH40G_B1_RX3N")
	)
	(arc
		(start -316.238727 48.064257)
		(mid -316.151691 48.006102)
		(end -316.049025 47.98568)
		(width 0.11176)
		(layer "In5.Cu")
		(net "ETH40G_B1_RX3N")
	)
	(arc
		(start -315.842122 47.98568)
		(mid -315.578422 48.038133)
		(end -315.354868 48.187508)
		(width 0.11176)
		(layer "In5.Cu")
		(net "ETH40G_B1_RX3N")
	)
	(arc
		(start -295.529 43.2054)
		(mid -295.890333 43.055731)
		(end -296.040002 42.694398)
		(width 0.11176)
		(layer "In5.Cu")
		(net "ETH40G_B1_RX3N")
	)
	(arc
		(start -294.8759 43.8585)
		(mid -295.067189 43.396689)
		(end -295.529 43.2054)
		(width 0.11176)
		(layer "In5.Cu")
		(net "ETH40G_B1_RX3N")
	)
	(arc
		(start -295.4728 46.7106)
		(mid -295.050728 46.535772)
		(end -294.8759 46.1137)
		(width 0.11176)
		(layer "In5.Cu")
		(net "ETH40G_B1_RX3N")
	)
	(arc
		(start -309.293898 48.514)
		(mid -308.824169 48.420567)
		(end -308.425952 48.154488)
		(width 0.11176)
		(layer "In5.Cu")
		(net "ETH40G_B1_RX3N")
	)
	(arc
		(start -307.198121 46.926655)
		(mid -306.958809 46.766752)
		(end -306.676522 46.7106)
		(width 0.11176)
		(layer "In5.Cu")
		(net "ETH40G_B1_RX3N")
	)
	(segment
		(start -319.83283 40.087588)
		(end -319.83283 37.151991)
		(width 0.10668)
		(layer "F.Cu")
		(net "ETH40G_B1_RX2P")
	)
	(segment
		(start -319.650001 41.340001)
		(end -319.650001 40.358794)
		(width 0.10668)
		(layer "F.Cu")
		(net "ETH40G_B1_RX2P")
	)
	(segment
		(start -319.681248 40.283359)
		(end -319.801583 40.163024)
		(width 0.10668)
		(layer "F.Cu")
		(net "ETH40G_B1_RX2P")
	)
	(via
		(at -319.640054 36.686589)
		(size 0.5588)
		(drill 0.254)
		(layers "F.Cu" "B.Cu")
		(net "ETH40G_B1_RX2P")
	)
	(arc
		(start -319.650001 40.358794)
		(mid -319.658122 40.317969)
		(end -319.681248 40.283359)
		(width 0.10668)
		(layer "F.Cu")
		(net "ETH40G_B1_RX2P")
	)
	(arc
		(start -319.801583 40.163024)
		(mid -319.82471 40.128414)
		(end -319.83283 40.087588)
		(width 0.10668)
		(layer "F.Cu")
		(net "ETH40G_B1_RX2P")
	)
	(arc
		(start -319.83283 37.151991)
		(mid -319.782729 36.900117)
		(end -319.640054 36.686589)
		(width 0.10668)
		(layer "F.Cu")
		(net "ETH40G_B1_RX2P")
	)
	(segment
		(start -318.032689 33.90646)
		(end -318.261289 34.13506)
		(width 0.10668)
		(layer "B.Cu")
		(net "ETH40G_B1_RX2P")
	)
	(segment
		(start -319.686711 36.639929)
		(end -319.640054 36.686589)
		(width 0.10668)
		(layer "B.Cu")
		(net "ETH40G_B1_RX2P")
	)
	(segment
		(start -305.66106 30.76194)
		(end -306.73294 30.76194)
		(width 0.10668)
		(layer "B.Cu")
		(net "ETH40G_B1_RX2P")
	)
	(segment
		(start -306.73294 30.76194)
		(end -306.98694 31.01594)
		(width 0.10668)
		(layer "B.Cu")
		(net "ETH40G_B1_RX2P")
	)
	(segment
		(start -304.94986 31.0388)
		(end -305.3842 31.0388)
		(width 0.10668)
		(layer "B.Cu")
		(net "ETH40G_B1_RX2P")
	)
	(segment
		(start -319.82156 34.53638)
		(end -319.82156 34.74466)
		(width 0.10668)
		(layer "B.Cu")
		(net "ETH40G_B1_RX2P")
	)
	(segment
		(start -318.261289 34.13506)
		(end -318.672769 34.13506)
		(width 0.10668)
		(layer "B.Cu")
		(net "ETH40G_B1_RX2P")
	)
	(segment
		(start -304.673 30.76194)
		(end -304.94986 31.0388)
		(width 0.10668)
		(layer "B.Cu")
		(net "ETH40G_B1_RX2P")
	)
	(segment
		(start -299.23994 44.2722)
		(end -299.23994 32.525386)
		(width 0.10668)
		(layer "B.Cu")
		(net "ETH40G_B1_RX2P")
	)
	(segment
		(start -319.74282 35.33648)
		(end -319.82156 35.41522)
		(width 0.10668)
		(layer "B.Cu")
		(net "ETH40G_B1_RX2P")
	)
	(segment
		(start -307.594 30.76194)
		(end -309.6274 30.76194)
		(width 0.10668)
		(layer "B.Cu")
		(net "ETH40G_B1_RX2P")
	)
	(segment
		(start -298.040001 45.360001)
		(end -298.438908 44.961094)
		(width 0.10668)
		(layer "B.Cu")
		(net "ETH40G_B1_RX2P")
	)
	(segment
		(start -301.290754 30.76194)
		(end -304.673 30.76194)
		(width 0.10668)
		(layer "B.Cu")
		(net "ETH40G_B1_RX2P")
	)
	(segment
		(start -319.82156 35.41522)
		(end -319.82156 36.31438)
		(width 0.10668)
		(layer "B.Cu")
		(net "ETH40G_B1_RX2P")
	)
	(segment
		(start -306.98694 31.01594)
		(end -307.34 31.01594)
		(width 0.10668)
		(layer "B.Cu")
		(net "ETH40G_B1_RX2P")
	)
	(segment
		(start -319.74282 34.8234)
		(end -319.74282 35.33648)
		(width 0.10668)
		(layer "B.Cu")
		(net "ETH40G_B1_RX2P")
	)
	(segment
		(start -317.218941 33.90646)
		(end -318.032689 33.90646)
		(width 0.10668)
		(layer "B.Cu")
		(net "ETH40G_B1_RX2P")
	)
	(segment
		(start -305.3842 31.0388)
		(end -305.66106 30.76194)
		(width 0.10668)
		(layer "B.Cu")
		(net "ETH40G_B1_RX2P")
	)
	(segment
		(start -307.34 31.01594)
		(end -307.594 30.76194)
		(width 0.10668)
		(layer "B.Cu")
		(net "ETH40G_B1_RX2P")
	)
	(segment
		(start -319.82156 34.74466)
		(end -319.74282 34.8234)
		(width 0.10668)
		(layer "B.Cu")
		(net "ETH40G_B1_RX2P")
	)
	(segment
		(start -318.672769 34.13506)
		(end -318.901369 33.90646)
		(width 0.10668)
		(layer "B.Cu")
		(net "ETH40G_B1_RX2P")
	)
	(segment
		(start -318.901369 33.90646)
		(end -319.19164 33.90646)
		(width 0.10668)
		(layer "B.Cu")
		(net "ETH40G_B1_RX2P")
	)
	(arc
		(start -298.438908 44.961094)
		(mid -298.526738 44.902408)
		(end -298.63034 44.8818)
		(width 0.10668)
		(layer "B.Cu")
		(net "ETH40G_B1_RX2P")
	)
	(arc
		(start -299.696924 31.422127)
		(mid -300.428179 30.933516)
		(end -301.290754 30.76194)
		(width 0.10668)
		(layer "B.Cu")
		(net "ETH40G_B1_RX2P")
	)
	(arc
		(start -298.63034 44.8818)
		(mid -299.061392 44.703252)
		(end -299.23994 44.2722)
		(width 0.10668)
		(layer "B.Cu")
		(net "ETH40G_B1_RX2P")
	)
	(arc
		(start -309.6274 30.76194)
		(mid -312.627477 31.358692)
		(end -315.17082 33.0581)
		(width 0.10668)
		(layer "B.Cu")
		(net "ETH40G_B1_RX2P")
	)
	(arc
		(start -315.17082 33.0581)
		(mid -316.110506 33.685978)
		(end -317.218941 33.90646)
		(width 0.10668)
		(layer "B.Cu")
		(net "ETH40G_B1_RX2P")
	)
	(arc
		(start -299.23994 32.525386)
		(mid -299.358706 31.928307)
		(end -299.696924 31.422127)
		(width 0.10668)
		(layer "B.Cu")
		(net "ETH40G_B1_RX2P")
	)
	(arc
		(start -319.19164 33.90646)
		(mid -319.637061 34.090959)
		(end -319.82156 34.53638)
		(width 0.10668)
		(layer "B.Cu")
		(net "ETH40G_B1_RX2P")
	)
	(arc
		(start -319.82156 36.31438)
		(mid -319.786513 36.490566)
		(end -319.686711 36.639929)
		(width 0.10668)
		(layer "B.Cu")
		(net "ETH40G_B1_RX2P")
	)
	(segment
		(start -320.418752 40.283359)
		(end -320.298417 40.163024)
		(width 0.10668)
		(layer "F.Cu")
		(net "ETH40G_B1_RX2N")
	)
	(segment
		(start -320.449999 41.340001)
		(end -320.449999 40.358794)
		(width 0.10668)
		(layer "F.Cu")
		(net "ETH40G_B1_RX2N")
	)
	(segment
		(start -320.26717 40.087588)
		(end -320.26717 37.134871)
		(width 0.10668)
		(layer "F.Cu")
		(net "ETH40G_B1_RX2N")
	)
	(via
		(at -320.452854 36.686589)
		(size 0.5588)
		(drill 0.254)
		(layers "F.Cu" "B.Cu")
		(net "ETH40G_B1_RX2N")
	)
	(arc
		(start -320.449999 40.358794)
		(mid -320.441878 40.317969)
		(end -320.418752 40.283359)
		(width 0.10668)
		(layer "F.Cu")
		(net "ETH40G_B1_RX2N")
	)
	(arc
		(start -320.298417 40.163024)
		(mid -320.27529 40.128414)
		(end -320.26717 40.087588)
		(width 0.10668)
		(layer "F.Cu")
		(net "ETH40G_B1_RX2N")
	)
	(arc
		(start -320.26717 37.134871)
		(mid -320.315428 36.892263)
		(end -320.452854 36.686589)
		(width 0.10668)
		(layer "F.Cu")
		(net "ETH40G_B1_RX2N")
	)
	(segment
		(start -320.2559 34.53638)
		(end -320.2559 36.31438)
		(width 0.10668)
		(layer "B.Cu")
		(net "ETH40G_B1_RX2N")
	)
	(segment
		(start -320.379824 36.613559)
		(end -320.452854 36.686589)
		(width 0.10668)
		(layer "B.Cu")
		(net "ETH40G_B1_RX2N")
	)
	(segment
		(start -301.290751 30.3276)
		(end -309.627402 30.3276)
		(width 0.10668)
		(layer "B.Cu")
		(net "ETH40G_B1_RX2N")
	)
	(segment
		(start -298.040001 43.960001)
		(end -298.454714 44.374712)
		(width 0.10668)
		(layer "B.Cu")
		(net "ETH40G_B1_RX2N")
	)
	(segment
		(start -298.8056 44.2722)
		(end -298.8056 32.525383)
		(width 0.10668)
		(layer "B.Cu")
		(net "ETH40G_B1_RX2N")
	)
	(segment
		(start -317.218944 33.47212)
		(end -319.19164 33.47212)
		(width 0.10668)
		(layer "B.Cu")
		(net "ETH40G_B1_RX2N")
	)
	(arc
		(start -298.63034 44.44746)
		(mid -298.754268 44.396128)
		(end -298.8056 44.2722)
		(width 0.10668)
		(layer "B.Cu")
		(net "ETH40G_B1_RX2N")
	)
	(arc
		(start -298.454714 44.374712)
		(mid -298.535292 44.428553)
		(end -298.63034 44.44746)
		(width 0.10668)
		(layer "B.Cu")
		(net "ETH40G_B1_RX2N")
	)
	(arc
		(start -309.627402 30.3276)
		(mid -312.793693 30.957414)
		(end -315.477947 32.750973)
		(width 0.10668)
		(layer "B.Cu")
		(net "ETH40G_B1_RX2N")
	)
	(arc
		(start -319.19164 33.47212)
		(mid -319.944185 33.783835)
		(end -320.2559 34.53638)
		(width 0.10668)
		(layer "B.Cu")
		(net "ETH40G_B1_RX2N")
	)
	(arc
		(start -299.3898 31.115)
		(mid -300.261964 30.532239)
		(end -301.290751 30.3276)
		(width 0.10668)
		(layer "B.Cu")
		(net "ETH40G_B1_RX2N")
	)
	(arc
		(start -315.477947 32.750973)
		(mid -316.276723 33.284699)
		(end -317.218944 33.47212)
		(width 0.10668)
		(layer "B.Cu")
		(net "ETH40G_B1_RX2N")
	)
	(arc
		(start -298.8056 32.525383)
		(mid -298.957429 31.762089)
		(end -299.3898 31.115)
		(width 0.10668)
		(layer "B.Cu")
		(net "ETH40G_B1_RX2N")
	)
	(arc
		(start -320.2559 36.31438)
		(mid -320.288107 36.476295)
		(end -320.379824 36.613559)
		(width 0.10668)
		(layer "B.Cu")
		(net "ETH40G_B1_RX2N")
	)
	(segment
		(start -321.649999 43.840001)
		(end -321.649999 44.821208)
		(width 0.10668)
		(layer "F.Cu")
		(net "ETH40G_B1_RX1P")
	)
	(segment
		(start -321.832829 46.454568)
		(end -321.643601 46.643795)
		(width 0.10668)
		(layer "F.Cu")
		(net "ETH40G_B1_RX1P")
	)
	(segment
		(start -321.832829 45.092414)
		(end -321.832829 46.454568)
		(width 0.10668)
		(layer "F.Cu")
		(net "ETH40G_B1_RX1P")
	)
	(segment
		(start -321.681246 44.896644)
		(end -321.801581 45.016979)
		(width 0.10668)
		(layer "F.Cu")
		(net "ETH40G_B1_RX1P")
	)
	(via
		(at -321.643601 46.643795)
		(size 0.5588)
		(drill 0.254)
		(layers "F.Cu" "B.Cu")
		(net "ETH40G_B1_RX1P")
	)
	(arc
		(start -321.649999 44.821208)
		(mid -321.65812 44.862034)
		(end -321.681246 44.896644)
		(width 0.10668)
		(layer "F.Cu")
		(net "ETH40G_B1_RX1P")
	)
	(arc
		(start -321.801581 45.016979)
		(mid -321.824707 45.051589)
		(end -321.832829 45.092414)
		(width 0.10668)
		(layer "F.Cu")
		(net "ETH40G_B1_RX1P")
	)
	(segment
		(start -309.877165 43.46702)
		(end -315.417744 43.46702)
		(width 0.10668)
		(layer "B.Cu")
		(net "ETH40G_B1_RX1P")
	)
	(segment
		(start -319.336953 43.69562)
		(end -319.748433 43.69562)
		(width 0.10668)
		(layer "B.Cu")
		(net "ETH40G_B1_RX1P")
	)
	(segment
		(start -319.108353 43.46702)
		(end -319.336953 43.69562)
		(width 0.10668)
		(layer "B.Cu")
		(net "ETH40G_B1_RX1P")
	)
	(segment
		(start -319.977033 43.46702)
		(end -321.078451 43.46702)
		(width 0.10668)
		(layer "B.Cu")
		(net "ETH40G_B1_RX1P")
	)
	(segment
		(start -315.966384 43.60418)
		(end -316.103544 43.46702)
		(width 0.10668)
		(layer "B.Cu")
		(net "ETH40G_B1_RX1P")
	)
	(segment
		(start -318.056793 43.69562)
		(end -318.468273 43.69562)
		(width 0.10668)
		(layer "B.Cu")
		(net "ETH40G_B1_RX1P")
	)
	(segment
		(start -318.468273 43.69562)
		(end -318.696873 43.46702)
		(width 0.10668)
		(layer "B.Cu")
		(net "ETH40G_B1_RX1P")
	)
	(segment
		(start -302.04 45.360001)
		(end -302.491582 44.908419)
		(width 0.10668)
		(layer "B.Cu")
		(net "ETH40G_B1_RX1P")
	)
	(segment
		(start -306.992757 46.079197)
		(end -309.412432 43.659522)
		(width 0.10668)
		(layer "B.Cu")
		(net "ETH40G_B1_RX1P")
	)
	(segment
		(start -319.748433 43.69562)
		(end -319.977033 43.46702)
		(width 0.10668)
		(layer "B.Cu")
		(net "ETH40G_B1_RX1P")
	)
	(segment
		(start -316.103544 43.46702)
		(end -316.548033 43.46702)
		(width 0.10668)
		(layer "B.Cu")
		(net "ETH40G_B1_RX1P")
	)
	(segment
		(start -317.188113 43.69562)
		(end -317.416713 43.46702)
		(width 0.10668)
		(layer "B.Cu")
		(net "ETH40G_B1_RX1P")
	)
	(segment
		(start -316.548033 43.46702)
		(end -316.776633 43.69562)
		(width 0.10668)
		(layer "B.Cu")
		(net "ETH40G_B1_RX1P")
	)
	(segment
		(start -317.416713 43.46702)
		(end -317.828193 43.46702)
		(width 0.10668)
		(layer "B.Cu")
		(net "ETH40G_B1_RX1P")
	)
	(segment
		(start -318.696873 43.46702)
		(end -319.108353 43.46702)
		(width 0.10668)
		(layer "B.Cu")
		(net "ETH40G_B1_RX1P")
	)
	(segment
		(start -302.567017 44.877172)
		(end -302.7934 44.877172)
		(width 0.10668)
		(layer "B.Cu")
		(net "ETH40G_B1_RX1P")
	)
	(segment
		(start -315.554904 43.60418)
		(end -315.966384 43.60418)
		(width 0.10668)
		(layer "B.Cu")
		(net "ETH40G_B1_RX1P")
	)
	(segment
		(start -317.828193 43.46702)
		(end -318.056793 43.69562)
		(width 0.10668)
		(layer "B.Cu")
		(net "ETH40G_B1_RX1P")
	)
	(segment
		(start -315.417744 43.46702)
		(end -315.554904 43.60418)
		(width 0.10668)
		(layer "B.Cu")
		(net "ETH40G_B1_RX1P")
	)
	(segment
		(start -302.91786 45.001632)
		(end -302.91786 45.847)
		(width 0.10668)
		(layer "B.Cu")
		(net "ETH40G_B1_RX1P")
	)
	(segment
		(start -303.7586 46.68774)
		(end -305.5236 46.68774)
		(width 0.10668)
		(layer "B.Cu")
		(net "ETH40G_B1_RX1P")
	)
	(segment
		(start -316.776633 43.69562)
		(end -317.188113 43.69562)
		(width 0.10668)
		(layer "B.Cu")
		(net "ETH40G_B1_RX1P")
	)
	(segment
		(start -321.832831 44.2214)
		(end -321.832831 46.186954)
		(width 0.10668)
		(layer "B.Cu")
		(net "ETH40G_B1_RX1P")
	)
	(arc
		(start -321.832831 46.186954)
		(mid -321.783652 46.434195)
		(end -321.643601 46.643795)
		(width 0.10668)
		(layer "B.Cu")
		(net "ETH40G_B1_RX1P")
	)
	(arc
		(start -309.412432 43.659522)
		(mid -309.625653 43.517051)
		(end -309.877165 43.46702)
		(width 0.10668)
		(layer "B.Cu")
		(net "ETH40G_B1_RX1P")
	)
	(arc
		(start -321.078451 43.46702)
		(mid -321.611878 43.687973)
		(end -321.832831 44.2214)
		(width 0.10668)
		(layer "B.Cu")
		(net "ETH40G_B1_RX1P")
	)
	(arc
		(start -302.91786 45.847)
		(mid -303.164107 46.441493)
		(end -303.7586 46.68774)
		(width 0.10668)
		(layer "B.Cu")
		(net "ETH40G_B1_RX1P")
	)
	(arc
		(start -302.7934 44.877172)
		(mid -302.881407 44.913625)
		(end -302.91786 45.001632)
		(width 0.10668)
		(layer "B.Cu")
		(net "ETH40G_B1_RX1P")
	)
	(arc
		(start -305.5236 46.68774)
		(mid -306.318701 46.529585)
		(end -306.992757 46.079197)
		(width 0.10668)
		(layer "B.Cu")
		(net "ETH40G_B1_RX1P")
	)
	(arc
		(start -302.491582 44.908419)
		(mid -302.526192 44.885293)
		(end -302.567017 44.877172)
		(width 0.10668)
		(layer "B.Cu")
		(net "ETH40G_B1_RX1P")
	)
	(segment
		(start -322.418753 44.896644)
		(end -322.298416 45.016981)
		(width 0.10668)
		(layer "F.Cu")
		(net "ETH40G_B1_RX1N")
	)
	(segment
		(start -322.267169 46.454563)
		(end -322.456401 46.643795)
		(width 0.10668)
		(layer "F.Cu")
		(net "ETH40G_B1_RX1N")
	)
	(segment
		(start -322.45 43.840001)
		(end -322.45 44.821208)
		(width 0.10668)
		(layer "F.Cu")
		(net "ETH40G_B1_RX1N")
	)
	(segment
		(start -322.267169 45.092417)
		(end -322.267169 46.454563)
		(width 0.10668)
		(layer "F.Cu")
		(net "ETH40G_B1_RX1N")
	)
	(via
		(at -322.456401 46.643795)
		(size 0.5588)
		(drill 0.254)
		(layers "F.Cu" "B.Cu")
		(net "ETH40G_B1_RX1N")
	)
	(arc
		(start -322.298416 45.016981)
		(mid -322.275289 45.051591)
		(end -322.267169 45.092417)
		(width 0.10668)
		(layer "F.Cu")
		(net "ETH40G_B1_RX1N")
	)
	(arc
		(start -322.45 44.821208)
		(mid -322.441879 44.862034)
		(end -322.418753 44.896644)
		(width 0.10668)
		(layer "F.Cu")
		(net "ETH40G_B1_RX1N")
	)
	(segment
		(start -303.7586 46.2534)
		(end -305.523598 46.2534)
		(width 0.10668)
		(layer "B.Cu")
		(net "ETH40G_B1_RX1N")
	)
	(segment
		(start -306.68563 45.77207)
		(end -309.105305 43.352395)
		(width 0.10668)
		(layer "B.Cu")
		(net "ETH40G_B1_RX1N")
	)
	(segment
		(start -322.267171 44.2214)
		(end -322.267171 46.186954)
		(width 0.10668)
		(layer "B.Cu")
		(net "ETH40G_B1_RX1N")
	)
	(segment
		(start -302.04 43.960001)
		(end -302.491585 44.411585)
		(width 0.10668)
		(layer "B.Cu")
		(net "ETH40G_B1_RX1N")
	)
	(segment
		(start -303.3522 45.001632)
		(end -303.3522 45.847)
		(width 0.10668)
		(layer "B.Cu")
		(net "ETH40G_B1_RX1N")
	)
	(segment
		(start -302.56702 44.442832)
		(end -302.7934 44.442832)
		(width 0.10668)
		(layer "B.Cu")
		(net "ETH40G_B1_RX1N")
	)
	(segment
		(start -309.877165 43.03268)
		(end -321.078451 43.03268)
		(width 0.10668)
		(layer "B.Cu")
		(net "ETH40G_B1_RX1N")
	)
	(arc
		(start -303.3522 45.847)
		(mid -303.471232 46.134368)
		(end -303.7586 46.2534)
		(width 0.10668)
		(layer "B.Cu")
		(net "ETH40G_B1_RX1N")
	)
	(arc
		(start -322.267171 46.186954)
		(mid -322.31635 46.434195)
		(end -322.456401 46.643795)
		(width 0.10668)
		(layer "B.Cu")
		(net "ETH40G_B1_RX1N")
	)
	(arc
		(start -302.7934 44.442832)
		(mid -303.188531 44.606501)
		(end -303.3522 45.001632)
		(width 0.10668)
		(layer "B.Cu")
		(net "ETH40G_B1_RX1N")
	)
	(arc
		(start -321.078451 43.03268)
		(mid -321.919003 43.380848)
		(end -322.267171 44.2214)
		(width 0.10668)
		(layer "B.Cu")
		(net "ETH40G_B1_RX1N")
	)
	(arc
		(start -302.491585 44.411585)
		(mid -302.526195 44.434711)
		(end -302.56702 44.442832)
		(width 0.10668)
		(layer "B.Cu")
		(net "ETH40G_B1_RX1N")
	)
	(arc
		(start -305.523598 46.2534)
		(mid -306.152485 46.128307)
		(end -306.68563 45.77207)
		(width 0.10668)
		(layer "B.Cu")
		(net "ETH40G_B1_RX1N")
	)
	(arc
		(start -309.105305 43.352395)
		(mid -309.459437 43.115771)
		(end -309.877165 43.03268)
		(width 0.10668)
		(layer "B.Cu")
		(net "ETH40G_B1_RX1N")
	)
	(segment
		(start -322.081248 40.283359)
		(end -322.201583 40.163024)
		(width 0.10668)
		(layer "F.Cu")
		(net "ETH40G_B1_RX0P")
	)
	(segment
		(start -322.23283 40.087588)
		(end -322.23283 39.008962)
		(width 0.10668)
		(layer "F.Cu")
		(net "ETH40G_B1_RX0P")
	)
	(segment
		(start -322.050001 41.340001)
		(end -322.050001 40.358794)
		(width 0.10668)
		(layer "F.Cu")
		(net "ETH40G_B1_RX0P")
	)
	(via
		(at -322.0436 38.55212)
		(size 0.5588)
		(drill 0.254)
		(layers "F.Cu" "B.Cu")
		(net "ETH40G_B1_RX0P")
	)
	(arc
		(start -322.201583 40.163024)
		(mid -322.22471 40.128414)
		(end -322.23283 40.087588)
		(width 0.10668)
		(layer "F.Cu")
		(net "ETH40G_B1_RX0P")
	)
	(arc
		(start -322.23283 39.008962)
		(mid -322.183651 38.761721)
		(end -322.0436 38.55212)
		(width 0.10668)
		(layer "F.Cu")
		(net "ETH40G_B1_RX0P")
	)
	(arc
		(start -322.050001 40.358794)
		(mid -322.058122 40.317969)
		(end -322.081248 40.283359)
		(width 0.10668)
		(layer "F.Cu")
		(net "ETH40G_B1_RX0P")
	)
	(segment
		(start -309.394327 32.903373)
		(end -315.305003 38.81405)
		(width 0.10668)
		(layer "B.Cu")
		(net "ETH40G_B1_RX0P")
	)
	(segment
		(start -303.512985 39.377173)
		(end -303.406302 39.377173)
		(width 0.10668)
		(layer "B.Cu")
		(net "ETH40G_B1_RX0P")
	)
	(segment
		(start -302.83626 38.807131)
		(end -302.83626 32.825667)
		(width 0.10668)
		(layer "B.Cu")
		(net "ETH40G_B1_RX0P")
	)
	(segment
		(start -305.900186 32.33166)
		(end -308.014086 32.33166)
		(width 0.10668)
		(layer "B.Cu")
		(net "ETH40G_B1_RX0P")
	)
	(segment
		(start -304.040002 39.860002)
		(end -303.58842 39.40842)
		(width 0.10668)
		(layer "B.Cu")
		(net "ETH40G_B1_RX0P")
	)
	(segment
		(start -320.59626 41.00576)
		(end -321.21937 41.00576)
		(width 0.10668)
		(layer "B.Cu")
		(net "ETH40G_B1_RX0P")
	)
	(segment
		(start -322.23283 39.9923)
		(end -322.23283 39.008962)
		(width 0.10668)
		(layer "B.Cu")
		(net "ETH40G_B1_RX0P")
	)
	(arc
		(start -308.014086 32.33166)
		(mid -308.761067 32.480243)
		(end -309.394327 32.903373)
		(width 0.10668)
		(layer "B.Cu")
		(net "ETH40G_B1_RX0P")
	)
	(arc
		(start -315.305003 38.81405)
		(mid -317.732652 40.436153)
		(end -320.59626 41.00576)
		(width 0.10668)
		(layer "B.Cu")
		(net "ETH40G_B1_RX0P")
	)
	(arc
		(start -303.230173 31.874673)
		(mid -304.01355 31.550188)
		(end -304.796927 31.874673)
		(width 0.10668)
		(layer "B.Cu")
		(net "ETH40G_B1_RX0P")
	)
	(arc
		(start -304.796927 31.874673)
		(mid -305.303106 32.212892)
		(end -305.900186 32.33166)
		(width 0.10668)
		(layer "B.Cu")
		(net "ETH40G_B1_RX0P")
	)
	(arc
		(start -303.406302 39.377173)
		(mid -303.003221 39.210212)
		(end -302.83626 38.807131)
		(width 0.10668)
		(layer "B.Cu")
		(net "ETH40G_B1_RX0P")
	)
	(arc
		(start -302.83626 32.825667)
		(mid -302.938635 32.310993)
		(end -303.230173 31.874673)
		(width 0.10668)
		(layer "B.Cu")
		(net "ETH40G_B1_RX0P")
	)
	(arc
		(start -321.21937 41.00576)
		(mid -321.935994 40.708924)
		(end -322.23283 39.9923)
		(width 0.10668)
		(layer "B.Cu")
		(net "ETH40G_B1_RX0P")
	)
	(arc
		(start -303.58842 39.40842)
		(mid -303.55381 39.385294)
		(end -303.512985 39.377173)
		(width 0.10668)
		(layer "B.Cu")
		(net "ETH40G_B1_RX0P")
	)
	(arc
		(start -322.23283 39.008962)
		(mid -322.183651 38.761721)
		(end -322.0436 38.55212)
		(width 0.10668)
		(layer "B.Cu")
		(net "ETH40G_B1_RX0P")
	)
	(segment
		(start -322.66717 40.087588)
		(end -322.66717 39.008962)
		(width 0.10668)
		(layer "F.Cu")
		(net "ETH40G_B1_RX0N")
	)
	(segment
		(start -322.849999 41.340001)
		(end -322.849999 40.358794)
		(width 0.10668)
		(layer "F.Cu")
		(net "ETH40G_B1_RX0N")
	)
	(segment
		(start -322.818752 40.283359)
		(end -322.698417 40.163024)
		(width 0.10668)
		(layer "F.Cu")
		(net "ETH40G_B1_RX0N")
	)
	(via
		(at -322.8564 38.55212)
		(size 0.5588)
		(drill 0.254)
		(layers "F.Cu" "B.Cu")
		(net "ETH40G_B1_RX0N")
	)
	(arc
		(start -322.698417 40.163024)
		(mid -322.67529 40.128414)
		(end -322.66717 40.087588)
		(width 0.10668)
		(layer "F.Cu")
		(net "ETH40G_B1_RX0N")
	)
	(arc
		(start -322.849999 40.358794)
		(mid -322.841878 40.317969)
		(end -322.818752 40.283359)
		(width 0.10668)
		(layer "F.Cu")
		(net "ETH40G_B1_RX0N")
	)
	(arc
		(start -322.66717 39.008962)
		(mid -322.716349 38.761721)
		(end -322.8564 38.55212)
		(width 0.10668)
		(layer "F.Cu")
		(net "ETH40G_B1_RX0N")
	)
	(segment
		(start -312.45812 36.58142)
		(end -314.997876 39.121177)
		(width 0.10668)
		(layer "B.Cu")
		(net "ETH40G_B1_RX0N")
	)
	(segment
		(start -309.543963 33.959363)
		(end -309.836063 33.959363)
		(width 0.10668)
		(layer "B.Cu")
		(net "ETH40G_B1_RX0N")
	)
	(segment
		(start -310.417982 34.833382)
		(end -310.710082 34.833382)
		(width 0.10668)
		(layer "B.Cu")
		(net "ETH40G_B1_RX0N")
	)
	(segment
		(start -320.59626 41.4401)
		(end -321.21937 41.4401)
		(width 0.10668)
		(layer "B.Cu")
		(net "ETH40G_B1_RX0N")
	)
	(segment
		(start -312.16602 36.58142)
		(end -312.45812 36.58142)
		(width 0.10668)
		(layer "B.Cu")
		(net "ETH40G_B1_RX0N")
	)
	(segment
		(start -309.253004 33.376304)
		(end -309.253004 33.668404)
		(width 0.10668)
		(layer "B.Cu")
		(net "ETH40G_B1_RX0N")
	)
	(segment
		(start -322.66717 39.9923)
		(end -322.66717 39.008962)
		(width 0.10668)
		(layer "B.Cu")
		(net "ETH40G_B1_RX0N")
	)
	(segment
		(start -305.900183 32.766)
		(end -308.014083 32.766)
		(width 0.10668)
		(layer "B.Cu")
		(net "ETH40G_B1_RX0N")
	)
	(segment
		(start -309.836063 33.959363)
		(end -310.127023 34.250323)
		(width 0.10668)
		(layer "B.Cu")
		(net "ETH40G_B1_RX0N")
	)
	(segment
		(start -311.001042 35.124342)
		(end -311.001042 35.416442)
		(width 0.10668)
		(layer "B.Cu")
		(net "ETH40G_B1_RX0N")
	)
	(segment
		(start -311.875061 35.998361)
		(end -311.875061 36.290461)
		(width 0.10668)
		(layer "B.Cu")
		(net "ETH40G_B1_RX0N")
	)
	(segment
		(start -303.2706 38.807131)
		(end -303.2706 32.82567)
		(width 0.10668)
		(layer "B.Cu")
		(net "ETH40G_B1_RX0N")
	)
	(segment
		(start -311.875061 36.290461)
		(end -312.16602 36.58142)
		(width 0.10668)
		(layer "B.Cu")
		(net "ETH40G_B1_RX0N")
	)
	(segment
		(start -310.127023 34.542423)
		(end -310.417982 34.833382)
		(width 0.10668)
		(layer "B.Cu")
		(net "ETH40G_B1_RX0N")
	)
	(segment
		(start -310.710082 34.833382)
		(end -311.001042 35.124342)
		(width 0.10668)
		(layer "B.Cu")
		(net "ETH40G_B1_RX0N")
	)
	(segment
		(start -304.040002 38.460002)
		(end -303.588417 38.911586)
		(width 0.10668)
		(layer "B.Cu")
		(net "ETH40G_B1_RX0N")
	)
	(segment
		(start -309.0872 33.2105)
		(end -309.253004 33.376304)
		(width 0.10668)
		(layer "B.Cu")
		(net "ETH40G_B1_RX0N")
	)
	(segment
		(start -311.001042 35.416442)
		(end -311.292001 35.707401)
		(width 0.10668)
		(layer "B.Cu")
		(net "ETH40G_B1_RX0N")
	)
	(segment
		(start -310.127023 34.250323)
		(end -310.127023 34.542423)
		(width 0.10668)
		(layer "B.Cu")
		(net "ETH40G_B1_RX0N")
	)
	(segment
		(start -311.584101 35.707401)
		(end -311.875061 35.998361)
		(width 0.10668)
		(layer "B.Cu")
		(net "ETH40G_B1_RX0N")
	)
	(segment
		(start -303.512982 38.942833)
		(end -303.406302 38.942833)
		(width 0.10668)
		(layer "B.Cu")
		(net "ETH40G_B1_RX0N")
	)
	(segment
		(start -309.253004 33.668404)
		(end -309.543963 33.959363)
		(width 0.10668)
		(layer "B.Cu")
		(net "ETH40G_B1_RX0N")
	)
	(segment
		(start -311.292001 35.707401)
		(end -311.584101 35.707401)
		(width 0.10668)
		(layer "B.Cu")
		(net "ETH40G_B1_RX0N")
	)
	(arc
		(start -303.588417 38.911586)
		(mid -303.553807 38.934712)
		(end -303.512982 38.942833)
		(width 0.10668)
		(layer "B.Cu")
		(net "ETH40G_B1_RX0N")
	)
	(arc
		(start -303.2706 32.82567)
		(mid -303.339913 32.47721)
		(end -303.5373 32.1818)
		(width 0.10668)
		(layer "B.Cu")
		(net "ETH40G_B1_RX0N")
	)
	(arc
		(start -308.014083 32.766)
		(mid -308.59485 32.881522)
		(end -309.0872 33.2105)
		(width 0.10668)
		(layer "B.Cu")
		(net "ETH40G_B1_RX0N")
	)
	(arc
		(start -303.5373 32.1818)
		(mid -304.01355 31.984531)
		(end -304.4898 32.1818)
		(width 0.10668)
		(layer "B.Cu")
		(net "ETH40G_B1_RX0N")
	)
	(arc
		(start -321.21937 41.4401)
		(mid -322.243119 41.016049)
		(end -322.66717 39.9923)
		(width 0.10668)
		(layer "B.Cu")
		(net "ETH40G_B1_RX0N")
	)
	(arc
		(start -303.406302 38.942833)
		(mid -303.310346 38.903087)
		(end -303.2706 38.807131)
		(width 0.10668)
		(layer "B.Cu")
		(net "ETH40G_B1_RX0N")
	)
	(arc
		(start -314.997876 39.121177)
		(mid -317.566437 40.837433)
		(end -320.59626 41.4401)
		(width 0.10668)
		(layer "B.Cu")
		(net "ETH40G_B1_RX0N")
	)
	(arc
		(start -322.66717 39.008962)
		(mid -322.716349 38.761721)
		(end -322.8564 38.55212)
		(width 0.10668)
		(layer "B.Cu")
		(net "ETH40G_B1_RX0N")
	)
	(arc
		(start -304.4898 32.1818)
		(mid -305.136889 32.614171)
		(end -305.900183 32.766)
		(width 0.10668)
		(layer "B.Cu")
		(net "ETH40G_B1_RX0N")
	)
	(segment
		(start -315.650001 38.58768)
		(end -316.086881 38.1508)
		(width 0.1016)
		(layer "F.Cu")
		(net "ETH40G_B1_RESET_N")
	)
	(segment
		(start -315.650001 41.340001)
		(end -315.650001 38.58768)
		(width 0.1016)
		(layer "F.Cu")
		(net "ETH40G_B1_RESET_N")
	)
	(segment
		(start -316.086881 38.1508)
		(end -317.21044 38.1508)
		(width 0.1016)
		(layer "F.Cu")
		(net "ETH40G_B1_RESET_N")
	)
	(segment
		(start -330.819999 10.4648)
		(end -329.692 10.4648)
		(width 0.1016)
		(layer "F.Cu")
		(net "ETH40G_B1_RESET_N")
	)
	(segment
		(start -332.120001 17.4498)
		(end -332.882001 17.4498)
		(width 0.1016)
		(layer "F.Cu")
		(net "ETH40G_B1_RESET_N")
	)
	(via
		(at -332.882001 17.4498)
		(size 0.5588)
		(drill 0.254)
		(layers "F.Cu" "B.Cu")
		(net "ETH40G_B1_RESET_N")
	)
	(via
		(at -329.692 10.4648)
		(size 0.5588)
		(drill 0.254)
		(layers "F.Cu" "B.Cu")
		(net "ETH40G_B1_RESET_N")
	)
	(via
		(at -317.21044 38.1508)
		(size 0.5588)
		(drill 0.254)
		(layers "F.Cu" "B.Cu")
		(net "ETH40G_B1_RESET_N")
	)
	(segment
		(start -332.3844 20.8026)
		(end -333.6036 19.5834)
		(width 0.12954)
		(layer "In2.Cu")
		(net "ETH40G_B1_RESET_N")
	)
	(segment
		(start -331.47 12.2428)
		(end -331.47 16.129)
		(width 0.12954)
		(layer "In2.Cu")
		(net "ETH40G_B1_RESET_N")
	)
	(segment
		(start -329.7428 24.0792)
		(end -332.3844 21.4376)
		(width 0.12954)
		(layer "In2.Cu")
		(net "ETH40G_B1_RESET_N")
	)
	(segment
		(start -318.36106 37.2237)
		(end -318.36106 31.33598)
		(width 0.12954)
		(layer "In2.Cu")
		(net "ETH40G_B1_RESET_N")
	)
	(segment
		(start -333.6036 18.171399)
		(end -332.882001 17.4498)
		(width 0.12954)
		(layer "In2.Cu")
		(net "ETH40G_B1_RESET_N")
	)
	(segment
		(start -326.054822 25.709778)
		(end -327.6854 24.0792)
		(width 0.12954)
		(layer "In2.Cu")
		(net "ETH40G_B1_RESET_N")
	)
	(segment
		(start -331.47 16.129)
		(end -332.7908 17.4498)
		(width 0.12954)
		(layer "In2.Cu")
		(net "ETH40G_B1_RESET_N")
	)
	(segment
		(start -333.6036 19.5834)
		(end -333.6036 18.171399)
		(width 0.12954)
		(layer "In2.Cu")
		(net "ETH40G_B1_RESET_N")
	)
	(segment
		(start -317.43396 38.1508)
		(end -318.36106 37.2237)
		(width 0.12954)
		(layer "In2.Cu")
		(net "ETH40G_B1_RESET_N")
	)
	(segment
		(start -323.987262 25.709778)
		(end -326.054822 25.709778)
		(width 0.12954)
		(layer "In2.Cu")
		(net "ETH40G_B1_RESET_N")
	)
	(segment
		(start -332.7908 17.4498)
		(end -332.882001 17.4498)
		(width 0.12954)
		(layer "In2.Cu")
		(net "ETH40G_B1_RESET_N")
	)
	(segment
		(start -329.692 10.4648)
		(end -331.47 12.2428)
		(width 0.12954)
		(layer "In2.Cu")
		(net "ETH40G_B1_RESET_N")
	)
	(segment
		(start -317.21044 38.1508)
		(end -317.43396 38.1508)
		(width 0.12954)
		(layer "In2.Cu")
		(net "ETH40G_B1_RESET_N")
	)
	(segment
		(start -318.36106 31.33598)
		(end -323.987262 25.709778)
		(width 0.12954)
		(layer "In2.Cu")
		(net "ETH40G_B1_RESET_N")
	)
	(segment
		(start -332.3844 21.4376)
		(end -332.3844 20.8026)
		(width 0.12954)
		(layer "In2.Cu")
		(net "ETH40G_B1_RESET_N")
	)
	(segment
		(start -327.6854 24.0792)
		(end -329.7428 24.0792)
		(width 0.12954)
		(layer "In2.Cu")
		(net "ETH40G_B1_RESET_N")
	)
	(segment
		(start -299.4914 11.811)
		(end -299.4406 11.8618)
		(width 0.1016)
		(layer "F.Cu")
		(net "ETH40G_B1_PRES_N")
	)
	(segment
		(start -300.339999 11.811)
		(end -299.4914 11.811)
		(width 0.1016)
		(layer "F.Cu")
		(net "ETH40G_B1_PRES_N")
	)
	(via
		(at -299.4406 11.8618)
		(size 0.5588)
		(drill 0.254)
		(layers "F.Cu" "B.Cu")
		(net "ETH40G_B1_PRES_N")
	)
	(segment
		(start -302.04 35.467)
		(end -302.04 35.56)
		(width 0.12954)
		(layer "In2.Cu")
		(net "ETH40G_B1_PRES_N")
	)
	(segment
		(start -301.7266 12.3698)
		(end -304.7492 15.3924)
		(width 0.12954)
		(layer "In2.Cu")
		(net "ETH40G_B1_PRES_N")
	)
	(segment
		(start -299.9486 12.3698)
		(end -301.7266 12.3698)
		(width 0.12954)
		(layer "In2.Cu")
		(net "ETH40G_B1_PRES_N")
	)
	(segment
		(start -304.7492 24.4602)
		(end -303.149 26.0604)
		(width 0.12954)
		(layer "In2.Cu")
		(net "ETH40G_B1_PRES_N")
	)
	(segment
		(start -303.149 29.1338)
		(end -301.2948 30.988)
		(width 0.12954)
		(layer "In2.Cu")
		(net "ETH40G_B1_PRES_N")
	)
	(segment
		(start -299.4406 11.8618)
		(end -299.9486 12.3698)
		(width 0.12954)
		(layer "In2.Cu")
		(net "ETH40G_B1_PRES_N")
	)
	(segment
		(start -301.2948 34.7218)
		(end -302.04 35.467)
		(width 0.12954)
		(layer "In2.Cu")
		(net "ETH40G_B1_PRES_N")
	)
	(segment
		(start -303.149 26.0604)
		(end -303.149 29.1338)
		(width 0.12954)
		(layer "In2.Cu")
		(net "ETH40G_B1_PRES_N")
	)
	(segment
		(start -304.7492 15.3924)
		(end -304.7492 24.4602)
		(width 0.12954)
		(layer "In2.Cu")
		(net "ETH40G_B1_PRES_N")
	)
	(segment
		(start -301.2948 30.988)
		(end -301.2948 34.7218)
		(width 0.12954)
		(layer "In2.Cu")
		(net "ETH40G_B1_PRES_N")
	)
	(segment
		(start -314.02274 39.0398)
		(end -314.02274 35.65906)
		(width 0.1016)
		(layer "F.Cu")
		(net "ETH40G_B1_MODSEL_N")
	)
	(segment
		(start -314.85 39.86706)
		(end -314.02274 39.0398)
		(width 0.1016)
		(layer "F.Cu")
		(net "ETH40G_B1_MODSEL_N")
	)
	(segment
		(start -314.85 41.340001)
		(end -314.85 39.86706)
		(width 0.1016)
		(layer "F.Cu")
		(net "ETH40G_B1_MODSEL_N")
	)
	(segment
		(start -329.89012 13.2588)
		(end -330.819999 13.2588)
		(width 0.1016)
		(layer "F.Cu")
		(net "ETH40G_B1_MODSEL_N")
	)
	(segment
		(start -330.819999 11.8618)
		(end -330.819999 13.2588)
		(width 0.1016)
		(layer "F.Cu")
		(net "ETH40G_B1_MODSEL_N")
	)
	(via
		(at -329.89012 13.2588)
		(size 0.5588)
		(drill 0.254)
		(layers "F.Cu" "B.Cu")
		(net "ETH40G_B1_MODSEL_N")
	)
	(via
		(at -314.02274 35.65906)
		(size 0.5588)
		(drill 0.254)
		(layers "F.Cu" "B.Cu")
		(net "ETH40G_B1_MODSEL_N")
	)
	(segment
		(start -323.3674 19.78152)
		(end -323.3674 23.22322)
		(width 0.12954)
		(layer "In2.Cu")
		(net "ETH40G_B1_MODSEL_N")
	)
	(segment
		(start -315.3156 34.3662)
		(end -314.02274 35.65906)
		(width 0.12954)
		(layer "In2.Cu")
		(net "ETH40G_B1_MODSEL_N")
	)
	(segment
		(start -329.89012 13.2588)
		(end -323.3674 19.78152)
		(width 0.12954)
		(layer "In2.Cu")
		(net "ETH40G_B1_MODSEL_N")
	)
	(segment
		(start -315.3156 31.27502)
		(end -315.3156 34.3662)
		(width 0.12954)
		(layer "In2.Cu")
		(net "ETH40G_B1_MODSEL_N")
	)
	(segment
		(start -323.3674 23.22322)
		(end -315.3156 31.27502)
		(width 0.12954)
		(layer "In2.Cu")
		(net "ETH40G_B1_MODSEL_N")
	)
	(segment
		(start -301.640001 11.811)
		(end -302.514 11.811)
		(width 0.1016)
		(layer "F.Cu")
		(net "ETH40G_B1_MODPRS_N")
	)
	(segment
		(start -317.65 43.840001)
		(end -317.65 45.69968)
		(width 0.1016)
		(layer "F.Cu")
		(net "ETH40G_B1_MODPRS_N")
	)
	(via
		(at -302.514 11.811)
		(size 0.5588)
		(drill 0.254)
		(layers "F.Cu" "B.Cu")
		(net "ETH40G_B1_MODPRS_N")
	)
	(via
		(at -305.45532 44.7802)
		(size 0.5588)
		(drill 0.254)
		(layers "F.Cu" "B.Cu")
		(net "ETH40G_B1_MODPRS_N")
	)
	(via
		(at -317.65 45.69968)
		(size 0.5588)
		(drill 0.254)
		(layers "F.Cu" "B.Cu")
		(net "ETH40G_B1_MODPRS_N")
	)
	(segment
		(start -306.3748 12.1666)
		(end -303.6316 9.4234)
		(width 0.12954)
		(layer "In2.Cu")
		(net "ETH40G_B1_MODPRS_N")
	)
	(segment
		(start -305.45532 44.7802)
		(end -305.16322 45.0723)
		(width 0.12954)
		(layer "In2.Cu")
		(net "ETH40G_B1_MODPRS_N")
	)
	(segment
		(start -303.6316 9.4234)
		(end -302.3108 9.4234)
		(width 0.12954)
		(layer "In2.Cu")
		(net "ETH40G_B1_MODPRS_N")
	)
	(segment
		(start -308.1782 18.8214)
		(end -307.8734 18.5166)
		(width 0.12954)
		(layer "In2.Cu")
		(net "ETH40G_B1_MODPRS_N")
	)
	(segment
		(start -302.4886 11.811)
		(end -302.514 11.811)
		(width 0.12954)
		(layer "In2.Cu")
		(net "ETH40G_B1_MODPRS_N")
	)
	(segment
		(start -306.3748 16.9672)
		(end -306.3748 12.1666)
		(width 0.12954)
		(layer "In2.Cu")
		(net "ETH40G_B1_MODPRS_N")
	)
	(segment
		(start -303.24552 45.90796)
		(end -303.24552 32.16656)
		(width 0.12954)
		(layer "In2.Cu")
		(net "ETH40G_B1_MODPRS_N")
	)
	(segment
		(start -301.752 9.9822)
		(end -301.752 11.0744)
		(width 0.12954)
		(layer "In2.Cu")
		(net "ETH40G_B1_MODPRS_N")
	)
	(segment
		(start -303.54778 46.21022)
		(end -303.24552 45.90796)
		(width 0.12954)
		(layer "In2.Cu")
		(net "ETH40G_B1_MODPRS_N")
	)
	(segment
		(start -303.24552 32.16656)
		(end -304.270446 31.141634)
		(width 0.12954)
		(layer "In2.Cu")
		(net "ETH40G_B1_MODPRS_N")
	)
	(segment
		(start -304.270446 31.141634)
		(end -306.043366 31.141634)
		(width 0.12954)
		(layer "In2.Cu")
		(net "ETH40G_B1_MODPRS_N")
	)
	(segment
		(start -307.8734 18.4658)
		(end -306.3748 16.9672)
		(width 0.12954)
		(layer "In2.Cu")
		(net "ETH40G_B1_MODPRS_N")
	)
	(segment
		(start -305.16322 45.0723)
		(end -305.16322 45.54474)
		(width 0.12954)
		(layer "In2.Cu")
		(net "ETH40G_B1_MODPRS_N")
	)
	(segment
		(start -301.752 11.0744)
		(end -302.4886 11.811)
		(width 0.12954)
		(layer "In2.Cu")
		(net "ETH40G_B1_MODPRS_N")
	)
	(segment
		(start -308.1782 29.0068)
		(end -308.1782 18.8214)
		(width 0.12954)
		(layer "In2.Cu")
		(net "ETH40G_B1_MODPRS_N")
	)
	(segment
		(start -307.8734 18.5166)
		(end -307.8734 18.4658)
		(width 0.12954)
		(layer "In2.Cu")
		(net "ETH40G_B1_MODPRS_N")
	)
	(segment
		(start -305.16322 45.54474)
		(end -304.49774 46.21022)
		(width 0.12954)
		(layer "In2.Cu")
		(net "ETH40G_B1_MODPRS_N")
	)
	(segment
		(start -306.043366 31.141634)
		(end -308.1782 29.0068)
		(width 0.12954)
		(layer "In2.Cu")
		(net "ETH40G_B1_MODPRS_N")
	)
	(segment
		(start -304.49774 46.21022)
		(end -303.54778 46.21022)
		(width 0.12954)
		(layer "In2.Cu")
		(net "ETH40G_B1_MODPRS_N")
	)
	(segment
		(start -302.3108 9.4234)
		(end -301.752 9.9822)
		(width 0.12954)
		(layer "In2.Cu")
		(net "ETH40G_B1_MODPRS_N")
	)
	(segment
		(start -305.45532 44.7802)
		(end -306.197 44.7802)
		(width 0.12954)
		(layer "In3.Cu")
		(net "ETH40G_B1_MODPRS_N")
	)
	(segment
		(start -317.25376 46.09592)
		(end -317.65 45.69968)
		(width 0.12954)
		(layer "In3.Cu")
		(net "ETH40G_B1_MODPRS_N")
	)
	(segment
		(start -315.595 46.09592)
		(end -317.25376 46.09592)
		(width 0.12954)
		(layer "In3.Cu")
		(net "ETH40G_B1_MODPRS_N")
	)
	(segment
		(start -314.78474 48.30318)
		(end -315.10732 47.9806)
		(width 0.12954)
		(layer "In3.Cu")
		(net "ETH40G_B1_MODPRS_N")
	)
	(segment
		(start -315.10732 47.9806)
		(end -315.10732 46.5836)
		(width 0.12954)
		(layer "In3.Cu")
		(net "ETH40G_B1_MODPRS_N")
	)
	(segment
		(start -315.10732 46.5836)
		(end -315.595 46.09592)
		(width 0.12954)
		(layer "In3.Cu")
		(net "ETH40G_B1_MODPRS_N")
	)
	(segment
		(start -306.197 44.7802)
		(end -309.71998 48.30318)
		(width 0.12954)
		(layer "In3.Cu")
		(net "ETH40G_B1_MODPRS_N")
	)
	(segment
		(start -309.71998 48.30318)
		(end -314.78474 48.30318)
		(width 0.12954)
		(layer "In3.Cu")
		(net "ETH40G_B1_MODPRS_N")
	)
	(segment
		(start -314.450001 45.6819)
		(end -314.450001 43.840001)
		(width 0.1016)
		(layer "F.Cu")
		(net "ETH40G_B1_LPMODE")
	)
	(segment
		(start -334.6958 16.240999)
		(end -334.6958 15.2908)
		(width 0.1016)
		(layer "F.Cu")
		(net "ETH40G_B1_LPMODE")
	)
	(segment
		(start -332.120001 7.6708)
		(end -333.0448 7.6708)
		(width 0.1016)
		(layer "F.Cu")
		(net "ETH40G_B1_LPMODE")
	)
	(via
		(at -334.6958 15.2908)
		(size 0.5588)
		(drill 0.254)
		(layers "F.Cu" "B.Cu")
		(net "ETH40G_B1_LPMODE")
	)
	(via
		(at -324.975065 45.867165)
		(size 0.5588)
		(drill 0.254)
		(layers "F.Cu" "B.Cu")
		(net "ETH40G_B1_LPMODE")
	)
	(via
		(at -314.450001 45.6819)
		(size 0.5588)
		(drill 0.254)
		(layers "F.Cu" "B.Cu")
		(net "ETH40G_B1_LPMODE")
	)
	(via
		(at -333.0448 7.6708)
		(size 0.5588)
		(drill 0.254)
		(layers "F.Cu" "B.Cu")
		(net "ETH40G_B1_LPMODE")
	)
	(segment
		(start -323.41566 47.98568)
		(end -324.34276 47.05858)
		(width 0.1016)
		(layer "B.Cu")
		(net "ETH40G_B1_LPMODE")
	)
	(segment
		(start -324.34276 47.05858)
		(end -324.34276 46.1772)
		(width 0.1016)
		(layer "B.Cu")
		(net "ETH40G_B1_LPMODE")
	)
	(segment
		(start -319.25768 44.73702)
		(end -319.86474 45.34408)
		(width 0.1016)
		(layer "B.Cu")
		(net "ETH40G_B1_LPMODE")
	)
	(segment
		(start -324.34276 46.1772)
		(end -324.652795 45.867165)
		(width 0.1016)
		(layer "B.Cu")
		(net "ETH40G_B1_LPMODE")
	)
	(segment
		(start -319.86474 45.34408)
		(end -319.86474 47.43958)
		(width 0.1016)
		(layer "B.Cu")
		(net "ETH40G_B1_LPMODE")
	)
	(segment
		(start -314.84316 44.73702)
		(end -319.25768 44.73702)
		(width 0.1016)
		(layer "B.Cu")
		(net "ETH40G_B1_LPMODE")
	)
	(segment
		(start -319.86474 47.43958)
		(end -320.41084 47.98568)
		(width 0.1016)
		(layer "B.Cu")
		(net "ETH40G_B1_LPMODE")
	)
	(segment
		(start -314.4901 45.641801)
		(end -314.4901 45.09008)
		(width 0.1016)
		(layer "B.Cu")
		(net "ETH40G_B1_LPMODE")
	)
	(segment
		(start -314.450001 45.6819)
		(end -314.4901 45.641801)
		(width 0.1016)
		(layer "B.Cu")
		(net "ETH40G_B1_LPMODE")
	)
	(segment
		(start -320.41084 47.98568)
		(end -323.41566 47.98568)
		(width 0.1016)
		(layer "B.Cu")
		(net "ETH40G_B1_LPMODE")
	)
	(segment
		(start -314.4901 45.09008)
		(end -314.84316 44.73702)
		(width 0.1016)
		(layer "B.Cu")
		(net "ETH40G_B1_LPMODE")
	)
	(segment
		(start -324.652795 45.867165)
		(end -324.975065 45.867165)
		(width 0.1016)
		(layer "B.Cu")
		(net "ETH40G_B1_LPMODE")
	)
	(segment
		(start -334.6958 8.7376)
		(end -334.6958 15.2908)
		(width 0.12954)
		(layer "In2.Cu")
		(net "ETH40G_B1_LPMODE")
	)
	(segment
		(start -333.629 7.6708)
		(end -334.6958 8.7376)
		(width 0.12954)
		(layer "In2.Cu")
		(net "ETH40G_B1_LPMODE")
	)
	(segment
		(start -335.1784 20.0406)
		(end -335.1784 15.7734)
		(width 0.12954)
		(layer "In2.Cu")
		(net "ETH40G_B1_LPMODE")
	)
	(segment
		(start -328.041 25.019)
		(end -330.2 25.019)
		(width 0.12954)
		(layer "In2.Cu")
		(net "ETH40G_B1_LPMODE")
	)
	(segment
		(start -327.2536 25.8064)
		(end -328.041 25.019)
		(width 0.12954)
		(layer "In2.Cu")
		(net "ETH40G_B1_LPMODE")
	)
	(segment
		(start -327.2536 44.958)
		(end -327.2536 25.8064)
		(width 0.12954)
		(layer "In2.Cu")
		(net "ETH40G_B1_LPMODE")
	)
	(segment
		(start -333.0448 7.6708)
		(end -333.629 7.6708)
		(width 0.12954)
		(layer "In2.Cu")
		(net "ETH40G_B1_LPMODE")
	)
	(segment
		(start -324.975065 45.867165)
		(end -326.344435 45.867165)
		(width 0.12954)
		(layer "In2.Cu")
		(net "ETH40G_B1_LPMODE")
	)
	(segment
		(start -330.2 25.019)
		(end -335.1784 20.0406)
		(width 0.12954)
		(layer "In2.Cu")
		(net "ETH40G_B1_LPMODE")
	)
	(segment
		(start -326.344435 45.867165)
		(end -327.2536 44.958)
		(width 0.12954)
		(layer "In2.Cu")
		(net "ETH40G_B1_LPMODE")
	)
	(segment
		(start -335.1784 15.7734)
		(end -334.6958 15.2908)
		(width 0.12954)
		(layer "In2.Cu")
		(net "ETH40G_B1_LPMODE")
	)
	(segment
		(start -316.849999 43.840001)
		(end -316.849999 45.058414)
		(width 0.1016)
		(layer "F.Cu")
		(net "ETH40G_B1_INT_N")
	)
	(segment
		(start -329.8698 9.0678)
		(end -330.819999 9.0678)
		(width 0.1016)
		(layer "F.Cu")
		(net "ETH40G_B1_INT_N")
	)
	(segment
		(start -316.849999 45.058414)
		(end -316.986567 45.194982)
		(width 0.1016)
		(layer "F.Cu")
		(net "ETH40G_B1_INT_N")
	)
	(via
		(at -316.986567 45.194982)
		(size 0.5588)
		(drill 0.254)
		(layers "F.Cu" "B.Cu")
		(net "ETH40G_B1_INT_N")
	)
	(via
		(at -324.32244 45.21962)
		(size 0.5588)
		(drill 0.254)
		(layers "F.Cu" "B.Cu")
		(net "ETH40G_B1_INT_N")
	)
	(via
		(at -329.8698 9.0678)
		(size 0.5588)
		(drill 0.254)
		(layers "F.Cu" "B.Cu")
		(net "ETH40G_B1_INT_N")
	)
	(segment
		(start -326.519593 45.184007)
		(end -325.201333 45.184007)
		(width 0.12954)
		(layer "In2.Cu")
		(net "ETH40G_B1_INT_N")
	)
	(segment
		(start -326.96404 25.58796)
		(end -326.96404 44.73956)
		(width 0.12954)
		(layer "In2.Cu")
		(net "ETH40G_B1_INT_N")
	)
	(segment
		(start -329.8698 9.0678)
		(end -330.5556 9.7536)
		(width 0.12954)
		(layer "In2.Cu")
		(net "ETH40G_B1_INT_N")
	)
	(segment
		(start -327.914 24.638)
		(end -326.96404 25.58796)
		(width 0.12954)
		(layer "In2.Cu")
		(net "ETH40G_B1_INT_N")
	)
	(segment
		(start -330.5556 9.7536)
		(end -333.1464 9.7536)
		(width 0.12954)
		(layer "In2.Cu")
		(net "ETH40G_B1_INT_N")
	)
	(segment
		(start -334.137 20.574)
		(end -330.073 24.638)
		(width 0.12954)
		(layer "In2.Cu")
		(net "ETH40G_B1_INT_N")
	)
	(segment
		(start -325.16572 45.21962)
		(end -324.32244 45.21962)
		(width 0.12954)
		(layer "In2.Cu")
		(net "ETH40G_B1_INT_N")
	)
	(segment
		(start -326.96404 44.73956)
		(end -326.519593 45.184007)
		(width 0.12954)
		(layer "In2.Cu")
		(net "ETH40G_B1_INT_N")
	)
	(segment
		(start -325.201333 45.184007)
		(end -325.16572 45.21962)
		(width 0.12954)
		(layer "In2.Cu")
		(net "ETH40G_B1_INT_N")
	)
	(segment
		(start -333.1464 9.7536)
		(end -334.137 10.7442)
		(width 0.12954)
		(layer "In2.Cu")
		(net "ETH40G_B1_INT_N")
	)
	(segment
		(start -330.073 24.638)
		(end -327.914 24.638)
		(width 0.12954)
		(layer "In2.Cu")
		(net "ETH40G_B1_INT_N")
	)
	(segment
		(start -334.137 10.7442)
		(end -334.137 20.574)
		(width 0.12954)
		(layer "In2.Cu")
		(net "ETH40G_B1_INT_N")
	)
	(segment
		(start -324.32244 43.50258)
		(end -324.32244 45.21962)
		(width 0.12954)
		(layer "In5.Cu")
		(net "ETH40G_B1_INT_N")
	)
	(segment
		(start -317.22822 42.98442)
		(end -317.627 42.58564)
		(width 0.12954)
		(layer "In5.Cu")
		(net "ETH40G_B1_INT_N")
	)
	(segment
		(start -317.22822 44.953329)
		(end -317.22822 42.98442)
		(width 0.12954)
		(layer "In5.Cu")
		(net "ETH40G_B1_INT_N")
	)
	(segment
		(start -317.627 42.58564)
		(end -323.4055 42.58564)
		(width 0.12954)
		(layer "In5.Cu")
		(net "ETH40G_B1_INT_N")
	)
	(segment
		(start -316.986567 45.194982)
		(end -317.22822 44.953329)
		(width 0.12954)
		(layer "In5.Cu")
		(net "ETH40G_B1_INT_N")
	)
	(segment
		(start -323.4055 42.58564)
		(end -324.32244 43.50258)
		(width 0.12954)
		(layer "In5.Cu")
		(net "ETH40G_B1_INT_N")
	)
	(segment
		(start -59.150001 26.4668)
		(end -59.150001 27.96)
		(width 0.1016)
		(layer "F.Cu")
		(net "ETH10G_B2_TX_FAULT")
	)
	(segment
		(start -73.749002 1.130402)
		(end -73.7362 1.1176)
		(width 0.1016)
		(layer "F.Cu")
		(net "ETH10G_B2_TX_FAULT")
	)
	(segment
		(start -74.6428 1.130402)
		(end -73.749002 1.130402)
		(width 0.1016)
		(layer "F.Cu")
		(net "ETH10G_B2_TX_FAULT")
	)
	(via
		(at -73.7362 1.1176)
		(size 0.5588)
		(drill 0.254)
		(layers "F.Cu" "B.Cu")
		(net "ETH10G_B2_TX_FAULT")
	)
	(via
		(at -59.150001 26.4668)
		(size 0.5588)
		(drill 0.254)
		(layers "F.Cu" "B.Cu")
		(net "ETH10G_B2_TX_FAULT")
	)
	(segment
		(start -62.7126 22.3828)
		(end -59.150001 25.945399)
		(width 0.12954)
		(layer "In2.Cu")
		(net "ETH10G_B2_TX_FAULT")
	)
	(segment
		(start -62.7126 15.5194)
		(end -62.7126 22.3828)
		(width 0.12954)
		(layer "In2.Cu")
		(net "ETH10G_B2_TX_FAULT")
	)
	(segment
		(start -59.150001 25.945399)
		(end -59.150001 26.4668)
		(width 0.12954)
		(layer "In2.Cu")
		(net "ETH10G_B2_TX_FAULT")
	)
	(segment
		(start -73.7362 1.1176)
		(end -71.9636 2.8902)
		(width 0.12954)
		(layer "In2.Cu")
		(net "ETH10G_B2_TX_FAULT")
	)
	(segment
		(start -71.9636 2.8902)
		(end -71.9636 6.2684)
		(width 0.12954)
		(layer "In2.Cu")
		(net "ETH10G_B2_TX_FAULT")
	)
	(segment
		(start -71.9636 6.2684)
		(end -62.7126 15.5194)
		(width 0.12954)
		(layer "In2.Cu")
		(net "ETH10G_B2_TX_FAULT")
	)
	(segment
		(start -74.6428 5.270602)
		(end -74.6428 6.591402)
		(width 0.1016)
		(layer "F.Cu")
		(net "ETH10G_B2_TX_DIS")
	)
	(segment
		(start -73.875798 6.591402)
		(end -74.6428 6.591402)
		(width 0.1016)
		(layer "F.Cu")
		(net "ETH10G_B2_TX_DIS")
	)
	(segment
		(start -73.8632 6.604)
		(end -73.875798 6.591402)
		(width 0.1016)
		(layer "F.Cu")
		(net "ETH10G_B2_TX_DIS")
	)
	(segment
		(start -59.950002 25.9334)
		(end -59.950002 27.96)
		(width 0.1016)
		(layer "F.Cu")
		(net "ETH10G_B2_TX_DIS")
	)
	(via
		(at -59.950002 25.9334)
		(size 0.5588)
		(drill 0.254)
		(layers "F.Cu" "B.Cu")
		(net "ETH10G_B2_TX_DIS")
	)
	(via
		(at -73.8632 6.604)
		(size 0.5588)
		(drill 0.254)
		(layers "F.Cu" "B.Cu")
		(net "ETH10G_B2_TX_DIS")
	)
	(segment
		(start -59.950002 25.9334)
		(end -59.950002 25.881998)
		(width 0.12954)
		(layer "In2.Cu")
		(net "ETH10G_B2_TX_DIS")
	)
	(segment
		(start -63.3476 22.4844)
		(end -63.3476 15.9766)
		(width 0.12954)
		(layer "In2.Cu")
		(net "ETH10G_B2_TX_DIS")
	)
	(segment
		(start -72.7202 6.604)
		(end -73.8632 6.604)
		(width 0.12954)
		(layer "In2.Cu")
		(net "ETH10G_B2_TX_DIS")
	)
	(segment
		(start -59.950002 25.881998)
		(end -63.3476 22.4844)
		(width 0.12954)
		(layer "In2.Cu")
		(net "ETH10G_B2_TX_DIS")
	)
	(segment
		(start -63.3476 15.9766)
		(end -72.7202 6.604)
		(width 0.12954)
		(layer "In2.Cu")
		(net "ETH10G_B2_TX_DIS")
	)
	(segment
		(start -59.66238 30.71114)
		(end -60.153781 30.71114)
		(width 0.10668)
		(layer "F.Cu")
		(net "ETH10G_B2_TXP")
	)
	(segment
		(start -59.36774 34.69894)
		(end -59.36774 31.00578)
		(width 0.10668)
		(layer "F.Cu")
		(net "ETH10G_B2_TXP")
	)
	(segment
		(start -59.55 36.159999)
		(end -59.55 34.8812)
		(width 0.10668)
		(layer "F.Cu")
		(net "ETH10G_B2_TXP")
	)
	(segment
		(start -59.55 34.8812)
		(end -59.36774 34.69894)
		(width 0.10668)
		(layer "F.Cu")
		(net "ETH10G_B2_TXP")
	)
	(via
		(at -60.610623 30.90037)
		(size 0.5588)
		(drill 0.254)
		(layers "F.Cu" "B.Cu")
		(net "ETH10G_B2_TXP")
	)
	(arc
		(start -59.36774 31.00578)
		(mid -59.454038 30.797438)
		(end -59.66238 30.71114)
		(width 0.10668)
		(layer "F.Cu")
		(net "ETH10G_B2_TXP")
	)
	(arc
		(start -60.153781 30.71114)
		(mid -60.401022 30.760319)
		(end -60.610623 30.90037)
		(width 0.10668)
		(layer "F.Cu")
		(net "ETH10G_B2_TXP")
	)
	(segment
		(start -72.58842 36.508418)
		(end -73.040001 36.96)
		(width 0.10668)
		(layer "B.Cu")
		(net "ETH10G_B2_TXP")
	)
	(segment
		(start -61.83408 30.99308)
		(end -62.20492 30.99308)
		(width 0.10668)
		(layer "B.Cu")
		(net "ETH10G_B2_TXP")
	)
	(segment
		(start -62.337 30.861)
		(end -62.337 30.83814)
		(width 0.10668)
		(layer "B.Cu")
		(net "ETH10G_B2_TXP")
	)
	(segment
		(start -63.861 30.83814)
		(end -63.861 30.861)
		(width 0.10668)
		(layer "B.Cu")
		(net "ETH10G_B2_TXP")
	)
	(segment
		(start -72.243559 36.477171)
		(end -72.512984 36.477171)
		(width 0.10668)
		(layer "B.Cu")
		(net "ETH10G_B2_TXP")
	)
	(segment
		(start -64.496 30.861)
		(end -64.496 30.8556)
		(width 0.10668)
		(layer "B.Cu")
		(net "ETH10G_B2_TXP")
	)
	(segment
		(start -70.704128 35.321182)
		(end -71.588991 36.206044)
		(width 0.10668)
		(layer "B.Cu")
		(net "ETH10G_B2_TXP")
	)
	(segment
		(start -70.05606 33.7566)
		(end -70.05606 33.756603)
		(width 0.10668)
		(layer "B.Cu")
		(net "ETH10G_B2_TXP")
	)
	(segment
		(start -64.0134 31.0134)
		(end -64.3436 31.0134)
		(width 0.10668)
		(layer "B.Cu")
		(net "ETH10G_B2_TXP")
	)
	(segment
		(start -62.464 30.71114)
		(end -63.734 30.71114)
		(width 0.10668)
		(layer "B.Cu")
		(net "ETH10G_B2_TXP")
	)
	(segment
		(start -64.64046 30.71114)
		(end -67.0106 30.71114)
		(width 0.10668)
		(layer "B.Cu")
		(net "ETH10G_B2_TXP")
	)
	(segment
		(start -61.064018 30.712567)
		(end -61.57279 30.712567)
		(width 0.10668)
		(layer "B.Cu")
		(net "ETH10G_B2_TXP")
	)
	(arc
		(start -63.861 30.861)
		(mid -63.905637 30.968763)
		(end -64.0134 31.0134)
		(width 0.10668)
		(layer "B.Cu")
		(net "ETH10G_B2_TXP")
	)
	(arc
		(start -64.496 30.8556)
		(mid -64.538311 30.753451)
		(end -64.64046 30.71114)
		(width 0.10668)
		(layer "B.Cu")
		(net "ETH10G_B2_TXP")
	)
	(arc
		(start -71.588991 36.206044)
		(mid -71.88931 36.406709)
		(end -72.243559 36.477171)
		(width 0.10668)
		(layer "B.Cu")
		(net "ETH10G_B2_TXP")
	)
	(arc
		(start -62.337 30.83814)
		(mid -62.374197 30.748337)
		(end -62.464 30.71114)
		(width 0.10668)
		(layer "B.Cu")
		(net "ETH10G_B2_TXP")
	)
	(arc
		(start -61.702 30.861)
		(mid -61.740685 30.954395)
		(end -61.83408 30.99308)
		(width 0.10668)
		(layer "B.Cu")
		(net "ETH10G_B2_TXP")
	)
	(arc
		(start -67.0106 30.71114)
		(mid -69.164065 31.603135)
		(end -70.05606 33.7566)
		(width 0.10668)
		(layer "B.Cu")
		(net "ETH10G_B2_TXP")
	)
	(arc
		(start -63.734 30.71114)
		(mid -63.823803 30.748337)
		(end -63.861 30.83814)
		(width 0.10668)
		(layer "B.Cu")
		(net "ETH10G_B2_TXP")
	)
	(arc
		(start -61.57279 30.712567)
		(mid -61.665173 30.762603)
		(end -61.702 30.861)
		(width 0.10668)
		(layer "B.Cu")
		(net "ETH10G_B2_TXP")
	)
	(arc
		(start -70.05606 33.756603)
		(mid -70.224488 34.603347)
		(end -70.704128 35.321182)
		(width 0.10668)
		(layer "B.Cu")
		(net "ETH10G_B2_TXP")
	)
	(arc
		(start -64.3436 31.0134)
		(mid -64.451363 30.968763)
		(end -64.496 30.861)
		(width 0.10668)
		(layer "B.Cu")
		(net "ETH10G_B2_TXP")
	)
	(arc
		(start -60.610623 30.90037)
		(mid -60.818642 30.761376)
		(end -61.064018 30.712567)
		(width 0.10668)
		(layer "B.Cu")
		(net "ETH10G_B2_TXP")
	)
	(arc
		(start -62.20492 30.99308)
		(mid -62.298315 30.954395)
		(end -62.337 30.861)
		(width 0.10668)
		(layer "B.Cu")
		(net "ETH10G_B2_TXP")
	)
	(arc
		(start -72.512984 36.477171)
		(mid -72.55381 36.485292)
		(end -72.58842 36.508418)
		(width 0.10668)
		(layer "B.Cu")
		(net "ETH10G_B2_TXP")
	)
	(segment
		(start -58.750002 36.159999)
		(end -58.750002 34.889958)
		(width 0.10668)
		(layer "F.Cu")
		(net "ETH10G_B2_TXN")
	)
	(segment
		(start -58.750002 34.889958)
		(end -58.9334 34.70656)
		(width 0.10668)
		(layer "F.Cu")
		(net "ETH10G_B2_TXN")
	)
	(segment
		(start -59.66238 30.2768)
		(end -60.153781 30.2768)
		(width 0.10668)
		(layer "F.Cu")
		(net "ETH10G_B2_TXN")
	)
	(segment
		(start -58.9334 34.70656)
		(end -58.9334 31.00578)
		(width 0.10668)
		(layer "F.Cu")
		(net "ETH10G_B2_TXN")
	)
	(via
		(at -60.610623 30.08757)
		(size 0.5588)
		(drill 0.254)
		(layers "F.Cu" "B.Cu")
		(net "ETH10G_B2_TXN")
	)
	(arc
		(start -58.9334 31.00578)
		(mid -59.146913 30.490313)
		(end -59.66238 30.2768)
		(width 0.10668)
		(layer "F.Cu")
		(net "ETH10G_B2_TXN")
	)
	(arc
		(start -60.153781 30.2768)
		(mid -60.401022 30.227621)
		(end -60.610623 30.08757)
		(width 0.10668)
		(layer "F.Cu")
		(net "ETH10G_B2_TXN")
	)
	(segment
		(start -72.243556 36.042831)
		(end -72.512982 36.042831)
		(width 0.10668)
		(layer "B.Cu")
		(net "ETH10G_B2_TXN")
	)
	(segment
		(start -71.011255 35.014055)
		(end -71.896117 35.898917)
		(width 0.10668)
		(layer "B.Cu")
		(net "ETH10G_B2_TXN")
	)
	(segment
		(start -61.067465 30.2768)
		(end -67.0106 30.2768)
		(width 0.10668)
		(layer "B.Cu")
		(net "ETH10G_B2_TXN")
	)
	(segment
		(start -72.588417 36.011584)
		(end -73.040001 35.56)
		(width 0.10668)
		(layer "B.Cu")
		(net "ETH10G_B2_TXN")
	)
	(arc
		(start -67.0106 30.2768)
		(mid -69.47119 31.29601)
		(end -70.4904 33.7566)
		(width 0.10668)
		(layer "B.Cu")
		(net "ETH10G_B2_TXN")
	)
	(arc
		(start -60.610623 30.08757)
		(mid -60.820224 30.227621)
		(end -61.067465 30.2768)
		(width 0.10668)
		(layer "B.Cu")
		(net "ETH10G_B2_TXN")
	)
	(arc
		(start -71.896117 35.898917)
		(mid -72.055523 36.005429)
		(end -72.243556 36.042831)
		(width 0.10668)
		(layer "B.Cu")
		(net "ETH10G_B2_TXN")
	)
	(arc
		(start -70.4904 33.7566)
		(mid -70.625766 34.43713)
		(end -71.011255 35.014055)
		(width 0.10668)
		(layer "B.Cu")
		(net "ETH10G_B2_TXN")
	)
	(arc
		(start -72.512982 36.042831)
		(mid -72.553807 36.03471)
		(end -72.588417 36.011584)
		(width 0.10668)
		(layer "B.Cu")
		(net "ETH10G_B2_TXN")
	)
	(segment
		(start -60.75 27.96)
		(end -60.75 26.479061)
		(width 0.1016)
		(layer "F.Cu")
		(net "ETH10G_B2_SDA")
	)
	(segment
		(start -76.011801 12.3952)
		(end -77.0128 12.3952)
		(width 0.1016)
		(layer "F.Cu")
		(net "ETH10G_B2_SDA")
	)
	(segment
		(start -60.75 26.479061)
		(end -60.762261 26.4668)
		(width 0.1016)
		(layer "F.Cu")
		(net "ETH10G_B2_SDA")
	)
	(via
		(at -70.6374 45.2628)
		(size 0.5588)
		(drill 0.254)
		(layers "F.Cu" "B.Cu")
		(net "ETH10G_B2_SDA")
	)
	(via
		(at -77.0128 12.3952)
		(size 0.5588)
		(drill 0.254)
		(layers "F.Cu" "B.Cu")
		(net "ETH10G_B2_SDA")
	)
	(via
		(at -60.762261 26.4668)
		(size 0.5588)
		(drill 0.254)
		(layers "F.Cu" "B.Cu")
		(net "ETH10G_B2_SDA")
	)
	(segment
		(start -76.2 42.000002)
		(end -77.040001 41.160002)
		(width 0.1016)
		(layer "B.Cu")
		(net "ETH10G_B2_SDA")
	)
	(segment
		(start -70.6374 45.6692)
		(end -71.5645 46.5963)
		(width 0.1016)
		(layer "B.Cu")
		(net "ETH10G_B2_SDA")
	)
	(segment
		(start -76.2 45.9232)
		(end -76.2 42.000002)
		(width 0.1016)
		(layer "B.Cu")
		(net "ETH10G_B2_SDA")
	)
	(segment
		(start -75.5269 46.5963)
		(end -76.2 45.9232)
		(width 0.1016)
		(layer "B.Cu")
		(net "ETH10G_B2_SDA")
	)
	(segment
		(start -70.6374 45.2628)
		(end -70.6374 45.6692)
		(width 0.1016)
		(layer "B.Cu")
		(net "ETH10G_B2_SDA")
	)
	(segment
		(start -71.5645 46.5963)
		(end -75.5269 46.5963)
		(width 0.1016)
		(layer "B.Cu")
		(net "ETH10G_B2_SDA")
	)
	(segment
		(start -70.6374 45.2628)
		(end -70.6374 32.9184)
		(width 0.12954)
		(layer "In2.Cu")
		(net "ETH10G_B2_SDA")
	)
	(segment
		(start -67.2846 29.5656)
		(end -62.235461 29.5656)
		(width 0.12954)
		(layer "In2.Cu")
		(net "ETH10G_B2_SDA")
	)
	(segment
		(start -70.6374 32.9184)
		(end -67.2846 29.5656)
		(width 0.12954)
		(layer "In2.Cu")
		(net "ETH10G_B2_SDA")
	)
	(segment
		(start -62.235461 29.5656)
		(end -60.762261 28.0924)
		(width 0.12954)
		(layer "In2.Cu")
		(net "ETH10G_B2_SDA")
	)
	(segment
		(start -60.762261 28.0924)
		(end -60.762261 26.4668)
		(width 0.12954)
		(layer "In2.Cu")
		(net "ETH10G_B2_SDA")
	)
	(segment
		(start -70.6374 33.13176)
		(end -70.6374 37.27704)
		(width 0.12954)
		(layer "In5.Cu")
		(net "ETH10G_B2_SDA")
	)
	(segment
		(start -71.227843 17.278457)
		(end -71.227843 18.357957)
		(width 0.12954)
		(layer "In5.Cu")
		(net "ETH10G_B2_SDA")
	)
	(segment
		(start -70.6374 37.27704)
		(end -70.07098 37.84346)
		(width 0.12954)
		(layer "In5.Cu")
		(net "ETH10G_B2_SDA")
	)
	(segment
		(start -67.1068 29.60116)
		(end -70.6374 33.13176)
		(width 0.12954)
		(layer "In5.Cu")
		(net "ETH10G_B2_SDA")
	)
	(segment
		(start -67.1068 22.479)
		(end -67.1068 29.60116)
		(width 0.12954)
		(layer "In5.Cu")
		(net "ETH10G_B2_SDA")
	)
	(segment
		(start -76.1111 12.3952)
		(end -71.227843 17.278457)
		(width 0.12954)
		(layer "In5.Cu")
		(net "ETH10G_B2_SDA")
	)
	(segment
		(start -70.07098 37.84346)
		(end -70.07098 43.89534)
		(width 0.12954)
		(layer "In5.Cu")
		(net "ETH10G_B2_SDA")
	)
	(segment
		(start -77.0128 12.3952)
		(end -76.1111 12.3952)
		(width 0.12954)
		(layer "In5.Cu")
		(net "ETH10G_B2_SDA")
	)
	(segment
		(start -71.227843 18.357957)
		(end -67.1068 22.479)
		(width 0.12954)
		(layer "In5.Cu")
		(net "ETH10G_B2_SDA")
	)
	(arc
		(start -70.07098 43.89534)
		(mid -70.218188 44.635404)
		(end -70.6374 45.2628)
		(width 0.12954)
		(layer "In5.Cu")
		(net "ETH10G_B2_SDA")
	)
	(segment
		(start -76.011801 10.9982)
		(end -77.0128 10.9982)
		(width 0.1016)
		(layer "F.Cu")
		(net "ETH10G_B2_SCL")
	)
	(segment
		(start -61.550001 27.96)
		(end -61.550001 25.8064)
		(width 0.1016)
		(layer "F.Cu")
		(net "ETH10G_B2_SCL")
	)
	(via
		(at -69.6976 45.2628)
		(size 0.5588)
		(drill 0.254)
		(layers "F.Cu" "B.Cu")
		(net "ETH10G_B2_SCL")
	)
	(via
		(at -77.0128 10.9982)
		(size 0.5588)
		(drill 0.254)
		(layers "F.Cu" "B.Cu")
		(net "ETH10G_B2_SCL")
	)
	(via
		(at -61.550001 25.8064)
		(size 0.5588)
		(drill 0.254)
		(layers "F.Cu" "B.Cu")
		(net "ETH10G_B2_SCL")
	)
	(segment
		(start -69.6976 45.2374)
		(end -70.1548 44.7802)
		(width 0.1016)
		(layer "B.Cu")
		(net "ETH10G_B2_SCL")
	)
	(segment
		(start -75.8952 45.7962)
		(end -75.8952 40.904803)
		(width 0.1016)
		(layer "B.Cu")
		(net "ETH10G_B2_SCL")
	)
	(segment
		(start -70.8152 44.7802)
		(end -72.37222 46.33722)
		(width 0.1016)
		(layer "B.Cu")
		(net "ETH10G_B2_SCL")
	)
	(segment
		(start -75.8952 40.904803)
		(end -77.040001 39.760002)
		(width 0.1016)
		(layer "B.Cu")
		(net "ETH10G_B2_SCL")
	)
	(segment
		(start -70.1548 44.7802)
		(end -70.8152 44.7802)
		(width 0.1016)
		(layer "B.Cu")
		(net "ETH10G_B2_SCL")
	)
	(segment
		(start -72.37222 46.33722)
		(end -75.35418 46.33722)
		(width 0.1016)
		(layer "B.Cu")
		(net "ETH10G_B2_SCL")
	)
	(segment
		(start -75.35418 46.33722)
		(end -75.8952 45.7962)
		(width 0.1016)
		(layer "B.Cu")
		(net "ETH10G_B2_SCL")
	)
	(segment
		(start -69.6976 45.2628)
		(end -69.6976 45.2374)
		(width 0.1016)
		(layer "B.Cu")
		(net "ETH10G_B2_SCL")
	)
	(segment
		(start -71.7804 19.2786)
		(end -65.9384 25.1206)
		(width 0.12954)
		(layer "In2.Cu")
		(net "ETH10G_B2_SCL")
	)
	(segment
		(start -76.0857 10.9982)
		(end -71.7804 15.3035)
		(width 0.12954)
		(layer "In2.Cu")
		(net "ETH10G_B2_SCL")
	)
	(segment
		(start -77.0128 10.9982)
		(end -76.0857 10.9982)
		(width 0.12954)
		(layer "In2.Cu")
		(net "ETH10G_B2_SCL")
	)
	(segment
		(start -65.9384 25.1206)
		(end -65.9384 25.4762)
		(width 0.12954)
		(layer "In2.Cu")
		(net "ETH10G_B2_SCL")
	)
	(segment
		(start -65.9384 25.4762)
		(end -63.881 27.5336)
		(width 0.12954)
		(layer "In2.Cu")
		(net "ETH10G_B2_SCL")
	)
	(segment
		(start -63.881 27.5336)
		(end -61.849 27.5336)
		(width 0.12954)
		(layer "In2.Cu")
		(net "ETH10G_B2_SCL")
	)
	(segment
		(start -71.7804 15.3035)
		(end -71.7804 19.2786)
		(width 0.12954)
		(layer "In2.Cu")
		(net "ETH10G_B2_SCL")
	)
	(segment
		(start -61.550001 27.234601)
		(end -61.550001 25.8064)
		(width 0.12954)
		(layer "In2.Cu")
		(net "ETH10G_B2_SCL")
	)
	(segment
		(start -61.849 27.5336)
		(end -61.550001 27.234601)
		(width 0.12954)
		(layer "In2.Cu")
		(net "ETH10G_B2_SCL")
	)
	(segment
		(start -70.510466 17.195734)
		(end -70.510466 18.465734)
		(width 0.12954)
		(layer "In5.Cu")
		(net "ETH10G_B2_SCL")
	)
	(segment
		(start -66.4718 22.5044)
		(end -66.4718 29.57068)
		(width 0.12954)
		(layer "In5.Cu")
		(net "ETH10G_B2_SCL")
	)
	(segment
		(start -69.6976 37.62502)
		(end -69.6976 45.2628)
		(width 0.12954)
		(layer "In5.Cu")
		(net "ETH10G_B2_SCL")
	)
	(segment
		(start -66.4718 29.57068)
		(end -70.30212 33.401)
		(width 0.12954)
		(layer "In5.Cu")
		(net "ETH10G_B2_SCL")
	)
	(segment
		(start -70.30212 37.0205)
		(end -69.6976 37.62502)
		(width 0.12954)
		(layer "In5.Cu")
		(net "ETH10G_B2_SCL")
	)
	(segment
		(start -76.708 10.9982)
		(end -70.510466 17.195734)
		(width 0.12954)
		(layer "In5.Cu")
		(net "ETH10G_B2_SCL")
	)
	(segment
		(start -70.30212 33.401)
		(end -70.30212 37.0205)
		(width 0.12954)
		(layer "In5.Cu")
		(net "ETH10G_B2_SCL")
	)
	(segment
		(start -70.510466 18.465734)
		(end -66.4718 22.5044)
		(width 0.12954)
		(layer "In5.Cu")
		(net "ETH10G_B2_SCL")
	)
	(segment
		(start -77.0128 10.9982)
		(end -76.708 10.9982)
		(width 0.12954)
		(layer "In5.Cu")
		(net "ETH10G_B2_SCL")
	)
	(segment
		(start -63.950002 27.96)
		(end -63.950002 26.504859)
		(width 0.1016)
		(layer "F.Cu")
		(net "ETH10G_B2_RX_LOS")
	)
	(segment
		(start -78.2066 3.461601)
		(end -79.448797 3.461601)
		(width 0.1016)
		(layer "F.Cu")
		(net "ETH10G_B2_RX_LOS")
	)
	(segment
		(start -63.950002 26.504859)
		(end -63.955041 26.49982)
		(width 0.1016)
		(layer "F.Cu")
		(net "ETH10G_B2_RX_LOS")
	)
	(via
		(at -78.2066 3.461601)
		(size 0.5588)
		(drill 0.254)
		(layers "F.Cu" "B.Cu")
		(net "ETH10G_B2_RX_LOS")
	)
	(via
		(at -63.955041 26.49982)
		(size 0.5588)
		(drill 0.254)
		(layers "F.Cu" "B.Cu")
		(net "ETH10G_B2_RX_LOS")
	)
	(segment
		(start -75.2602 4.4704)
		(end -76.6826 3.048)
		(width 0.12954)
		(layer "In2.Cu")
		(net "ETH10G_B2_RX_LOS")
	)
	(segment
		(start -63.955041 25.788559)
		(end -70.739 19.0046)
		(width 0.12954)
		(layer "In2.Cu")
		(net "ETH10G_B2_RX_LOS")
	)
	(segment
		(start -75.2602 7.9756)
		(end -75.2602 4.4704)
		(width 0.12954)
		(layer "In2.Cu")
		(net "ETH10G_B2_RX_LOS")
	)
	(segment
		(start -70.739 12.4968)
		(end -75.2602 7.9756)
		(width 0.12954)
		(layer "In2.Cu")
		(net "ETH10G_B2_RX_LOS")
	)
	(segment
		(start -76.6826 3.048)
		(end -77.792999 3.048)
		(width 0.12954)
		(layer "In2.Cu")
		(net "ETH10G_B2_RX_LOS")
	)
	(segment
		(start -63.955041 26.49982)
		(end -63.955041 25.788559)
		(width 0.12954)
		(layer "In2.Cu")
		(net "ETH10G_B2_RX_LOS")
	)
	(segment
		(start -77.792999 3.048)
		(end -78.2066 3.461601)
		(width 0.12954)
		(layer "In2.Cu")
		(net "ETH10G_B2_RX_LOS")
	)
	(segment
		(start -70.739 19.0046)
		(end -70.739 12.4968)
		(width 0.12954)
		(layer "In2.Cu")
		(net "ETH10G_B2_RX_LOS")
	)
	(segment
		(start -63.732829 37.626389)
		(end -63.732829 38.959633)
		(width 0.10668)
		(layer "F.Cu")
		(net "ETH10G_B2_RXP")
	)
	(segment
		(start -63.55 36.159999)
		(end -63.55 37.44356)
		(width 0.10668)
		(layer "F.Cu")
		(net "ETH10G_B2_RXP")
	)
	(segment
		(start -63.55 37.44356)
		(end -63.732829 37.626389)
		(width 0.10668)
		(layer "F.Cu")
		(net "ETH10G_B2_RXP")
	)
	(via
		(at -63.543599 39.416474)
		(size 0.5588)
		(drill 0.254)
		(layers "F.Cu" "B.Cu")
		(net "ETH10G_B2_RXP")
	)
	(arc
		(start -63.732829 38.959633)
		(mid -63.68365 39.206874)
		(end -63.543599 39.416474)
		(width 0.10668)
		(layer "F.Cu")
		(net "ETH10G_B2_RXP")
	)
	(segment
		(start -72.1922 40.677173)
		(end -72.512984 40.677173)
		(width 0.10668)
		(layer "B.Cu")
		(net "ETH10G_B2_RXP")
	)
	(segment
		(start -72.58842 40.70842)
		(end -73.040001 41.160002)
		(width 0.10668)
		(layer "B.Cu")
		(net "ETH10G_B2_RXP")
	)
	(segment
		(start -63.732829 39.873316)
		(end -63.732829 40.3098)
		(width 0.10668)
		(layer "B.Cu")
		(net "ETH10G_B2_RXP")
	)
	(segment
		(start -71.706527 40.972524)
		(end -71.867298 40.811752)
		(width 0.10668)
		(layer "B.Cu")
		(net "ETH10G_B2_RXP")
	)
	(segment
		(start -71.448171 41.230885)
		(end -71.706527 40.972524)
		(width 0.10668)
		(layer "B.Cu")
		(net "ETH10G_B2_RXP")
	)
	(segment
		(start -64.852969 41.42994)
		(end -70.9676 41.42994)
		(width 0.10668)
		(layer "B.Cu")
		(net "ETH10G_B2_RXP")
	)
	(arc
		(start -63.543599 39.416474)
		(mid -63.68365 39.626075)
		(end -63.732829 39.873316)
		(width 0.10668)
		(layer "B.Cu")
		(net "ETH10G_B2_RXP")
	)
	(arc
		(start -70.9676 41.42994)
		(mid -71.227683 41.378208)
		(end -71.448171 41.230885)
		(width 0.10668)
		(layer "B.Cu")
		(net "ETH10G_B2_RXP")
	)
	(arc
		(start -72.512984 40.677173)
		(mid -72.55381 40.685294)
		(end -72.58842 40.70842)
		(width 0.10668)
		(layer "B.Cu")
		(net "ETH10G_B2_RXP")
	)
	(arc
		(start -71.867298 40.811752)
		(mid -72.016364 40.712148)
		(end -72.1922 40.677173)
		(width 0.10668)
		(layer "B.Cu")
		(net "ETH10G_B2_RXP")
	)
	(arc
		(start -63.732829 40.3098)
		(mid -64.06091 41.101859)
		(end -64.852969 41.42994)
		(width 0.10668)
		(layer "B.Cu")
		(net "ETH10G_B2_RXP")
	)
	(segment
		(start -64.167169 37.638891)
		(end -64.167169 38.959633)
		(width 0.10668)
		(layer "F.Cu")
		(net "ETH10G_B2_RXN")
	)
	(segment
		(start -64.350001 36.159999)
		(end -64.350001 37.456059)
		(width 0.10668)
		(layer "F.Cu")
		(net "ETH10G_B2_RXN")
	)
	(segment
		(start -64.350001 37.456059)
		(end -64.167169 37.638891)
		(width 0.10668)
		(layer "F.Cu")
		(net "ETH10G_B2_RXN")
	)
	(via
		(at -64.356399 39.416474)
		(size 0.5588)
		(drill 0.254)
		(layers "F.Cu" "B.Cu")
		(net "ETH10G_B2_RXN")
	)
	(arc
		(start -64.167169 38.959633)
		(mid -64.216348 39.206874)
		(end -64.356399 39.416474)
		(width 0.10668)
		(layer "F.Cu")
		(net "ETH10G_B2_RXN")
	)
	(segment
		(start -69.14928 40.68572)
		(end -69.36772 40.68572)
		(width 0.10668)
		(layer "B.Cu")
		(net "ETH10G_B2_RXN")
	)
	(segment
		(start -69.6776 40.9956)
		(end -70.9676 40.9956)
		(width 0.10668)
		(layer "B.Cu")
		(net "ETH10G_B2_RXN")
	)
	(segment
		(start -64.852969 40.9956)
		(end -66.5534 40.9956)
		(width 0.10668)
		(layer "B.Cu")
		(net "ETH10G_B2_RXN")
	)
	(segment
		(start -66.8328 40.7162)
		(end -67.1122 40.7162)
		(width 0.10668)
		(layer "B.Cu")
		(net "ETH10G_B2_RXN")
	)
	(segment
		(start -64.167169 39.873316)
		(end -64.167169 40.3098)
		(width 0.10668)
		(layer "B.Cu")
		(net "ETH10G_B2_RXN")
	)
	(segment
		(start -71.141044 40.923759)
		(end -71.3994 40.6654)
		(width 0.10668)
		(layer "B.Cu")
		(net "ETH10G_B2_RXN")
	)
	(segment
		(start -72.588417 40.211586)
		(end -73.040001 39.760002)
		(width 0.10668)
		(layer "B.Cu")
		(net "ETH10G_B2_RXN")
	)
	(segment
		(start -71.3994 40.6654)
		(end -71.560174 40.504626)
		(width 0.10668)
		(layer "B.Cu")
		(net "ETH10G_B2_RXN")
	)
	(segment
		(start -67.3916 40.9956)
		(end -68.8394 40.9956)
		(width 0.10668)
		(layer "B.Cu")
		(net "ETH10G_B2_RXN")
	)
	(segment
		(start -72.1922 40.242833)
		(end -72.512982 40.242833)
		(width 0.10668)
		(layer "B.Cu")
		(net "ETH10G_B2_RXN")
	)
	(arc
		(start -66.655 40.894)
		(mid -66.707076 40.768276)
		(end -66.8328 40.7162)
		(width 0.10668)
		(layer "B.Cu")
		(net "ETH10G_B2_RXN")
	)
	(arc
		(start -72.512982 40.242833)
		(mid -72.553807 40.234712)
		(end -72.588417 40.211586)
		(width 0.10668)
		(layer "B.Cu")
		(net "ETH10G_B2_RXN")
	)
	(arc
		(start -64.167169 40.3098)
		(mid -64.368035 40.794734)
		(end -64.852969 40.9956)
		(width 0.10668)
		(layer "B.Cu")
		(net "ETH10G_B2_RXN")
	)
	(arc
		(start -68.8394 40.9956)
		(mid -68.911242 40.965842)
		(end -68.941 40.894)
		(width 0.10668)
		(layer "B.Cu")
		(net "ETH10G_B2_RXN")
	)
	(arc
		(start -67.29 40.894)
		(mid -67.319758 40.965842)
		(end -67.3916 40.9956)
		(width 0.10668)
		(layer "B.Cu")
		(net "ETH10G_B2_RXN")
	)
	(arc
		(start -69.36772 40.68572)
		(mid -69.514996 40.746724)
		(end -69.576 40.894)
		(width 0.10668)
		(layer "B.Cu")
		(net "ETH10G_B2_RXN")
	)
	(arc
		(start -64.356399 39.416474)
		(mid -64.216348 39.626075)
		(end -64.167169 39.873316)
		(width 0.10668)
		(layer "B.Cu")
		(net "ETH10G_B2_RXN")
	)
	(arc
		(start -67.1122 40.7162)
		(mid -67.237924 40.768276)
		(end -67.29 40.894)
		(width 0.10668)
		(layer "B.Cu")
		(net "ETH10G_B2_RXN")
	)
	(arc
		(start -71.560174 40.504626)
		(mid -71.85015 40.310871)
		(end -72.1922 40.242833)
		(width 0.10668)
		(layer "B.Cu")
		(net "ETH10G_B2_RXN")
	)
	(arc
		(start -66.5534 40.9956)
		(mid -66.625242 40.965842)
		(end -66.655 40.894)
		(width 0.10668)
		(layer "B.Cu")
		(net "ETH10G_B2_RXN")
	)
	(arc
		(start -69.576 40.894)
		(mid -69.605758 40.965842)
		(end -69.6776 40.9956)
		(width 0.10668)
		(layer "B.Cu")
		(net "ETH10G_B2_RXN")
	)
	(arc
		(start -68.941 40.894)
		(mid -69.002004 40.746724)
		(end -69.14928 40.68572)
		(width 0.10668)
		(layer "B.Cu")
		(net "ETH10G_B2_RXN")
	)
	(arc
		(start -70.9676 40.9956)
		(mid -71.061467 40.97693)
		(end -71.141044 40.923759)
		(width 0.10668)
		(layer "B.Cu")
		(net "ETH10G_B2_RXN")
	)
	(segment
		(start -75.9792 2.476398)
		(end -75.9792 3.873398)
		(width 0.1016)
		(layer "F.Cu")
		(net "ETH10G_B2_RS1")
	)
	(segment
		(start -64.75 25.8318)
		(end -64.75 27.96)
		(width 0.1016)
		(layer "F.Cu")
		(net "ETH10G_B2_RS1")
	)
	(segment
		(start -76.822402 3.873398)
		(end -75.9792 3.873398)
		(width 0.1016)
		(layer "F.Cu")
		(net "ETH10G_B2_RS1")
	)
	(segment
		(start -76.835 3.8608)
		(end -76.822402 3.873398)
		(width 0.1016)
		(layer "F.Cu")
		(net "ETH10G_B2_RS1")
	)
	(via
		(at -76.835 3.8608)
		(size 0.5588)
		(drill 0.254)
		(layers "F.Cu" "B.Cu")
		(net "ETH10G_B2_RS1")
	)
	(via
		(at -64.75 25.8318)
		(size 0.5588)
		(drill 0.254)
		(layers "F.Cu" "B.Cu")
		(net "ETH10G_B2_RS1")
	)
	(segment
		(start -71.0692 12.827)
		(end -71.0692 19.4364)
		(width 0.12954)
		(layer "In2.Cu")
		(net "ETH10G_B2_RS1")
	)
	(segment
		(start -76.835 3.8608)
		(end -75.819 4.8768)
		(width 0.12954)
		(layer "In2.Cu")
		(net "ETH10G_B2_RS1")
	)
	(segment
		(start -64.75 25.7556)
		(end -64.75 25.8318)
		(width 0.12954)
		(layer "In2.Cu")
		(net "ETH10G_B2_RS1")
	)
	(segment
		(start -75.819 4.8768)
		(end -75.819 8.0772)
		(width 0.12954)
		(layer "In2.Cu")
		(net "ETH10G_B2_RS1")
	)
	(segment
		(start -71.0692 19.4364)
		(end -64.75 25.7556)
		(width 0.12954)
		(layer "In2.Cu")
		(net "ETH10G_B2_RS1")
	)
	(segment
		(start -75.819 8.0772)
		(end -71.0692 12.827)
		(width 0.12954)
		(layer "In2.Cu")
		(net "ETH10G_B2_RS1")
	)
	(segment
		(start -63.150001 25.8469)
		(end -63.150001 27.96)
		(width 0.1016)
		(layer "F.Cu")
		(net "ETH10G_B2_RS0")
	)
	(segment
		(start -74.711799 9.652)
		(end -74.711799 8.255)
		(width 0.1016)
		(layer "F.Cu")
		(net "ETH10G_B2_RS0")
	)
	(segment
		(start -74.711799 8.255)
		(end -73.533 8.255)
		(width 0.1016)
		(layer "F.Cu")
		(net "ETH10G_B2_RS0")
	)
	(via
		(at -73.533 8.255)
		(size 0.5588)
		(drill 0.254)
		(layers "F.Cu" "B.Cu")
		(net "ETH10G_B2_RS0")
	)
	(via
		(at -63.150001 25.8469)
		(size 0.5588)
		(drill 0.254)
		(layers "F.Cu" "B.Cu")
		(net "ETH10G_B2_RS0")
	)
	(segment
		(start -73.533 8.255)
		(end -64.242 17.546)
		(width 0.12954)
		(layer "In2.Cu")
		(net "ETH10G_B2_RS0")
	)
	(segment
		(start -63.150001 24.663199)
		(end -63.150001 25.8469)
		(width 0.12954)
		(layer "In2.Cu")
		(net "ETH10G_B2_RS0")
	)
	(segment
		(start -64.242 23.5712)
		(end -63.150001 24.663199)
		(width 0.12954)
		(layer "In2.Cu")
		(net "ETH10G_B2_RS0")
	)
	(segment
		(start -64.242 17.546)
		(end -64.242 23.5712)
		(width 0.12954)
		(layer "In2.Cu")
		(net "ETH10G_B2_RS0")
	)
	(segment
		(start -80.736201 1.8542)
		(end -81.7372 1.8542)
		(width 0.1016)
		(layer "F.Cu")
		(net "ETH10G_B2_PRES_N")
	)
	(via
		(at -81.7372 1.8542)
		(size 0.5588)
		(drill 0.254)
		(layers "F.Cu" "B.Cu")
		(net "ETH10G_B2_PRES_N")
	)
	(segment
		(start -80.0354 3.556)
		(end -81.7372 1.8542)
		(width 0.12954)
		(layer "In2.Cu")
		(net "ETH10G_B2_PRES_N")
	)
	(segment
		(start -77.5462 11.2776)
		(end -77.5462 6.0198)
		(width 0.12954)
		(layer "In2.Cu")
		(net "ETH10G_B2_PRES_N")
	)
	(segment
		(start -80.01 3.556)
		(end -80.0354 3.556)
		(width 0.12954)
		(layer "In2.Cu")
		(net "ETH10G_B2_PRES_N")
	)
	(segment
		(start -72.1868 24.0538)
		(end -72.1868 15.5956)
		(width 0.12954)
		(layer "In2.Cu")
		(net "ETH10G_B2_PRES_N")
	)
	(segment
		(start -75.8444 33.455602)
		(end -75.8444 32.4104)
		(width 0.12954)
		(layer "In2.Cu")
		(net "ETH10G_B2_PRES_N")
	)
	(segment
		(start -77.5462 6.0198)
		(end -80.01 3.556)
		(width 0.12954)
		(layer "In2.Cu")
		(net "ETH10G_B2_PRES_N")
	)
	(segment
		(start -73.7108 30.2768)
		(end -73.7108 25.5778)
		(width 0.12954)
		(layer "In2.Cu")
		(net "ETH10G_B2_PRES_N")
	)
	(segment
		(start -75.8444 32.4104)
		(end -73.7108 30.2768)
		(width 0.12954)
		(layer "In2.Cu")
		(net "ETH10G_B2_PRES_N")
	)
	(segment
		(start -75.040002 34.26)
		(end -75.8444 33.455602)
		(width 0.12954)
		(layer "In2.Cu")
		(net "ETH10G_B2_PRES_N")
	)
	(segment
		(start -77.2922 11.5316)
		(end -77.5462 11.2776)
		(width 0.12954)
		(layer "In2.Cu")
		(net "ETH10G_B2_PRES_N")
	)
	(segment
		(start -73.7108 25.5778)
		(end -72.1868 24.0538)
		(width 0.12954)
		(layer "In2.Cu")
		(net "ETH10G_B2_PRES_N")
	)
	(segment
		(start -72.1868 15.5956)
		(end -76.2508 11.5316)
		(width 0.12954)
		(layer "In2.Cu")
		(net "ETH10G_B2_PRES_N")
	)
	(segment
		(start -76.2508 11.5316)
		(end -77.2922 11.5316)
		(width 0.12954)
		(layer "In2.Cu")
		(net "ETH10G_B2_PRES_N")
	)
	(segment
		(start -79.436199 1.8542)
		(end -78.4606 1.8542)
		(width 0.1016)
		(layer "F.Cu")
		(net "ETH10G_B2_MOD_ABS")
	)
	(segment
		(start -78.4606 1.8542)
		(end -78.4352 1.8796)
		(width 0.1016)
		(layer "F.Cu")
		(net "ETH10G_B2_MOD_ABS")
	)
	(segment
		(start -79.436199 1.8542)
		(end -79.436199 0.381)
		(width 0.1016)
		(layer "F.Cu")
		(net "ETH10G_B2_MOD_ABS")
	)
	(segment
		(start -62.35 27.96)
		(end -62.35 26.492439)
		(width 0.1016)
		(layer "F.Cu")
		(net "ETH10G_B2_MOD_ABS")
	)
	(segment
		(start -62.35 26.492439)
		(end -62.334521 26.47696)
		(width 0.1016)
		(layer "F.Cu")
		(net "ETH10G_B2_MOD_ABS")
	)
	(via
		(at -78.4352 1.8796)
		(size 0.5588)
		(drill 0.254)
		(layers "F.Cu" "B.Cu")
		(net "ETH10G_B2_MOD_ABS")
	)
	(via
		(at -62.334521 26.47696)
		(size 0.5588)
		(drill 0.254)
		(layers "F.Cu" "B.Cu")
		(net "ETH10G_B2_MOD_ABS")
	)
	(segment
		(start -63.8556 23.1013)
		(end -63.8429 23.114)
		(width 0.12954)
		(layer "In2.Cu")
		(net "ETH10G_B2_MOD_ABS")
	)
	(segment
		(start -77.1906 1.9558)
		(end -74.6506 4.4958)
		(width 0.12954)
		(layer "In2.Cu")
		(net "ETH10G_B2_MOD_ABS")
	)
	(segment
		(start -78.359 1.9558)
		(end -77.1906 1.9558)
		(width 0.12954)
		(layer "In2.Cu")
		(net "ETH10G_B2_MOD_ABS")
	)
	(segment
		(start -63.8556 16.7132)
		(end -63.8556 23.1013)
		(width 0.12954)
		(layer "In2.Cu")
		(net "ETH10G_B2_MOD_ABS")
	)
	(segment
		(start -62.334521 24.609679)
		(end -62.334521 26.47696)
		(width 0.12954)
		(layer "In2.Cu")
		(net "ETH10G_B2_MOD_ABS")
	)
	(segment
		(start -74.6506 4.4958)
		(end -74.6506 6.858)
		(width 0.12954)
		(layer "In2.Cu")
		(net "ETH10G_B2_MOD_ABS")
	)
	(segment
		(start -78.4352 1.8796)
		(end -78.359 1.9558)
		(width 0.12954)
		(layer "In2.Cu")
		(net "ETH10G_B2_MOD_ABS")
	)
	(segment
		(start -74.040855 7.467745)
		(end -73.101055 7.467745)
		(width 0.12954)
		(layer "In2.Cu")
		(net "ETH10G_B2_MOD_ABS")
	)
	(segment
		(start -73.101055 7.467745)
		(end -63.8556 16.7132)
		(width 0.12954)
		(layer "In2.Cu")
		(net "ETH10G_B2_MOD_ABS")
	)
	(segment
		(start -74.6506 6.858)
		(end -74.040855 7.467745)
		(width 0.12954)
		(layer "In2.Cu")
		(net "ETH10G_B2_MOD_ABS")
	)
	(segment
		(start -63.8302 23.114)
		(end -62.334521 24.609679)
		(width 0.12954)
		(layer "In2.Cu")
		(net "ETH10G_B2_MOD_ABS")
	)
	(segment
		(start -63.8429 23.114)
		(end -63.8302 23.114)
		(width 0.12954)
		(layer "In2.Cu")
		(net "ETH10G_B2_MOD_ABS")
	)
	(segment
		(start -295.4958 1.460602)
		(end -294.5638 1.460602)
		(width 0.1016)
		(layer "F.Cu")
		(net "ETH10G_B1_TX_FAULT")
	)
	(segment
		(start -280.150001 26.4668)
		(end -280.150001 27.96)
		(width 0.1016)
		(layer "F.Cu")
		(net "ETH10G_B1_TX_FAULT")
	)
	(segment
		(start -295.4958 1.384402)
		(end -295.4958 1.460602)
		(width 0.1016)
		(layer "F.Cu")
		(net "ETH10G_B1_TX_FAULT")
	)
	(via
		(at -294.5638 1.460602)
		(size 0.5588)
		(drill 0.254)
		(layers "F.Cu" "B.Cu")
		(net "ETH10G_B1_TX_FAULT")
	)
	(via
		(at -280.150001 26.4668)
		(size 0.5588)
		(drill 0.254)
		(layers "F.Cu" "B.Cu")
		(net "ETH10G_B1_TX_FAULT")
	)
	(segment
		(start -282.8798 23.2156)
		(end -280.150001 25.945399)
		(width 0.12954)
		(layer "In2.Cu")
		(net "ETH10G_B1_TX_FAULT")
	)
	(segment
		(start -280.150001 25.945399)
		(end -280.150001 26.4668)
		(width 0.12954)
		(layer "In2.Cu")
		(net "ETH10G_B1_TX_FAULT")
	)
	(segment
		(start -293.624 6.223)
		(end -282.8798 16.9672)
		(width 0.12954)
		(layer "In2.Cu")
		(net "ETH10G_B1_TX_FAULT")
	)
	(segment
		(start -282.8798 16.9672)
		(end -282.8798 23.2156)
		(width 0.12954)
		(layer "In2.Cu")
		(net "ETH10G_B1_TX_FAULT")
	)
	(segment
		(start -294.5638 1.460602)
		(end -293.624 2.400402)
		(width 0.12954)
		(layer "In2.Cu")
		(net "ETH10G_B1_TX_FAULT")
	)
	(segment
		(start -293.624 2.400402)
		(end -293.624 6.223)
		(width 0.12954)
		(layer "In2.Cu")
		(net "ETH10G_B1_TX_FAULT")
	)
	(segment
		(start -294.3098 4.127602)
		(end -295.4958 4.127602)
		(width 0.1016)
		(layer "F.Cu")
		(net "ETH10G_B1_TX_DIS")
	)
	(segment
		(start -280.950002 25.9334)
		(end -280.950002 27.96)
		(width 0.1016)
		(layer "F.Cu")
		(net "ETH10G_B1_TX_DIS")
	)
	(segment
		(start -295.4958 4.127602)
		(end -295.4958 2.730602)
		(width 0.1016)
		(layer "F.Cu")
		(net "ETH10G_B1_TX_DIS")
	)
	(via
		(at -294.3098 4.127602)
		(size 0.5588)
		(drill 0.254)
		(layers "F.Cu" "B.Cu")
		(net "ETH10G_B1_TX_DIS")
	)
	(via
		(at -280.950002 25.9334)
		(size 0.5588)
		(drill 0.254)
		(layers "F.Cu" "B.Cu")
		(net "ETH10G_B1_TX_DIS")
	)
	(segment
		(start -294.3098 6.2992)
		(end -292.354 8.255)
		(width 0.12954)
		(layer "In2.Cu")
		(net "ETH10G_B1_TX_DIS")
	)
	(segment
		(start -283.3878 23.4442)
		(end -280.950002 25.881998)
		(width 0.12954)
		(layer "In2.Cu")
		(net "ETH10G_B1_TX_DIS")
	)
	(segment
		(start -283.3878 17.2466)
		(end -283.3878 23.4442)
		(width 0.12954)
		(layer "In2.Cu")
		(net "ETH10G_B1_TX_DIS")
	)
	(segment
		(start -292.354 8.2804)
		(end -283.3878 17.2466)
		(width 0.12954)
		(layer "In2.Cu")
		(net "ETH10G_B1_TX_DIS")
	)
	(segment
		(start -292.354 8.255)
		(end -292.354 8.2804)
		(width 0.12954)
		(layer "In2.Cu")
		(net "ETH10G_B1_TX_DIS")
	)
	(segment
		(start -294.3098 4.127602)
		(end -294.3098 6.2992)
		(width 0.12954)
		(layer "In2.Cu")
		(net "ETH10G_B1_TX_DIS")
	)
	(segment
		(start -280.950002 25.881998)
		(end -280.950002 25.9334)
		(width 0.12954)
		(layer "In2.Cu")
		(net "ETH10G_B1_TX_DIS")
	)
	(segment
		(start -280.66238 30.71114)
		(end -281.153781 30.71114)
		(width 0.10668)
		(layer "F.Cu")
		(net "ETH10G_B1_TXP")
	)
	(segment
		(start -280.55 34.8812)
		(end -280.36774 34.69894)
		(width 0.10668)
		(layer "F.Cu")
		(net "ETH10G_B1_TXP")
	)
	(segment
		(start -280.36774 34.69894)
		(end -280.36774 31.00578)
		(width 0.10668)
		(layer "F.Cu")
		(net "ETH10G_B1_TXP")
	)
	(segment
		(start -280.55 36.159999)
		(end -280.55 34.8812)
		(width 0.10668)
		(layer "F.Cu")
		(net "ETH10G_B1_TXP")
	)
	(via
		(at -281.610623 30.90037)
		(size 0.5588)
		(drill 0.254)
		(layers "F.Cu" "B.Cu")
		(net "ETH10G_B1_TXP")
	)
	(arc
		(start -280.36774 31.00578)
		(mid -280.454038 30.797438)
		(end -280.66238 30.71114)
		(width 0.10668)
		(layer "F.Cu")
		(net "ETH10G_B1_TXP")
	)
	(arc
		(start -281.153781 30.71114)
		(mid -281.401022 30.760319)
		(end -281.610623 30.90037)
		(width 0.10668)
		(layer "F.Cu")
		(net "ETH10G_B1_TXP")
	)
	(segment
		(start -284.861 30.83814)
		(end -284.861 30.861)
		(width 0.10668)
		(layer "B.Cu")
		(net "ETH10G_B1_TXP")
	)
	(segment
		(start -293.243559 36.477171)
		(end -293.512984 36.477171)
		(width 0.10668)
		(layer "B.Cu")
		(net "ETH10G_B1_TXP")
	)
	(segment
		(start -283.464 30.71114)
		(end -284.734 30.71114)
		(width 0.10668)
		(layer "B.Cu")
		(net "ETH10G_B1_TXP")
	)
	(segment
		(start -291.704128 35.321182)
		(end -292.588991 36.206044)
		(width 0.10668)
		(layer "B.Cu")
		(net "ETH10G_B1_TXP")
	)
	(segment
		(start -291.05606 33.7566)
		(end -291.05606 33.756603)
		(width 0.10668)
		(layer "B.Cu")
		(net "ETH10G_B1_TXP")
	)
	(segment
		(start -283.337 30.861)
		(end -283.337 30.83814)
		(width 0.10668)
		(layer "B.Cu")
		(net "ETH10G_B1_TXP")
	)
	(segment
		(start -282.064018 30.712567)
		(end -282.57279 30.712567)
		(width 0.10668)
		(layer "B.Cu")
		(net "ETH10G_B1_TXP")
	)
	(segment
		(start -285.496 30.861)
		(end -285.496 30.8556)
		(width 0.10668)
		(layer "B.Cu")
		(net "ETH10G_B1_TXP")
	)
	(segment
		(start -282.83408 30.99308)
		(end -283.20492 30.99308)
		(width 0.10668)
		(layer "B.Cu")
		(net "ETH10G_B1_TXP")
	)
	(segment
		(start -285.0134 31.0134)
		(end -285.3436 31.0134)
		(width 0.10668)
		(layer "B.Cu")
		(net "ETH10G_B1_TXP")
	)
	(segment
		(start -285.64046 30.71114)
		(end -288.0106 30.71114)
		(width 0.10668)
		(layer "B.Cu")
		(net "ETH10G_B1_TXP")
	)
	(segment
		(start -293.58842 36.508418)
		(end -294.040001 36.96)
		(width 0.10668)
		(layer "B.Cu")
		(net "ETH10G_B1_TXP")
	)
	(arc
		(start -282.702 30.861)
		(mid -282.740685 30.954395)
		(end -282.83408 30.99308)
		(width 0.10668)
		(layer "B.Cu")
		(net "ETH10G_B1_TXP")
	)
	(arc
		(start -283.20492 30.99308)
		(mid -283.298315 30.954395)
		(end -283.337 30.861)
		(width 0.10668)
		(layer "B.Cu")
		(net "ETH10G_B1_TXP")
	)
	(arc
		(start -284.734 30.71114)
		(mid -284.823803 30.748337)
		(end -284.861 30.83814)
		(width 0.10668)
		(layer "B.Cu")
		(net "ETH10G_B1_TXP")
	)
	(arc
		(start -284.861 30.861)
		(mid -284.905637 30.968763)
		(end -285.0134 31.0134)
		(width 0.10668)
		(layer "B.Cu")
		(net "ETH10G_B1_TXP")
	)
	(arc
		(start -283.337 30.83814)
		(mid -283.374197 30.748337)
		(end -283.464 30.71114)
		(width 0.10668)
		(layer "B.Cu")
		(net "ETH10G_B1_TXP")
	)
	(arc
		(start -285.496 30.8556)
		(mid -285.538311 30.753451)
		(end -285.64046 30.71114)
		(width 0.10668)
		(layer "B.Cu")
		(net "ETH10G_B1_TXP")
	)
	(arc
		(start -292.588991 36.206044)
		(mid -292.88931 36.406709)
		(end -293.243559 36.477171)
		(width 0.10668)
		(layer "B.Cu")
		(net "ETH10G_B1_TXP")
	)
	(arc
		(start -281.610623 30.90037)
		(mid -281.818642 30.761376)
		(end -282.064018 30.712567)
		(width 0.10668)
		(layer "B.Cu")
		(net "ETH10G_B1_TXP")
	)
	(arc
		(start -293.512984 36.477171)
		(mid -293.55381 36.485292)
		(end -293.58842 36.508418)
		(width 0.10668)
		(layer "B.Cu")
		(net "ETH10G_B1_TXP")
	)
	(arc
		(start -288.0106 30.71114)
		(mid -290.164065 31.603135)
		(end -291.05606 33.7566)
		(width 0.10668)
		(layer "B.Cu")
		(net "ETH10G_B1_TXP")
	)
	(arc
		(start -282.57279 30.712567)
		(mid -282.665172 30.762603)
		(end -282.702 30.861)
		(width 0.10668)
		(layer "B.Cu")
		(net "ETH10G_B1_TXP")
	)
	(arc
		(start -285.3436 31.0134)
		(mid -285.451363 30.968763)
		(end -285.496 30.861)
		(width 0.10668)
		(layer "B.Cu")
		(net "ETH10G_B1_TXP")
	)
	(arc
		(start -291.05606 33.756603)
		(mid -291.224488 34.603347)
		(end -291.704128 35.321182)
		(width 0.10668)
		(layer "B.Cu")
		(net "ETH10G_B1_TXP")
	)
	(segment
		(start -279.9334 34.70656)
		(end -279.9334 31.00578)
		(width 0.10668)
		(layer "F.Cu")
		(net "ETH10G_B1_TXN")
	)
	(segment
		(start -280.66238 30.2768)
		(end -281.153781 30.2768)
		(width 0.10668)
		(layer "F.Cu")
		(net "ETH10G_B1_TXN")
	)
	(segment
		(start -279.750002 34.889958)
		(end -279.9334 34.70656)
		(width 0.10668)
		(layer "F.Cu")
		(net "ETH10G_B1_TXN")
	)
	(segment
		(start -279.750002 36.159999)
		(end -279.750002 34.889958)
		(width 0.10668)
		(layer "F.Cu")
		(net "ETH10G_B1_TXN")
	)
	(via
		(at -281.610623 30.08757)
		(size 0.5588)
		(drill 0.254)
		(layers "F.Cu" "B.Cu")
		(net "ETH10G_B1_TXN")
	)
	(arc
		(start -281.153781 30.2768)
		(mid -281.401022 30.227621)
		(end -281.610623 30.08757)
		(width 0.10668)
		(layer "F.Cu")
		(net "ETH10G_B1_TXN")
	)
	(arc
		(start -279.9334 31.00578)
		(mid -280.146913 30.490313)
		(end -280.66238 30.2768)
		(width 0.10668)
		(layer "F.Cu")
		(net "ETH10G_B1_TXN")
	)
	(segment
		(start -282.067465 30.2768)
		(end -288.0106 30.2768)
		(width 0.10668)
		(layer "B.Cu")
		(net "ETH10G_B1_TXN")
	)
	(segment
		(start -292.011255 35.014055)
		(end -292.896117 35.898917)
		(width 0.10668)
		(layer "B.Cu")
		(net "ETH10G_B1_TXN")
	)
	(segment
		(start -293.243556 36.042831)
		(end -293.512982 36.042831)
		(width 0.10668)
		(layer "B.Cu")
		(net "ETH10G_B1_TXN")
	)
	(segment
		(start -293.588417 36.011584)
		(end -294.040001 35.56)
		(width 0.10668)
		(layer "B.Cu")
		(net "ETH10G_B1_TXN")
	)
	(arc
		(start -291.4904 33.7566)
		(mid -291.625766 34.43713)
		(end -292.011255 35.014055)
		(width 0.10668)
		(layer "B.Cu")
		(net "ETH10G_B1_TXN")
	)
	(arc
		(start -293.512982 36.042831)
		(mid -293.553807 36.03471)
		(end -293.588417 36.011584)
		(width 0.10668)
		(layer "B.Cu")
		(net "ETH10G_B1_TXN")
	)
	(arc
		(start -281.610623 30.08757)
		(mid -281.820224 30.227621)
		(end -282.067465 30.2768)
		(width 0.10668)
		(layer "B.Cu")
		(net "ETH10G_B1_TXN")
	)
	(arc
		(start -288.0106 30.2768)
		(mid -290.47119 31.29601)
		(end -291.4904 33.7566)
		(width 0.10668)
		(layer "B.Cu")
		(net "ETH10G_B1_TXN")
	)
	(arc
		(start -292.896117 35.898917)
		(mid -293.055523 36.005429)
		(end -293.243556 36.042831)
		(width 0.10668)
		(layer "B.Cu")
		(net "ETH10G_B1_TXN")
	)
	(segment
		(start -297.3578 12.573)
		(end -296.814001 12.573)
		(width 0.1016)
		(layer "F.Cu")
		(net "ETH10G_B1_SDA")
	)
	(segment
		(start -297.9928 12.6238)
		(end -297.4086 12.6238)
		(width 0.1016)
		(layer "F.Cu")
		(net "ETH10G_B1_SDA")
	)
	(segment
		(start -281.75 26.479061)
		(end -281.762261 26.4668)
		(width 0.1016)
		(layer "F.Cu")
		(net "ETH10G_B1_SDA")
	)
	(segment
		(start -281.75 27.96)
		(end -281.75 26.479061)
		(width 0.1016)
		(layer "F.Cu")
		(net "ETH10G_B1_SDA")
	)
	(segment
		(start -297.4086 12.6238)
		(end -297.3578 12.573)
		(width 0.1016)
		(layer "F.Cu")
		(net "ETH10G_B1_SDA")
	)
	(via
		(at -297.9928 12.6238)
		(size 0.5588)
		(drill 0.254)
		(layers "F.Cu" "B.Cu")
		(net "ETH10G_B1_SDA")
	)
	(via
		(at -281.762261 26.4668)
		(size 0.5588)
		(drill 0.254)
		(layers "F.Cu" "B.Cu")
		(net "ETH10G_B1_SDA")
	)
	(segment
		(start -298.157202 41.160002)
		(end -298.040001 41.160002)
		(width 0.12954)
		(layer "In2.Cu")
		(net "ETH10G_B1_SDA")
	)
	(segment
		(start -298.577 33.528)
		(end -298.577 31.1658)
		(width 0.12954)
		(layer "In2.Cu")
		(net "ETH10G_B1_SDA")
	)
	(segment
		(start -299.0596 42.0624)
		(end -299.0596 45.9486)
		(width 0.12954)
		(layer "In2.Cu")
		(net "ETH10G_B1_SDA")
	)
	(segment
		(start -286.258 28.3718)
		(end -282.5496 28.3718)
		(width 0.12954)
		(layer "In2.Cu")
		(net "ETH10G_B1_SDA")
	)
	(segment
		(start -291.4142 33.528)
		(end -286.258 28.3718)
		(width 0.12954)
		(layer "In2.Cu")
		(net "ETH10G_B1_SDA")
	)
	(segment
		(start -297.4848 12.6238)
		(end -297.9928 12.6238)
		(width 0.12954)
		(layer "In2.Cu")
		(net "ETH10G_B1_SDA")
	)
	(segment
		(start -298.2468 46.7614)
		(end -292.505869 46.7614)
		(width 0.12954)
		(layer "In2.Cu")
		(net "ETH10G_B1_SDA")
	)
	(segment
		(start -282.5496 28.3718)
		(end -281.762261 27.584461)
		(width 0.12954)
		(layer "In2.Cu")
		(net "ETH10G_B1_SDA")
	)
	(segment
		(start -291.4142 45.669731)
		(end -291.4142 33.528)
		(width 0.12954)
		(layer "In2.Cu")
		(net "ETH10G_B1_SDA")
	)
	(segment
		(start -294.8178 24.0538)
		(end -294.8178 15.2908)
		(width 0.12954)
		(layer "In2.Cu")
		(net "ETH10G_B1_SDA")
	)
	(segment
		(start -298.157202 41.160002)
		(end -298.183999 41.160002)
		(width 0.12954)
		(layer "In2.Cu")
		(net "ETH10G_B1_SDA")
	)
	(segment
		(start -298.577 31.1658)
		(end -299.4914 30.2514)
		(width 0.12954)
		(layer "In2.Cu")
		(net "ETH10G_B1_SDA")
	)
	(segment
		(start -294.8178 15.2908)
		(end -297.4848 12.6238)
		(width 0.12954)
		(layer "In2.Cu")
		(net "ETH10G_B1_SDA")
	)
	(segment
		(start -299.0596 45.9486)
		(end -298.2468 46.7614)
		(width 0.12954)
		(layer "In2.Cu")
		(net "ETH10G_B1_SDA")
	)
	(segment
		(start -292.505869 46.7614)
		(end -291.4142 45.669731)
		(width 0.12954)
		(layer "In2.Cu")
		(net "ETH10G_B1_SDA")
	)
	(segment
		(start -281.762261 27.584461)
		(end -281.762261 26.4668)
		(width 0.12954)
		(layer "In2.Cu")
		(net "ETH10G_B1_SDA")
	)
	(segment
		(start -298.157202 41.160002)
		(end -299.0596 42.0624)
		(width 0.12954)
		(layer "In2.Cu")
		(net "ETH10G_B1_SDA")
	)
	(segment
		(start -299.0342 33.9852)
		(end -298.577 33.528)
		(width 0.12954)
		(layer "In2.Cu")
		(net "ETH10G_B1_SDA")
	)
	(segment
		(start -299.4914 28.7274)
		(end -294.8178 24.0538)
		(width 0.12954)
		(layer "In2.Cu")
		(net "ETH10G_B1_SDA")
	)
	(segment
		(start -299.0342 40.3098)
		(end -299.0342 33.9852)
		(width 0.12954)
		(layer "In2.Cu")
		(net "ETH10G_B1_SDA")
	)
	(segment
		(start -298.183999 41.160002)
		(end -299.0342 40.3098)
		(width 0.12954)
		(layer "In2.Cu")
		(net "ETH10G_B1_SDA")
	)
	(segment
		(start -299.4914 30.2514)
		(end -299.4914 28.7274)
		(width 0.12954)
		(layer "In2.Cu")
		(net "ETH10G_B1_SDA")
	)
	(segment
		(start -296.814001 11.176)
		(end -297.815 11.176)
		(width 0.1016)
		(layer "F.Cu")
		(net "ETH10G_B1_SCL")
	)
	(segment
		(start -282.550001 27.96)
		(end -282.550001 25.8064)
		(width 0.1016)
		(layer "F.Cu")
		(net "ETH10G_B1_SCL")
	)
	(via
		(at -297.815 11.176)
		(size 0.5588)
		(drill 0.254)
		(layers "F.Cu" "B.Cu")
		(net "ETH10G_B1_SCL")
	)
	(via
		(at -282.550001 25.8064)
		(size 0.5588)
		(drill 0.254)
		(layers "F.Cu" "B.Cu")
		(net "ETH10G_B1_SCL")
	)
	(segment
		(start -287.1724 27.1526)
		(end -283.1338 27.1526)
		(width 0.12954)
		(layer "In2.Cu")
		(net "ETH10G_B1_SCL")
	)
	(segment
		(start -297.958398 39.760002)
		(end -298.040001 39.760002)
		(width 0.12954)
		(layer "In2.Cu")
		(net "ETH10G_B1_SCL")
	)
	(segment
		(start -282.7782 26.034599)
		(end -282.550001 25.8064)
		(width 0.12954)
		(layer "In2.Cu")
		(net "ETH10G_B1_SCL")
	)
	(segment
		(start -293.0652 46.3296)
		(end -296.4434 46.3296)
		(width 0.12954)
		(layer "In2.Cu")
		(net "ETH10G_B1_SCL")
	)
	(segment
		(start -297.053 45.72)
		(end -297.053 40.6654)
		(width 0.12954)
		(layer "In2.Cu")
		(net "ETH10G_B1_SCL")
	)
	(segment
		(start -286.5628 27.813)
		(end -292.0492 33.2994)
		(width 0.12954)
		(layer "In2.Cu")
		(net "ETH10G_B1_SCL")
	)
	(segment
		(start -296.4434 46.3296)
		(end -297.053 45.72)
		(width 0.12954)
		(layer "In2.Cu")
		(net "ETH10G_B1_SCL")
	)
	(segment
		(start -283.1338 27.1526)
		(end -282.7782 26.797)
		(width 0.12954)
		(layer "In2.Cu")
		(net "ETH10G_B1_SCL")
	)
	(segment
		(start -297.815 11.176)
		(end -296.3418 11.176)
		(width 0.12954)
		(layer "In2.Cu")
		(net "ETH10G_B1_SCL")
	)
	(segment
		(start -282.7782 26.797)
		(end -282.7782 26.034599)
		(width 0.12954)
		(layer "In2.Cu")
		(net "ETH10G_B1_SCL")
	)
	(segment
		(start -291.8206 15.6972)
		(end -291.8206 19.7866)
		(width 0.12954)
		(layer "In2.Cu")
		(net "ETH10G_B1_SCL")
	)
	(segment
		(start -282.8544 27.813)
		(end -286.5628 27.813)
		(width 0.12954)
		(layer "In2.Cu")
		(net "ETH10G_B1_SCL")
	)
	(segment
		(start -282.2448 27.2034)
		(end -282.8544 27.813)
		(width 0.12954)
		(layer "In2.Cu")
		(net "ETH10G_B1_SCL")
	)
	(segment
		(start -292.0492 33.2994)
		(end -292.0492 45.3136)
		(width 0.12954)
		(layer "In2.Cu")
		(net "ETH10G_B1_SCL")
	)
	(segment
		(start -292.0492 45.3136)
		(end -293.0652 46.3296)
		(width 0.12954)
		(layer "In2.Cu")
		(net "ETH10G_B1_SCL")
	)
	(segment
		(start -282.2448 26.111601)
		(end -282.2448 27.2034)
		(width 0.12954)
		(layer "In2.Cu")
		(net "ETH10G_B1_SCL")
	)
	(segment
		(start -291.8206 19.7866)
		(end -287.4518 24.1554)
		(width 0.12954)
		(layer "In2.Cu")
		(net "ETH10G_B1_SCL")
	)
	(segment
		(start -296.3418 11.176)
		(end -291.8206 15.6972)
		(width 0.12954)
		(layer "In2.Cu")
		(net "ETH10G_B1_SCL")
	)
	(segment
		(start -297.053 40.6654)
		(end -297.958398 39.760002)
		(width 0.12954)
		(layer "In2.Cu")
		(net "ETH10G_B1_SCL")
	)
	(segment
		(start -287.4518 24.1554)
		(end -287.4518 26.8732)
		(width 0.12954)
		(layer "In2.Cu")
		(net "ETH10G_B1_SCL")
	)
	(segment
		(start -282.550001 25.8064)
		(end -282.2448 26.111601)
		(width 0.12954)
		(layer "In2.Cu")
		(net "ETH10G_B1_SCL")
	)
	(segment
		(start -287.4518 26.8732)
		(end -287.1724 27.1526)
		(width 0.12954)
		(layer "In2.Cu")
		(net "ETH10G_B1_SCL")
	)
	(segment
		(start -284.950002 26.504859)
		(end -284.955041 26.49982)
		(width 0.1016)
		(layer "F.Cu")
		(net "ETH10G_B1_RX_LOS")
	)
	(segment
		(start -284.950002 27.96)
		(end -284.950002 26.504859)
		(width 0.1016)
		(layer "F.Cu")
		(net "ETH10G_B1_RX_LOS")
	)
	(segment
		(start -300.301797 3.080601)
		(end -299.168401 3.080601)
		(width 0.1016)
		(layer "F.Cu")
		(net "ETH10G_B1_RX_LOS")
	)
	(segment
		(start -299.168401 3.080601)
		(end -299.1612 3.0734)
		(width 0.1016)
		(layer "F.Cu")
		(net "ETH10G_B1_RX_LOS")
	)
	(via
		(at -299.1612 3.0734)
		(size 0.5588)
		(drill 0.254)
		(layers "F.Cu" "B.Cu")
		(net "ETH10G_B1_RX_LOS")
	)
	(via
		(at -284.955041 26.49982)
		(size 0.5588)
		(drill 0.254)
		(layers "F.Cu" "B.Cu")
		(net "ETH10G_B1_RX_LOS")
	)
	(segment
		(start -294.132 9.017)
		(end -294.767 9.017)
		(width 0.12954)
		(layer "In2.Cu")
		(net "ETH10G_B1_RX_LOS")
	)
	(segment
		(start -299.1612 4.6228)
		(end -299.1612 3.0734)
		(width 0.12954)
		(layer "In2.Cu")
		(net "ETH10G_B1_RX_LOS")
	)
	(segment
		(start -285.2166 17.9324)
		(end -294.132 9.017)
		(width 0.12954)
		(layer "In2.Cu")
		(net "ETH10G_B1_RX_LOS")
	)
	(segment
		(start -284.955041 26.49982)
		(end -285.2166 26.238261)
		(width 0.12954)
		(layer "In2.Cu")
		(net "ETH10G_B1_RX_LOS")
	)
	(segment
		(start -294.767 9.017)
		(end -299.1612 4.6228)
		(width 0.12954)
		(layer "In2.Cu")
		(net "ETH10G_B1_RX_LOS")
	)
	(segment
		(start -285.2166 26.238261)
		(end -285.2166 17.9324)
		(width 0.12954)
		(layer "In2.Cu")
		(net "ETH10G_B1_RX_LOS")
	)
	(segment
		(start -284.55 37.44356)
		(end -284.732829 37.626389)
		(width 0.10668)
		(layer "F.Cu")
		(net "ETH10G_B1_RXP")
	)
	(segment
		(start -284.732829 37.626389)
		(end -284.732829 38.959633)
		(width 0.10668)
		(layer "F.Cu")
		(net "ETH10G_B1_RXP")
	)
	(segment
		(start -284.55 36.159999)
		(end -284.55 37.44356)
		(width 0.10668)
		(layer "F.Cu")
		(net "ETH10G_B1_RXP")
	)
	(via
		(at -284.543599 39.416474)
		(size 0.5588)
		(drill 0.254)
		(layers "F.Cu" "B.Cu")
		(net "ETH10G_B1_RXP")
	)
	(arc
		(start -284.732829 38.959633)
		(mid -284.68365 39.206874)
		(end -284.543599 39.416474)
		(width 0.10668)
		(layer "F.Cu")
		(net "ETH10G_B1_RXP")
	)
	(segment
		(start -292.448171 41.230885)
		(end -292.706527 40.972524)
		(width 0.10668)
		(layer "B.Cu")
		(net "ETH10G_B1_RXP")
	)
	(segment
		(start -293.1922 40.677173)
		(end -293.512984 40.677173)
		(width 0.10668)
		(layer "B.Cu")
		(net "ETH10G_B1_RXP")
	)
	(segment
		(start -285.852969 41.42994)
		(end -291.9676 41.42994)
		(width 0.10668)
		(layer "B.Cu")
		(net "ETH10G_B1_RXP")
	)
	(segment
		(start -292.706527 40.972524)
		(end -292.867298 40.811752)
		(width 0.10668)
		(layer "B.Cu")
		(net "ETH10G_B1_RXP")
	)
	(segment
		(start -284.732829 39.873316)
		(end -284.732829 40.3098)
		(width 0.10668)
		(layer "B.Cu")
		(net "ETH10G_B1_RXP")
	)
	(segment
		(start -293.58842 40.70842)
		(end -294.040001 41.160002)
		(width 0.10668)
		(layer "B.Cu")
		(net "ETH10G_B1_RXP")
	)
	(arc
		(start -291.9676 41.42994)
		(mid -292.227683 41.378208)
		(end -292.448171 41.230885)
		(width 0.10668)
		(layer "B.Cu")
		(net "ETH10G_B1_RXP")
	)
	(arc
		(start -293.512984 40.677173)
		(mid -293.55381 40.685294)
		(end -293.58842 40.70842)
		(width 0.10668)
		(layer "B.Cu")
		(net "ETH10G_B1_RXP")
	)
	(arc
		(start -284.543599 39.416474)
		(mid -284.68365 39.626075)
		(end -284.732829 39.873316)
		(width 0.10668)
		(layer "B.Cu")
		(net "ETH10G_B1_RXP")
	)
	(arc
		(start -292.867298 40.811752)
		(mid -293.016364 40.712148)
		(end -293.1922 40.677173)
		(width 0.10668)
		(layer "B.Cu")
		(net "ETH10G_B1_RXP")
	)
	(arc
		(start -284.732829 40.3098)
		(mid -285.06091 41.101859)
		(end -285.852969 41.42994)
		(width 0.10668)
		(layer "B.Cu")
		(net "ETH10G_B1_RXP")
	)
	(segment
		(start -285.350001 36.159999)
		(end -285.350001 37.456059)
		(width 0.10668)
		(layer "F.Cu")
		(net "ETH10G_B1_RXN")
	)
	(segment
		(start -285.167169 37.638891)
		(end -285.167169 38.959633)
		(width 0.10668)
		(layer "F.Cu")
		(net "ETH10G_B1_RXN")
	)
	(segment
		(start -285.350001 37.456059)
		(end -285.167169 37.638891)
		(width 0.10668)
		(layer "F.Cu")
		(net "ETH10G_B1_RXN")
	)
	(via
		(at -285.356399 39.416474)
		(size 0.5588)
		(drill 0.254)
		(layers "F.Cu" "B.Cu")
		(net "ETH10G_B1_RXN")
	)
	(arc
		(start -285.167169 38.959633)
		(mid -285.216348 39.206874)
		(end -285.356399 39.416474)
		(width 0.10668)
		(layer "F.Cu")
		(net "ETH10G_B1_RXN")
	)
	(segment
		(start -288.3916 40.9956)
		(end -289.8394 40.9956)
		(width 0.10668)
		(layer "B.Cu")
		(net "ETH10G_B1_RXN")
	)
	(segment
		(start -290.6776 40.9956)
		(end -291.9676 40.9956)
		(width 0.10668)
		(layer "B.Cu")
		(net "ETH10G_B1_RXN")
	)
	(segment
		(start -285.852969 40.9956)
		(end -287.5534 40.9956)
		(width 0.10668)
		(layer "B.Cu")
		(net "ETH10G_B1_RXN")
	)
	(segment
		(start -287.8328 40.7162)
		(end -288.1122 40.7162)
		(width 0.10668)
		(layer "B.Cu")
		(net "ETH10G_B1_RXN")
	)
	(segment
		(start -293.1922 40.242833)
		(end -293.512982 40.242833)
		(width 0.10668)
		(layer "B.Cu")
		(net "ETH10G_B1_RXN")
	)
	(segment
		(start -292.141044 40.923759)
		(end -292.3994 40.6654)
		(width 0.10668)
		(layer "B.Cu")
		(net "ETH10G_B1_RXN")
	)
	(segment
		(start -293.588417 40.211586)
		(end -294.040001 39.760002)
		(width 0.10668)
		(layer "B.Cu")
		(net "ETH10G_B1_RXN")
	)
	(segment
		(start -290.14928 40.68572)
		(end -290.36772 40.68572)
		(width 0.10668)
		(layer "B.Cu")
		(net "ETH10G_B1_RXN")
	)
	(segment
		(start -285.167169 39.873316)
		(end -285.167169 40.3098)
		(width 0.10668)
		(layer "B.Cu")
		(net "ETH10G_B1_RXN")
	)
	(segment
		(start -292.3994 40.6654)
		(end -292.560174 40.504626)
		(width 0.10668)
		(layer "B.Cu")
		(net "ETH10G_B1_RXN")
	)
	(arc
		(start -290.576 40.894)
		(mid -290.605758 40.965842)
		(end -290.6776 40.9956)
		(width 0.10668)
		(layer "B.Cu")
		(net "ETH10G_B1_RXN")
	)
	(arc
		(start -289.941 40.894)
		(mid -290.002004 40.746724)
		(end -290.14928 40.68572)
		(width 0.10668)
		(layer "B.Cu")
		(net "ETH10G_B1_RXN")
	)
	(arc
		(start -288.1122 40.7162)
		(mid -288.237924 40.768276)
		(end -288.29 40.894)
		(width 0.10668)
		(layer "B.Cu")
		(net "ETH10G_B1_RXN")
	)
	(arc
		(start -287.655 40.894)
		(mid -287.707076 40.768276)
		(end -287.8328 40.7162)
		(width 0.10668)
		(layer "B.Cu")
		(net "ETH10G_B1_RXN")
	)
	(arc
		(start -285.167169 40.3098)
		(mid -285.368035 40.794734)
		(end -285.852969 40.9956)
		(width 0.10668)
		(layer "B.Cu")
		(net "ETH10G_B1_RXN")
	)
	(arc
		(start -292.560174 40.504626)
		(mid -292.85015 40.310871)
		(end -293.1922 40.242833)
		(width 0.10668)
		(layer "B.Cu")
		(net "ETH10G_B1_RXN")
	)
	(arc
		(start -290.36772 40.68572)
		(mid -290.514996 40.746724)
		(end -290.576 40.894)
		(width 0.10668)
		(layer "B.Cu")
		(net "ETH10G_B1_RXN")
	)
	(arc
		(start -285.356399 39.416474)
		(mid -285.216348 39.626075)
		(end -285.167169 39.873316)
		(width 0.10668)
		(layer "B.Cu")
		(net "ETH10G_B1_RXN")
	)
	(arc
		(start -289.8394 40.9956)
		(mid -289.911242 40.965842)
		(end -289.941 40.894)
		(width 0.10668)
		(layer "B.Cu")
		(net "ETH10G_B1_RXN")
	)
	(arc
		(start -287.5534 40.9956)
		(mid -287.625242 40.965842)
		(end -287.655 40.894)
		(width 0.10668)
		(layer "B.Cu")
		(net "ETH10G_B1_RXN")
	)
	(arc
		(start -288.29 40.894)
		(mid -288.319758 40.965842)
		(end -288.3916 40.9956)
		(width 0.10668)
		(layer "B.Cu")
		(net "ETH10G_B1_RXN")
	)
	(arc
		(start -291.9676 40.9956)
		(mid -292.061467 40.97693)
		(end -292.141044 40.923759)
		(width 0.10668)
		(layer "B.Cu")
		(net "ETH10G_B1_RXN")
	)
	(arc
		(start -293.512982 40.242833)
		(mid -293.553807 40.234712)
		(end -293.588417 40.211586)
		(width 0.10668)
		(layer "B.Cu")
		(net "ETH10G_B1_RXN")
	)
	(segment
		(start -285.75 25.8318)
		(end -285.75 27.96)
		(width 0.1016)
		(layer "F.Cu")
		(net "ETH10G_B1_RS1")
	)
	(segment
		(start -299.4533 5.905602)
		(end -300.271 5.905602)
		(width 0.1016)
		(layer "F.Cu")
		(net "ETH10G_B1_RS1")
	)
	(segment
		(start -300.271 5.905602)
		(end -300.3218 5.956402)
		(width 0.1016)
		(layer "F.Cu")
		(net "ETH10G_B1_RS1")
	)
	(segment
		(start -300.3218 4.635602)
		(end -300.3218 5.956402)
		(width 0.1016)
		(layer "F.Cu")
		(net "ETH10G_B1_RS1")
	)
	(via
		(at -285.75 25.8318)
		(size 0.5588)
		(drill 0.254)
		(layers "F.Cu" "B.Cu")
		(net "ETH10G_B1_RS1")
	)
	(via
		(at -299.4533 5.905602)
		(size 0.5588)
		(drill 0.254)
		(layers "F.Cu" "B.Cu")
		(net "ETH10G_B1_RS1")
	)
	(segment
		(start -285.75 25.8318)
		(end -285.75 24.6126)
		(width 0.12954)
		(layer "In2.Cu")
		(net "ETH10G_B1_RS1")
	)
	(segment
		(start -285.75 24.6126)
		(end -291.3126 19.05)
		(width 0.12954)
		(layer "In2.Cu")
		(net "ETH10G_B1_RS1")
	)
	(segment
		(start -295.8846 10.6426)
		(end -295.8846 9.474302)
		(width 0.12954)
		(layer "In2.Cu")
		(net "ETH10G_B1_RS1")
	)
	(segment
		(start -295.8846 9.474302)
		(end -299.4533 5.905602)
		(width 0.12954)
		(layer "In2.Cu")
		(net "ETH10G_B1_RS1")
	)
	(segment
		(start -291.3126 19.05)
		(end -291.3126 15.2146)
		(width 0.12954)
		(layer "In2.Cu")
		(net "ETH10G_B1_RS1")
	)
	(segment
		(start -291.3126 15.2146)
		(end -295.8846 10.6426)
		(width 0.12954)
		(layer "In2.Cu")
		(net "ETH10G_B1_RS1")
	)
	(segment
		(start -295.4958 6.794602)
		(end -295.4958 6.845402)
		(width 0.1016)
		(layer "F.Cu")
		(net "ETH10G_B1_RS0")
	)
	(segment
		(start -284.150001 25.8469)
		(end -284.150001 27.96)
		(width 0.1016)
		(layer "F.Cu")
		(net "ETH10G_B1_RS0")
	)
	(segment
		(start -295.4958 6.794602)
		(end -295.4958 5.524602)
		(width 0.1016)
		(layer "F.Cu")
		(net "ETH10G_B1_RS0")
	)
	(segment
		(start -294.6781 6.794602)
		(end -295.4958 6.794602)
		(width 0.1016)
		(layer "F.Cu")
		(net "ETH10G_B1_RS0")
	)
	(via
		(at -294.6781 6.794602)
		(size 0.5588)
		(drill 0.254)
		(layers "F.Cu" "B.Cu")
		(net "ETH10G_B1_RS0")
	)
	(via
		(at -284.150001 25.8469)
		(size 0.5588)
		(drill 0.254)
		(layers "F.Cu" "B.Cu")
		(net "ETH10G_B1_RS0")
	)
	(segment
		(start -294.6781 6.794602)
		(end -284.150001 17.322701)
		(width 0.12954)
		(layer "In2.Cu")
		(net "ETH10G_B1_RS0")
	)
	(segment
		(start -284.150001 17.322701)
		(end -284.150001 25.8469)
		(width 0.12954)
		(layer "In2.Cu")
		(net "ETH10G_B1_RS0")
	)
	(segment
		(start -301.589201 1.4732)
		(end -302.859201 1.4732)
		(width 0.1016)
		(layer "F.Cu")
		(net "ETH10G_B1_PRES_N")
	)
	(via
		(at -302.859201 1.4732)
		(size 0.5588)
		(drill 0.254)
		(layers "F.Cu" "B.Cu")
		(net "ETH10G_B1_PRES_N")
	)
	(segment
		(start -295.1226 28.6766)
		(end -296.8244 30.3784)
		(width 0.12954)
		(layer "In2.Cu")
		(net "ETH10G_B1_PRES_N")
	)
	(segment
		(start -297.11647 9.94407)
		(end -297.688 10.5156)
		(width 0.12954)
		(layer "In2.Cu")
		(net "ETH10G_B1_PRES_N")
	)
	(segment
		(start -302.859201 1.4732)
		(end -301.498 2.834401)
		(width 0.12954)
		(layer "In2.Cu")
		(net "ETH10G_B1_PRES_N")
	)
	(segment
		(start -301.498 4.826)
		(end -297.11647 9.20753)
		(width 0.12954)
		(layer "In2.Cu")
		(net "ETH10G_B1_PRES_N")
	)
	(segment
		(start -298.03852 11.81608)
		(end -296.64152 11.81608)
		(width 0.12954)
		(layer "In2.Cu")
		(net "ETH10G_B1_PRES_N")
	)
	(segment
		(start -297.688 10.5156)
		(end -297.9928 10.5156)
		(width 0.12954)
		(layer "In2.Cu")
		(net "ETH10G_B1_PRES_N")
	)
	(segment
		(start -295.1226 25.8572)
		(end -295.1226 28.6766)
		(width 0.12954)
		(layer "In2.Cu")
		(net "ETH10G_B1_PRES_N")
	)
	(segment
		(start -297.9928 10.5156)
		(end -298.33824 10.86104)
		(width 0.12954)
		(layer "In2.Cu")
		(net "ETH10G_B1_PRES_N")
	)
	(segment
		(start -298.33824 10.86104)
		(end -298.33824 11.51636)
		(width 0.12954)
		(layer "In2.Cu")
		(net "ETH10G_B1_PRES_N")
	)
	(segment
		(start -296.8244 30.3784)
		(end -296.8244 33.475602)
		(width 0.12954)
		(layer "In2.Cu")
		(net "ETH10G_B1_PRES_N")
	)
	(segment
		(start -293.7256 14.732)
		(end -293.7256 24.4602)
		(width 0.12954)
		(layer "In2.Cu")
		(net "ETH10G_B1_PRES_N")
	)
	(segment
		(start -301.498 2.834401)
		(end -301.498 4.826)
		(width 0.12954)
		(layer "In2.Cu")
		(net "ETH10G_B1_PRES_N")
	)
	(segment
		(start -298.33824 11.51636)
		(end -298.03852 11.81608)
		(width 0.12954)
		(layer "In2.Cu")
		(net "ETH10G_B1_PRES_N")
	)
	(segment
		(start -296.8244 33.475602)
		(end -296.040002 34.26)
		(width 0.12954)
		(layer "In2.Cu")
		(net "ETH10G_B1_PRES_N")
	)
	(segment
		(start -297.11647 9.20753)
		(end -297.11647 9.94407)
		(width 0.12954)
		(layer "In2.Cu")
		(net "ETH10G_B1_PRES_N")
	)
	(segment
		(start -296.64152 11.81608)
		(end -293.7256 14.732)
		(width 0.12954)
		(layer "In2.Cu")
		(net "ETH10G_B1_PRES_N")
	)
	(segment
		(start -293.7256 24.4602)
		(end -295.1226 25.8572)
		(width 0.12954)
		(layer "In2.Cu")
		(net "ETH10G_B1_PRES_N")
	)
	(segment
		(start -300.289199 1.4732)
		(end -300.289199 0)
		(width 0.1016)
		(layer "F.Cu")
		(net "ETH10G_B1_MOD_ABS")
	)
	(segment
		(start -283.35 27.96)
		(end -283.35 26.492439)
		(width 0.1016)
		(layer "F.Cu")
		(net "ETH10G_B1_MOD_ABS")
	)
	(segment
		(start -283.35 26.492439)
		(end -283.334521 26.47696)
		(width 0.1016)
		(layer "F.Cu")
		(net "ETH10G_B1_MOD_ABS")
	)
	(segment
		(start -300.289199 1.4732)
		(end -299.4152 1.4732)
		(width 0.1016)
		(layer "F.Cu")
		(net "ETH10G_B1_MOD_ABS")
	)
	(via
		(at -283.334521 26.47696)
		(size 0.5588)
		(drill 0.254)
		(layers "F.Cu" "B.Cu")
		(net "ETH10G_B1_MOD_ABS")
	)
	(via
		(at -299.4152 1.4732)
		(size 0.5588)
		(drill 0.254)
		(layers "F.Cu" "B.Cu")
		(net "ETH10G_B1_MOD_ABS")
	)
	(segment
		(start -284.6324 26.035)
		(end -284.177679 26.489721)
		(width 0.12954)
		(layer "In2.Cu")
		(net "ETH10G_B1_MOD_ABS")
	)
	(segment
		(start -296.7482 4.826)
		(end -295.4782 6.096)
		(width 0.12954)
		(layer "In2.Cu")
		(net "ETH10G_B1_MOD_ABS")
	)
	(segment
		(start -299.4152 1.4732)
		(end -298.3992 2.4892)
		(width 0.12954)
		(layer "In2.Cu")
		(net "ETH10G_B1_MOD_ABS")
	)
	(segment
		(start -283.347282 26.489721)
		(end -283.334521 26.47696)
		(width 0.12954)
		(layer "In2.Cu")
		(net "ETH10G_B1_MOD_ABS")
	)
	(segment
		(start -297.7896 4.826)
		(end -296.7482 4.826)
		(width 0.12954)
		(layer "In2.Cu")
		(net "ETH10G_B1_MOD_ABS")
	)
	(segment
		(start -295.4782 6.096)
		(end -295.4782 6.7818)
		(width 0.12954)
		(layer "In2.Cu")
		(net "ETH10G_B1_MOD_ABS")
	)
	(segment
		(start -298.3992 4.2164)
		(end -297.7896 4.826)
		(width 0.12954)
		(layer "In2.Cu")
		(net "ETH10G_B1_MOD_ABS")
	)
	(segment
		(start -284.6324 17.6276)
		(end -284.6324 26.035)
		(width 0.12954)
		(layer "In2.Cu")
		(net "ETH10G_B1_MOD_ABS")
	)
	(segment
		(start -295.4782 6.7818)
		(end -284.6324 17.6276)
		(width 0.12954)
		(layer "In2.Cu")
		(net "ETH10G_B1_MOD_ABS")
	)
	(segment
		(start -298.3992 2.4892)
		(end -298.3992 4.2164)
		(width 0.12954)
		(layer "In2.Cu")
		(net "ETH10G_B1_MOD_ABS")
	)
	(segment
		(start -284.177679 26.489721)
		(end -283.347282 26.489721)
		(width 0.12954)
		(layer "In2.Cu")
		(net "ETH10G_B1_MOD_ABS")
	)
	(segment
		(start -149.634999 22.704999)
		(end -150.269999 22.069999)
		(width 0.127)
		(layer "F.Cu")
		(net "CLK_100M_B2_P<3>")
	)
	(via
		(at -150.269999 22.069999)
		(size 0.5588)
		(drill 0.254)
		(layers "F.Cu" "B.Cu")
		(net "CLK_100M_B2_P<3>")
	)
	(segment
		(start -158.824907 22.05228)
		(end -157.082467 20.30984)
		(width 0.127)
		(layer "In5.Cu")
		(net "CLK_100M_B2_P<3>")
	)
	(segment
		(start -161.297013 22.05228)
		(end -158.824907 22.05228)
		(width 0.127)
		(layer "In5.Cu")
		(net "CLK_100M_B2_P<3>")
	)
	(segment
		(start -152.3165 20.50288)
		(end -152.3165 21.29536)
		(width 0.127)
		(layer "In5.Cu")
		(net "CLK_100M_B2_P<3>")
	)
	(segment
		(start -150.758949 21.581049)
		(end -150.269999 22.069999)
		(width 0.127)
		(layer "In5.Cu")
		(net "CLK_100M_B2_P<3>")
	)
	(segment
		(start -180.821307 17.2212)
		(end -166.128093 17.2212)
		(width 0.127)
		(layer "In5.Cu")
		(net "CLK_100M_B2_P<3>")
	)
	(segment
		(start -186.3271 31.775095)
		(end -186.3271 22.726993)
		(width 0.127)
		(layer "In5.Cu")
		(net "CLK_100M_B2_P<3>")
	)
	(segment
		(start -166.128093 17.2212)
		(end -161.297013 22.05228)
		(width 0.127)
		(layer "In5.Cu")
		(net "CLK_100M_B2_P<3>")
	)
	(segment
		(start -152.3165 21.29536)
		(end -152.030811 21.581049)
		(width 0.127)
		(layer "In5.Cu")
		(net "CLK_100M_B2_P<3>")
	)
	(segment
		(start -152.50954 20.30984)
		(end -152.3165 20.50288)
		(width 0.127)
		(layer "In5.Cu")
		(net "CLK_100M_B2_P<3>")
	)
	(segment
		(start -152.030811 21.581049)
		(end -150.758949 21.581049)
		(width 0.127)
		(layer "In5.Cu")
		(net "CLK_100M_B2_P<3>")
	)
	(segment
		(start -187.460001 32.660001)
		(end -186.906052 32.106052)
		(width 0.127)
		(layer "In5.Cu")
		(net "CLK_100M_B2_P<3>")
	)
	(segment
		(start -186.3271 22.726993)
		(end -180.821307 17.2212)
		(width 0.127)
		(layer "In5.Cu")
		(net "CLK_100M_B2_P<3>")
	)
	(segment
		(start -186.906052 32.106052)
		(end -186.658057 32.106052)
		(width 0.127)
		(layer "In5.Cu")
		(net "CLK_100M_B2_P<3>")
	)
	(segment
		(start -157.082467 20.30984)
		(end -152.50954 20.30984)
		(width 0.127)
		(layer "In5.Cu")
		(net "CLK_100M_B2_P<3>")
	)
	(segment
		(start -186.658057 32.106052)
		(end -186.3271 31.775095)
		(width 0.127)
		(layer "In5.Cu")
		(net "CLK_100M_B2_P<3>")
	)
	(segment
		(start -152.809999 22.069999)
		(end -152.174999 22.704999)
		(width 0.127)
		(layer "F.Cu")
		(net "CLK_100M_B2_P<2>")
	)
	(via
		(at -152.809999 22.069999)
		(size 0.5588)
		(drill 0.254)
		(layers "F.Cu" "B.Cu")
		(net "CLK_100M_B2_P<2>")
	)
	(segment
		(start -155.84456 21.13026)
		(end -155.84456 20.537693)
		(width 0.127)
		(layer "B.Cu")
		(net "CLK_100M_B2_P<2>")
	)
	(segment
		(start -185.783149 23.521802)
		(end -178.390347 16.129)
		(width 0.127)
		(layer "B.Cu")
		(net "CLK_100M_B2_P<2>")
	)
	(segment
		(start -186.2982 24.012771)
		(end -185.807231 23.521802)
		(width 0.127)
		(layer "B.Cu")
		(net "CLK_100M_B2_P<2>")
	)
	(segment
		(start -178.390347 16.129)
		(end -165.5118 16.129)
		(width 0.127)
		(layer "B.Cu")
		(net "CLK_100M_B2_P<2>")
	)
	(segment
		(start -153.292599 21.587399)
		(end -152.809999 22.069999)
		(width 0.127)
		(layer "B.Cu")
		(net "CLK_100M_B2_P<2>")
	)
	(segment
		(start -186.912402 36.312401)
		(end -186.659147 36.312401)
		(width 0.127)
		(layer "B.Cu")
		(net "CLK_100M_B2_P<2>")
	)
	(segment
		(start -186.3144 24.053053)
		(end -186.2982 24.036853)
		(width 0.127)
		(layer "B.Cu")
		(net "CLK_100M_B2_P<2>")
	)
	(segment
		(start -160.05588 21.58492)
		(end -156.29922 21.58492)
		(width 0.127)
		(layer "B.Cu")
		(net "CLK_100M_B2_P<2>")
	)
	(segment
		(start -155.84456 20.537693)
		(end -155.619247 20.31238)
		(width 0.127)
		(layer "B.Cu")
		(net "CLK_100M_B2_P<2>")
	)
	(segment
		(start -155.061493 20.31238)
		(end -154.8565 20.517373)
		(width 0.127)
		(layer "B.Cu")
		(net "CLK_100M_B2_P<2>")
	)
	(segment
		(start -156.29922 21.58492)
		(end -155.84456 21.13026)
		(width 0.127)
		(layer "B.Cu")
		(net "CLK_100M_B2_P<2>")
	)
	(segment
		(start -185.807231 23.521802)
		(end -185.783149 23.521802)
		(width 0.127)
		(layer "B.Cu")
		(net "CLK_100M_B2_P<2>")
	)
	(segment
		(start -187.460001 36.86)
		(end -186.912402 36.312401)
		(width 0.127)
		(layer "B.Cu")
		(net "CLK_100M_B2_P<2>")
	)
	(segment
		(start -154.401901 21.587399)
		(end -153.292599 21.587399)
		(width 0.127)
		(layer "B.Cu")
		(net "CLK_100M_B2_P<2>")
	)
	(segment
		(start -165.5118 16.129)
		(end -160.05588 21.58492)
		(width 0.127)
		(layer "B.Cu")
		(net "CLK_100M_B2_P<2>")
	)
	(segment
		(start -186.3144 35.967655)
		(end -186.3144 24.053053)
		(width 0.127)
		(layer "B.Cu")
		(net "CLK_100M_B2_P<2>")
	)
	(segment
		(start -154.8565 21.1328)
		(end -154.401901 21.587399)
		(width 0.127)
		(layer "B.Cu")
		(net "CLK_100M_B2_P<2>")
	)
	(segment
		(start -155.619247 20.31238)
		(end -155.061493 20.31238)
		(width 0.127)
		(layer "B.Cu")
		(net "CLK_100M_B2_P<2>")
	)
	(segment
		(start -154.8565 20.517373)
		(end -154.8565 21.1328)
		(width 0.127)
		(layer "B.Cu")
		(net "CLK_100M_B2_P<2>")
	)
	(segment
		(start -186.2982 24.036853)
		(end -186.2982 24.012771)
		(width 0.127)
		(layer "B.Cu")
		(net "CLK_100M_B2_P<2>")
	)
	(segment
		(start -186.659147 36.312401)
		(end -186.3144 35.967655)
		(width 0.127)
		(layer "B.Cu")
		(net "CLK_100M_B2_P<2>")
	)
	(segment
		(start -155.349999 22.069999)
		(end -154.714999 22.704999)
		(width 0.127)
		(layer "F.Cu")
		(net "CLK_100M_B2_P<1>")
	)
	(via
		(at -155.349999 22.069999)
		(size 0.5588)
		(drill 0.254)
		(layers "F.Cu" "B.Cu")
		(net "CLK_100M_B2_P<1>")
	)
	(segment
		(start -186.2982 23.038158)
		(end -186.2982 40.201568)
		(width 0.127)
		(layer "In2.Cu")
		(net "CLK_100M_B2_P<1>")
	)
	(segment
		(start -160.389181 21.581049)
		(end -166.250722 15.719509)
		(width 0.127)
		(layer "In2.Cu")
		(net "CLK_100M_B2_P<1>")
	)
	(segment
		(start -155.349999 22.069999)
		(end -155.838949 21.581049)
		(width 0.127)
		(layer "In2.Cu")
		(net "CLK_100M_B2_P<1>")
	)
	(segment
		(start -186.2982 40.201568)
		(end -186.602685 40.506053)
		(width 0.127)
		(layer "In2.Cu")
		(net "CLK_100M_B2_P<1>")
	)
	(segment
		(start -186.906052 40.506053)
		(end -187.460001 41.060002)
		(width 0.127)
		(layer "In2.Cu")
		(net "CLK_100M_B2_P<1>")
	)
	(segment
		(start -178.979551 15.719509)
		(end -186.2982 23.038158)
		(width 0.127)
		(layer "In2.Cu")
		(net "CLK_100M_B2_P<1>")
	)
	(segment
		(start -155.838949 21.581049)
		(end -160.389181 21.581049)
		(width 0.127)
		(layer "In2.Cu")
		(net "CLK_100M_B2_P<1>")
	)
	(segment
		(start -166.250722 15.719509)
		(end -178.979551 15.719509)
		(width 0.127)
		(layer "In2.Cu")
		(net "CLK_100M_B2_P<1>")
	)
	(segment
		(start -186.602685 40.506053)
		(end -186.906052 40.506053)
		(width 0.127)
		(layer "In2.Cu")
		(net "CLK_100M_B2_P<1>")
	)
	(segment
		(start -159.302069 22.222399)
		(end -157.737599 22.222399)
		(width 0.127)
		(layer "F.Cu")
		(net "CLK_100M_B2_P<0>")
	)
	(segment
		(start -165.725668 15.7988)
		(end -159.302069 22.222399)
		(width 0.127)
		(layer "F.Cu")
		(net "CLK_100M_B2_P<0>")
	)
	(segment
		(start -157.737599 22.222399)
		(end -157.254999 22.704999)
		(width 0.127)
		(layer "F.Cu")
		(net "CLK_100M_B2_P<0>")
	)
	(segment
		(start -186.314329 23.000391)
		(end -179.112738 15.7988)
		(width 0.127)
		(layer "F.Cu")
		(net "CLK_100M_B2_P<0>")
	)
	(segment
		(start -187.460001 45.260001)
		(end -186.912402 44.712402)
		(width 0.127)
		(layer "F.Cu")
		(net "CLK_100M_B2_P<0>")
	)
	(segment
		(start -186.912402 44.712402)
		(end -186.659147 44.712402)
		(width 0.127)
		(layer "F.Cu")
		(net "CLK_100M_B2_P<0>")
	)
	(segment
		(start -186.659147 44.712402)
		(end -186.314329 44.367585)
		(width 0.127)
		(layer "F.Cu")
		(net "CLK_100M_B2_P<0>")
	)
	(segment
		(start -186.314329 44.367585)
		(end -186.314329 23.000391)
		(width 0.127)
		(layer "F.Cu")
		(net "CLK_100M_B2_P<0>")
	)
	(segment
		(start -179.112738 15.7988)
		(end -165.725668 15.7988)
		(width 0.127)
		(layer "F.Cu")
		(net "CLK_100M_B2_P<0>")
	)
	(segment
		(start -149.634999 21.434999)
		(end -150.269999 20.799999)
		(width 0.127)
		(layer "F.Cu")
		(net "CLK_100M_B2_N<3>")
	)
	(via
		(at -150.269999 20.799999)
		(size 0.5588)
		(drill 0.254)
		(layers "F.Cu" "B.Cu")
		(net "CLK_100M_B2_N<3>")
	)
	(segment
		(start -157.20346 20.01774)
		(end -152.388547 20.01774)
		(width 0.127)
		(layer "In5.Cu")
		(net "CLK_100M_B2_N<3>")
	)
	(segment
		(start -152.388547 20.01774)
		(end -152.0244 20.381887)
		(width 0.127)
		(layer "In5.Cu")
		(net "CLK_100M_B2_N<3>")
	)
	(segment
		(start -161.17602 21.76018)
		(end -158.9459 21.76018)
		(width 0.127)
		(layer "In5.Cu")
		(net "CLK_100M_B2_N<3>")
	)
	(segment
		(start -186.6192 22.606)
		(end -180.9423 16.9291)
		(width 0.127)
		(layer "In5.Cu")
		(net "CLK_100M_B2_N<3>")
	)
	(segment
		(start -152.0244 21.174367)
		(end -151.909818 21.288949)
		(width 0.127)
		(layer "In5.Cu")
		(net "CLK_100M_B2_N<3>")
	)
	(segment
		(start -158.9459 21.76018)
		(end -157.20346 20.01774)
		(width 0.127)
		(layer "In5.Cu")
		(net "CLK_100M_B2_N<3>")
	)
	(segment
		(start -166.0071 16.9291)
		(end -161.17602 21.76018)
		(width 0.127)
		(layer "In5.Cu")
		(net "CLK_100M_B2_N<3>")
	)
	(segment
		(start -186.90605 31.813952)
		(end -186.77905 31.813952)
		(width 0.127)
		(layer "In5.Cu")
		(net "CLK_100M_B2_N<3>")
	)
	(segment
		(start -180.9423 16.9291)
		(end -166.0071 16.9291)
		(width 0.127)
		(layer "In5.Cu")
		(net "CLK_100M_B2_N<3>")
	)
	(segment
		(start -186.6192 31.654102)
		(end -186.6192 22.606)
		(width 0.127)
		(layer "In5.Cu")
		(net "CLK_100M_B2_N<3>")
	)
	(segment
		(start -152.0244 20.381887)
		(end -152.0244 21.174367)
		(width 0.127)
		(layer "In5.Cu")
		(net "CLK_100M_B2_N<3>")
	)
	(segment
		(start -187.460001 31.260001)
		(end -186.90605 31.813952)
		(width 0.127)
		(layer "In5.Cu")
		(net "CLK_100M_B2_N<3>")
	)
	(segment
		(start -150.758949 21.288949)
		(end -150.269999 20.799999)
		(width 0.127)
		(layer "In5.Cu")
		(net "CLK_100M_B2_N<3>")
	)
	(segment
		(start -151.909818 21.288949)
		(end -150.758949 21.288949)
		(width 0.127)
		(layer "In5.Cu")
		(net "CLK_100M_B2_N<3>")
	)
	(segment
		(start -186.77905 31.813952)
		(end -186.6192 31.654102)
		(width 0.127)
		(layer "In5.Cu")
		(net "CLK_100M_B2_N<3>")
	)
	(segment
		(start -152.809999 20.799999)
		(end -152.174999 21.434999)
		(width 0.127)
		(layer "F.Cu")
		(net "CLK_100M_B2_N<2>")
	)
	(via
		(at -152.809999 20.799999)
		(size 0.5588)
		(drill 0.254)
		(layers "F.Cu" "B.Cu")
		(net "CLK_100M_B2_N<2>")
	)
	(segment
		(start -154.275648 21.282599)
		(end -153.292599 21.282599)
		(width 0.127)
		(layer "B.Cu")
		(net "CLK_100M_B2_N<2>")
	)
	(segment
		(start -154.5517 21.006547)
		(end -154.275648 21.282599)
		(width 0.127)
		(layer "B.Cu")
		(net "CLK_100M_B2_N<2>")
	)
	(segment
		(start -186.6192 23.9268)
		(end -186.603 23.9106)
		(width 0.127)
		(layer "B.Cu")
		(net "CLK_100M_B2_N<2>")
	)
	(segment
		(start -186.9124 36.007601)
		(end -186.7854 36.007601)
		(width 0.127)
		(layer "B.Cu")
		(net "CLK_100M_B2_N<2>")
	)
	(segment
		(start -155.7455 20.00758)
		(end -154.93524 20.00758)
		(width 0.127)
		(layer "B.Cu")
		(net "CLK_100M_B2_N<2>")
	)
	(segment
		(start -186.6192 35.841402)
		(end -186.6192 23.9268)
		(width 0.127)
		(layer "B.Cu")
		(net "CLK_100M_B2_N<2>")
	)
	(segment
		(start -186.603 23.9106)
		(end -186.603 23.886518)
		(width 0.127)
		(layer "B.Cu")
		(net "CLK_100M_B2_N<2>")
	)
	(segment
		(start -154.5517 20.39112)
		(end -154.5517 21.006547)
		(width 0.127)
		(layer "B.Cu")
		(net "CLK_100M_B2_N<2>")
	)
	(segment
		(start -156.14936 21.004007)
		(end -156.14936 20.41144)
		(width 0.127)
		(layer "B.Cu")
		(net "CLK_100M_B2_N<2>")
	)
	(segment
		(start -154.93524 20.00758)
		(end -154.5517 20.39112)
		(width 0.127)
		(layer "B.Cu")
		(net "CLK_100M_B2_N<2>")
	)
	(segment
		(start -165.385547 15.8242)
		(end -159.929627 21.28012)
		(width 0.127)
		(layer "B.Cu")
		(net "CLK_100M_B2_N<2>")
	)
	(segment
		(start -153.292599 21.282599)
		(end -152.809999 20.799999)
		(width 0.127)
		(layer "B.Cu")
		(net "CLK_100M_B2_N<2>")
	)
	(segment
		(start -185.933484 23.217002)
		(end -185.909402 23.217002)
		(width 0.127)
		(layer "B.Cu")
		(net "CLK_100M_B2_N<2>")
	)
	(segment
		(start -186.603 23.886518)
		(end -185.933484 23.217002)
		(width 0.127)
		(layer "B.Cu")
		(net "CLK_100M_B2_N<2>")
	)
	(segment
		(start -156.425473 21.28012)
		(end -156.14936 21.004007)
		(width 0.127)
		(layer "B.Cu")
		(net "CLK_100M_B2_N<2>")
	)
	(segment
		(start -178.5166 15.8242)
		(end -165.385547 15.8242)
		(width 0.127)
		(layer "B.Cu")
		(net "CLK_100M_B2_N<2>")
	)
	(segment
		(start -187.460001 35.46)
		(end -186.9124 36.007601)
		(width 0.127)
		(layer "B.Cu")
		(net "CLK_100M_B2_N<2>")
	)
	(segment
		(start -156.14936 20.41144)
		(end -155.7455 20.00758)
		(width 0.127)
		(layer "B.Cu")
		(net "CLK_100M_B2_N<2>")
	)
	(segment
		(start -186.7854 36.007601)
		(end -186.6192 35.841402)
		(width 0.127)
		(layer "B.Cu")
		(net "CLK_100M_B2_N<2>")
	)
	(segment
		(start -159.929627 21.28012)
		(end -156.425473 21.28012)
		(width 0.127)
		(layer "B.Cu")
		(net "CLK_100M_B2_N<2>")
	)
	(segment
		(start -185.909402 23.217002)
		(end -178.5166 15.8242)
		(width 0.127)
		(layer "B.Cu")
		(net "CLK_100M_B2_N<2>")
	)
	(segment
		(start -155.349999 20.799999)
		(end -154.714999 21.434999)
		(width 0.127)
		(layer "F.Cu")
		(net "CLK_100M_B2_N<1>")
	)
	(via
		(at -155.349999 20.799999)
		(size 0.5588)
		(drill 0.254)
		(layers "F.Cu" "B.Cu")
		(net "CLK_100M_B2_N<1>")
	)
	(segment
		(start -186.723678 40.213953)
		(end -186.90605 40.213953)
		(width 0.127)
		(layer "In2.Cu")
		(net "CLK_100M_B2_N<1>")
	)
	(segment
		(start -186.5903 40.080575)
		(end -186.723678 40.213953)
		(width 0.127)
		(layer "In2.Cu")
		(net "CLK_100M_B2_N<1>")
	)
	(segment
		(start -155.838949 21.288949)
		(end -160.268188 21.288949)
		(width 0.127)
		(layer "In2.Cu")
		(net "CLK_100M_B2_N<1>")
	)
	(segment
		(start -186.5903 22.917165)
		(end -186.5903 40.080575)
		(width 0.127)
		(layer "In2.Cu")
		(net "CLK_100M_B2_N<1>")
	)
	(segment
		(start -160.268188 21.288949)
		(end -166.129729 15.427409)
		(width 0.127)
		(layer "In2.Cu")
		(net "CLK_100M_B2_N<1>")
	)
	(segment
		(start -166.129729 15.427409)
		(end -179.100544 15.427409)
		(width 0.127)
		(layer "In2.Cu")
		(net "CLK_100M_B2_N<1>")
	)
	(segment
		(start -155.349999 20.799999)
		(end -155.838949 21.288949)
		(width 0.127)
		(layer "In2.Cu")
		(net "CLK_100M_B2_N<1>")
	)
	(segment
		(start -179.100544 15.427409)
		(end -186.5903 22.917165)
		(width 0.127)
		(layer "In2.Cu")
		(net "CLK_100M_B2_N<1>")
	)
	(segment
		(start -186.90605 40.213953)
		(end -187.460001 39.660002)
		(width 0.127)
		(layer "In2.Cu")
		(net "CLK_100M_B2_N<1>")
	)
	(segment
		(start -186.619129 22.874138)
		(end -186.619129 44.241331)
		(width 0.127)
		(layer "F.Cu")
		(net "CLK_100M_B2_N<0>")
	)
	(segment
		(start -157.737599 21.917599)
		(end -159.175816 21.917599)
		(width 0.127)
		(layer "F.Cu")
		(net "CLK_100M_B2_N<0>")
	)
	(segment
		(start -165.599415 15.494)
		(end -179.238991 15.494)
		(width 0.127)
		(layer "F.Cu")
		(net "CLK_100M_B2_N<0>")
	)
	(segment
		(start -159.175816 21.917599)
		(end -165.599415 15.494)
		(width 0.127)
		(layer "F.Cu")
		(net "CLK_100M_B2_N<0>")
	)
	(segment
		(start -179.238991 15.494)
		(end -186.619129 22.874138)
		(width 0.127)
		(layer "F.Cu")
		(net "CLK_100M_B2_N<0>")
	)
	(segment
		(start -157.254999 21.434999)
		(end -157.737599 21.917599)
		(width 0.127)
		(layer "F.Cu")
		(net "CLK_100M_B2_N<0>")
	)
	(segment
		(start -186.9124 44.407602)
		(end -187.460001 43.860001)
		(width 0.127)
		(layer "F.Cu")
		(net "CLK_100M_B2_N<0>")
	)
	(segment
		(start -186.7854 44.407602)
		(end -186.9124 44.407602)
		(width 0.127)
		(layer "F.Cu")
		(net "CLK_100M_B2_N<0>")
	)
	(segment
		(start -186.619129 44.241331)
		(end -186.7854 44.407602)
		(width 0.127)
		(layer "F.Cu")
		(net "CLK_100M_B2_N<0>")
	)
	(segment
		(start -371.268559 22.069999)
		(end -371.269999 22.069999)
		(width 0.127)
		(layer "F.Cu")
		(net "CLK_100M_B1_P<3>")
	)
	(segment
		(start -370.634999 22.703559)
		(end -371.268559 22.069999)
		(width 0.127)
		(layer "F.Cu")
		(net "CLK_100M_B1_P<3>")
	)
	(segment
		(start -370.634999 22.704999)
		(end -370.634999 22.703559)
		(width 0.127)
		(layer "F.Cu")
		(net "CLK_100M_B1_P<3>")
	)
	(via
		(at -371.269999 22.069999)
		(size 0.5588)
		(drill 0.254)
		(layers "F.Cu" "B.Cu")
		(net "CLK_100M_B1_P<3>")
	)
	(segment
		(start -401.821307 17.2212)
		(end -387.128093 17.2212)
		(width 0.127)
		(layer "In5.Cu")
		(net "CLK_100M_B1_P<3>")
	)
	(segment
		(start -373.3165 21.29536)
		(end -373.030811 21.581049)
		(width 0.127)
		(layer "In5.Cu")
		(net "CLK_100M_B1_P<3>")
	)
	(segment
		(start -379.824907 22.05228)
		(end -378.072307 20.29968)
		(width 0.127)
		(layer "In5.Cu")
		(net "CLK_100M_B1_P<3>")
	)
	(segment
		(start -378.072307 20.29968)
		(end -373.5197 20.29968)
		(width 0.127)
		(layer "In5.Cu")
		(net "CLK_100M_B1_P<3>")
	)
	(segment
		(start -373.5197 20.29968)
		(end -373.3165 20.50288)
		(width 0.127)
		(layer "In5.Cu")
		(net "CLK_100M_B1_P<3>")
	)
	(segment
		(start -407.3271 22.726993)
		(end -401.821307 17.2212)
		(width 0.127)
		(layer "In5.Cu")
		(net "CLK_100M_B1_P<3>")
	)
	(segment
		(start -382.297013 22.05228)
		(end -379.824907 22.05228)
		(width 0.127)
		(layer "In5.Cu")
		(net "CLK_100M_B1_P<3>")
	)
	(segment
		(start -407.3271 31.775095)
		(end -407.3271 22.726993)
		(width 0.127)
		(layer "In5.Cu")
		(net "CLK_100M_B1_P<3>")
	)
	(segment
		(start -373.030811 21.581049)
		(end -371.758949 21.581049)
		(width 0.127)
		(layer "In5.Cu")
		(net "CLK_100M_B1_P<3>")
	)
	(segment
		(start -371.758949 21.581049)
		(end -371.269999 22.069999)
		(width 0.127)
		(layer "In5.Cu")
		(net "CLK_100M_B1_P<3>")
	)
	(segment
		(start -407.906052 32.106052)
		(end -407.658057 32.106052)
		(width 0.127)
		(layer "In5.Cu")
		(net "CLK_100M_B1_P<3>")
	)
	(segment
		(start -408.460001 32.660001)
		(end -407.906052 32.106052)
		(width 0.127)
		(layer "In5.Cu")
		(net "CLK_100M_B1_P<3>")
	)
	(segment
		(start -387.128093 17.2212)
		(end -382.297013 22.05228)
		(width 0.127)
		(layer "In5.Cu")
		(net "CLK_100M_B1_P<3>")
	)
	(segment
		(start -373.3165 20.50288)
		(end -373.3165 21.29536)
		(width 0.127)
		(layer "In5.Cu")
		(net "CLK_100M_B1_P<3>")
	)
	(segment
		(start -407.658057 32.106052)
		(end -407.3271 31.775095)
		(width 0.127)
		(layer "In5.Cu")
		(net "CLK_100M_B1_P<3>")
	)
	(segment
		(start -373.783921 22.069999)
		(end -373.174999 22.678921)
		(width 0.127)
		(layer "F.Cu")
		(net "CLK_100M_B1_P<2>")
	)
	(segment
		(start -373.174999 22.678921)
		(end -373.174999 22.704999)
		(width 0.127)
		(layer "F.Cu")
		(net "CLK_100M_B1_P<2>")
	)
	(segment
		(start -373.809999 22.069999)
		(end -373.783921 22.069999)
		(width 0.127)
		(layer "F.Cu")
		(net "CLK_100M_B1_P<2>")
	)
	(via
		(at -373.809999 22.069999)
		(size 0.5588)
		(drill 0.254)
		(layers "F.Cu" "B.Cu")
		(net "CLK_100M_B1_P<2>")
	)
	(segment
		(start -408.460001 36.86)
		(end -407.912402 36.312401)
		(width 0.127)
		(layer "B.Cu")
		(net "CLK_100M_B1_P<2>")
	)
	(segment
		(start -374.292599 21.587399)
		(end -373.809999 22.069999)
		(width 0.127)
		(layer "B.Cu")
		(net "CLK_100M_B1_P<2>")
	)
	(segment
		(start -375.8565 20.517373)
		(end -375.8565 21.1328)
		(width 0.127)
		(layer "B.Cu")
		(net "CLK_100M_B1_P<2>")
	)
	(segment
		(start -376.619247 20.31238)
		(end -376.061493 20.31238)
		(width 0.127)
		(layer "B.Cu")
		(net "CLK_100M_B1_P<2>")
	)
	(segment
		(start -407.3144 24.053053)
		(end -407.2982 24.036853)
		(width 0.127)
		(layer "B.Cu")
		(net "CLK_100M_B1_P<2>")
	)
	(segment
		(start -399.390347 16.129)
		(end -386.5118 16.129)
		(width 0.127)
		(layer "B.Cu")
		(net "CLK_100M_B1_P<2>")
	)
	(segment
		(start -376.84456 20.537693)
		(end -376.619247 20.31238)
		(width 0.127)
		(layer "B.Cu")
		(net "CLK_100M_B1_P<2>")
	)
	(segment
		(start -407.912402 36.312401)
		(end -407.659147 36.312401)
		(width 0.127)
		(layer "B.Cu")
		(net "CLK_100M_B1_P<2>")
	)
	(segment
		(start -406.783149 23.521802)
		(end -399.390347 16.129)
		(width 0.127)
		(layer "B.Cu")
		(net "CLK_100M_B1_P<2>")
	)
	(segment
		(start -407.659147 36.312401)
		(end -407.3144 35.967655)
		(width 0.127)
		(layer "B.Cu")
		(net "CLK_100M_B1_P<2>")
	)
	(segment
		(start -407.2982 24.036853)
		(end -407.2982 24.012771)
		(width 0.127)
		(layer "B.Cu")
		(net "CLK_100M_B1_P<2>")
	)
	(segment
		(start -386.5118 16.129)
		(end -381.05588 21.58492)
		(width 0.127)
		(layer "B.Cu")
		(net "CLK_100M_B1_P<2>")
	)
	(segment
		(start -375.401901 21.587399)
		(end -374.292599 21.587399)
		(width 0.127)
		(layer "B.Cu")
		(net "CLK_100M_B1_P<2>")
	)
	(segment
		(start -407.2982 24.012771)
		(end -406.807231 23.521802)
		(width 0.127)
		(layer "B.Cu")
		(net "CLK_100M_B1_P<2>")
	)
	(segment
		(start -375.8565 21.1328)
		(end -375.401901 21.587399)
		(width 0.127)
		(layer "B.Cu")
		(net "CLK_100M_B1_P<2>")
	)
	(segment
		(start -406.807231 23.521802)
		(end -406.783149 23.521802)
		(width 0.127)
		(layer "B.Cu")
		(net "CLK_100M_B1_P<2>")
	)
	(segment
		(start -381.05588 21.58492)
		(end -377.29922 21.58492)
		(width 0.127)
		(layer "B.Cu")
		(net "CLK_100M_B1_P<2>")
	)
	(segment
		(start -376.84456 21.13026)
		(end -376.84456 20.537693)
		(width 0.127)
		(layer "B.Cu")
		(net "CLK_100M_B1_P<2>")
	)
	(segment
		(start -376.061493 20.31238)
		(end -375.8565 20.517373)
		(width 0.127)
		(layer "B.Cu")
		(net "CLK_100M_B1_P<2>")
	)
	(segment
		(start -407.3144 35.967655)
		(end -407.3144 24.053053)
		(width 0.127)
		(layer "B.Cu")
		(net "CLK_100M_B1_P<2>")
	)
	(segment
		(start -377.29922 21.58492)
		(end -376.84456 21.13026)
		(width 0.127)
		(layer "B.Cu")
		(net "CLK_100M_B1_P<2>")
	)
	(segment
		(start -375.716353 22.704999)
		(end -375.714999 22.704999)
		(width 0.127)
		(layer "F.Cu")
		(net "CLK_100M_B1_P<1>")
	)
	(segment
		(start -376.349999 22.071353)
		(end -375.716353 22.704999)
		(width 0.127)
		(layer "F.Cu")
		(net "CLK_100M_B1_P<1>")
	)
	(segment
		(start -376.349999 22.069999)
		(end -376.349999 22.071353)
		(width 0.127)
		(layer "F.Cu")
		(net "CLK_100M_B1_P<1>")
	)
	(via
		(at -376.349999 22.069999)
		(size 0.5588)
		(drill 0.254)
		(layers "F.Cu" "B.Cu")
		(net "CLK_100M_B1_P<1>")
	)
	(segment
		(start -407.602685 40.506053)
		(end -407.906052 40.506053)
		(width 0.127)
		(layer "In2.Cu")
		(net "CLK_100M_B1_P<1>")
	)
	(segment
		(start -376.349999 22.069999)
		(end -376.838949 21.581049)
		(width 0.127)
		(layer "In2.Cu")
		(net "CLK_100M_B1_P<1>")
	)
	(segment
		(start -407.906052 40.506053)
		(end -408.460001 41.060002)
		(width 0.127)
		(layer "In2.Cu")
		(net "CLK_100M_B1_P<1>")
	)
	(segment
		(start -381.389181 21.581049)
		(end -385.69823 17.272)
		(width 0.127)
		(layer "In2.Cu")
		(net "CLK_100M_B1_P<1>")
	)
	(segment
		(start -385.69823 17.272)
		(end -401.532042 17.272)
		(width 0.127)
		(layer "In2.Cu")
		(net "CLK_100M_B1_P<1>")
	)
	(segment
		(start -401.532042 17.272)
		(end -407.2982 23.038158)
		(width 0.127)
		(layer "In2.Cu")
		(net "CLK_100M_B1_P<1>")
	)
	(segment
		(start -407.2982 23.038158)
		(end -407.2982 40.201568)
		(width 0.127)
		(layer "In2.Cu")
		(net "CLK_100M_B1_P<1>")
	)
	(segment
		(start -376.838949 21.581049)
		(end -381.389181 21.581049)
		(width 0.127)
		(layer "In2.Cu")
		(net "CLK_100M_B1_P<1>")
	)
	(segment
		(start -407.2982 40.201568)
		(end -407.602685 40.506053)
		(width 0.127)
		(layer "In2.Cu")
		(net "CLK_100M_B1_P<1>")
	)
	(segment
		(start -407.659147 44.712402)
		(end -407.912402 44.712402)
		(width 0.127)
		(layer "F.Cu")
		(net "CLK_100M_B1_P<0>")
	)
	(segment
		(start -386.344668 16.1798)
		(end -400.493738 16.1798)
		(width 0.127)
		(layer "F.Cu")
		(net "CLK_100M_B1_P<0>")
	)
	(segment
		(start -378.737599 22.222399)
		(end -380.302069 22.222399)
		(width 0.127)
		(layer "F.Cu")
		(net "CLK_100M_B1_P<0>")
	)
	(segment
		(start -380.302069 22.222399)
		(end -386.344668 16.1798)
		(width 0.127)
		(layer "F.Cu")
		(net "CLK_100M_B1_P<0>")
	)
	(segment
		(start -400.493738 16.1798)
		(end -407.314329 23.000391)
		(width 0.127)
		(layer "F.Cu")
		(net "CLK_100M_B1_P<0>")
	)
	(segment
		(start -407.912402 44.712402)
		(end -408.460001 45.260001)
		(width 0.127)
		(layer "F.Cu")
		(net "CLK_100M_B1_P<0>")
	)
	(segment
		(start -407.314329 44.367585)
		(end -407.659147 44.712402)
		(width 0.127)
		(layer "F.Cu")
		(net "CLK_100M_B1_P<0>")
	)
	(segment
		(start -407.314329 23.000391)
		(end -407.314329 44.367585)
		(width 0.127)
		(layer "F.Cu")
		(net "CLK_100M_B1_P<0>")
	)
	(segment
		(start -378.254999 22.704999)
		(end -378.737599 22.222399)
		(width 0.127)
		(layer "F.Cu")
		(net "CLK_100M_B1_P<0>")
	)
	(segment
		(start -371.269999 20.799999)
		(end -371.269999 20.819641)
		(width 0.127)
		(layer "F.Cu")
		(net "CLK_100M_B1_N<3>")
	)
	(segment
		(start -371.269999 20.819641)
		(end -370.654641 21.434999)
		(width 0.127)
		(layer "F.Cu")
		(net "CLK_100M_B1_N<3>")
	)
	(segment
		(start -370.654641 21.434999)
		(end -370.634999 21.434999)
		(width 0.127)
		(layer "F.Cu")
		(net "CLK_100M_B1_N<3>")
	)
	(via
		(at -371.269999 20.799999)
		(size 0.5588)
		(drill 0.254)
		(layers "F.Cu" "B.Cu")
		(net "CLK_100M_B1_N<3>")
	)
	(segment
		(start -382.17602 21.76018)
		(end -379.9459 21.76018)
		(width 0.127)
		(layer "In5.Cu")
		(net "CLK_100M_B1_N<3>")
	)
	(segment
		(start -371.758949 21.288949)
		(end -371.269999 20.799999)
		(width 0.127)
		(layer "In5.Cu")
		(net "CLK_100M_B1_N<3>")
	)
	(segment
		(start -401.9423 16.9291)
		(end -387.0071 16.9291)
		(width 0.127)
		(layer "In5.Cu")
		(net "CLK_100M_B1_N<3>")
	)
	(segment
		(start -373.398707 20.00758)
		(end -373.0244 20.381887)
		(width 0.127)
		(layer "In5.Cu")
		(net "CLK_100M_B1_N<3>")
	)
	(segment
		(start -407.77905 31.813952)
		(end -407.6192 31.654102)
		(width 0.127)
		(layer "In5.Cu")
		(net "CLK_100M_B1_N<3>")
	)
	(segment
		(start -407.6192 31.654102)
		(end -407.6192 22.606)
		(width 0.127)
		(layer "In5.Cu")
		(net "CLK_100M_B1_N<3>")
	)
	(segment
		(start -378.1933 20.00758)
		(end -373.398707 20.00758)
		(width 0.127)
		(layer "In5.Cu")
		(net "CLK_100M_B1_N<3>")
	)
	(segment
		(start -373.0244 20.381887)
		(end -373.0244 21.174367)
		(width 0.127)
		(layer "In5.Cu")
		(net "CLK_100M_B1_N<3>")
	)
	(segment
		(start -408.460001 31.260001)
		(end -407.90605 31.813952)
		(width 0.127)
		(layer "In5.Cu")
		(net "CLK_100M_B1_N<3>")
	)
	(segment
		(start -407.6192 22.606)
		(end -401.9423 16.9291)
		(width 0.127)
		(layer "In5.Cu")
		(net "CLK_100M_B1_N<3>")
	)
	(segment
		(start -372.909818 21.288949)
		(end -371.758949 21.288949)
		(width 0.127)
		(layer "In5.Cu")
		(net "CLK_100M_B1_N<3>")
	)
	(segment
		(start -379.9459 21.76018)
		(end -378.1933 20.00758)
		(width 0.127)
		(layer "In5.Cu")
		(net "CLK_100M_B1_N<3>")
	)
	(segment
		(start -387.0071 16.9291)
		(end -382.17602 21.76018)
		(width 0.127)
		(layer "In5.Cu")
		(net "CLK_100M_B1_N<3>")
	)
	(segment
		(start -407.90605 31.813952)
		(end -407.77905 31.813952)
		(width 0.127)
		(layer "In5.Cu")
		(net "CLK_100M_B1_N<3>")
	)
	(segment
		(start -373.0244 21.174367)
		(end -372.909818 21.288949)
		(width 0.127)
		(layer "In5.Cu")
		(net "CLK_100M_B1_N<3>")
	)
	(segment
		(start -373.809999 20.799999)
		(end -373.174999 21.434999)
		(width 0.127)
		(layer "F.Cu")
		(net "CLK_100M_B1_N<2>")
	)
	(via
		(at -373.809999 20.799999)
		(size 0.5588)
		(drill 0.254)
		(layers "F.Cu" "B.Cu")
		(net "CLK_100M_B1_N<2>")
	)
	(segment
		(start -375.5517 21.006547)
		(end -375.275648 21.282599)
		(width 0.127)
		(layer "B.Cu")
		(net "CLK_100M_B1_N<2>")
	)
	(segment
		(start -377.14936 21.004007)
		(end -377.14936 20.41144)
		(width 0.127)
		(layer "B.Cu")
		(net "CLK_100M_B1_N<2>")
	)
	(segment
		(start -375.275648 21.282599)
		(end -374.292599 21.282599)
		(width 0.127)
		(layer "B.Cu")
		(net "CLK_100M_B1_N<2>")
	)
	(segment
		(start -407.9124 36.007601)
		(end -407.7854 36.007601)
		(width 0.127)
		(layer "B.Cu")
		(net "CLK_100M_B1_N<2>")
	)
	(segment
		(start -377.425473 21.28012)
		(end -377.14936 21.004007)
		(width 0.127)
		(layer "B.Cu")
		(net "CLK_100M_B1_N<2>")
	)
	(segment
		(start -407.603 23.886518)
		(end -406.933484 23.217002)
		(width 0.127)
		(layer "B.Cu")
		(net "CLK_100M_B1_N<2>")
	)
	(segment
		(start -407.6192 23.9268)
		(end -407.603 23.9106)
		(width 0.127)
		(layer "B.Cu")
		(net "CLK_100M_B1_N<2>")
	)
	(segment
		(start -408.460001 35.46)
		(end -407.9124 36.007601)
		(width 0.127)
		(layer "B.Cu")
		(net "CLK_100M_B1_N<2>")
	)
	(segment
		(start -375.93524 20.00758)
		(end -375.5517 20.39112)
		(width 0.127)
		(layer "B.Cu")
		(net "CLK_100M_B1_N<2>")
	)
	(segment
		(start -407.603 23.9106)
		(end -407.603 23.886518)
		(width 0.127)
		(layer "B.Cu")
		(net "CLK_100M_B1_N<2>")
	)
	(segment
		(start -406.933484 23.217002)
		(end -406.909402 23.217002)
		(width 0.127)
		(layer "B.Cu")
		(net "CLK_100M_B1_N<2>")
	)
	(segment
		(start -407.6192 35.841402)
		(end -407.6192 23.9268)
		(width 0.127)
		(layer "B.Cu")
		(net "CLK_100M_B1_N<2>")
	)
	(segment
		(start -376.7455 20.00758)
		(end -375.93524 20.00758)
		(width 0.127)
		(layer "B.Cu")
		(net "CLK_100M_B1_N<2>")
	)
	(segment
		(start -407.7854 36.007601)
		(end -407.6192 35.841402)
		(width 0.127)
		(layer "B.Cu")
		(net "CLK_100M_B1_N<2>")
	)
	(segment
		(start -386.385547 15.8242)
		(end -380.929627 21.28012)
		(width 0.127)
		(layer "B.Cu")
		(net "CLK_100M_B1_N<2>")
	)
	(segment
		(start -399.5166 15.8242)
		(end -386.385547 15.8242)
		(width 0.127)
		(layer "B.Cu")
		(net "CLK_100M_B1_N<2>")
	)
	(segment
		(start -375.5517 20.39112)
		(end -375.5517 21.006547)
		(width 0.127)
		(layer "B.Cu")
		(net "CLK_100M_B1_N<2>")
	)
	(segment
		(start -380.929627 21.28012)
		(end -377.425473 21.28012)
		(width 0.127)
		(layer "B.Cu")
		(net "CLK_100M_B1_N<2>")
	)
	(segment
		(start -374.292599 21.282599)
		(end -373.809999 20.799999)
		(width 0.127)
		(layer "B.Cu")
		(net "CLK_100M_B1_N<2>")
	)
	(segment
		(start -377.14936 20.41144)
		(end -376.7455 20.00758)
		(width 0.127)
		(layer "B.Cu")
		(net "CLK_100M_B1_N<2>")
	)
	(segment
		(start -406.909402 23.217002)
		(end -399.5166 15.8242)
		(width 0.127)
		(layer "B.Cu")
		(net "CLK_100M_B1_N<2>")
	)
	(segment
		(start -376.346527 20.799999)
		(end -375.714999 21.431527)
		(width 0.127)
		(layer "F.Cu")
		(net "CLK_100M_B1_N<1>")
	)
	(segment
		(start -375.714999 21.431527)
		(end -375.714999 21.434999)
		(width 0.127)
		(layer "F.Cu")
		(net "CLK_100M_B1_N<1>")
	)
	(segment
		(start -376.349999 20.799999)
		(end -376.346527 20.799999)
		(width 0.127)
		(layer "F.Cu")
		(net "CLK_100M_B1_N<1>")
	)
	(via
		(at -376.349999 20.799999)
		(size 0.5588)
		(drill 0.254)
		(layers "F.Cu" "B.Cu")
		(net "CLK_100M_B1_N<1>")
	)
	(segment
		(start -381.268188 21.288949)
		(end -385.577237 16.9799)
		(width 0.127)
		(layer "In2.Cu")
		(net "CLK_100M_B1_N<1>")
	)
	(segment
		(start -407.5903 40.080575)
		(end -407.723678 40.213953)
		(width 0.127)
		(layer "In2.Cu")
		(net "CLK_100M_B1_N<1>")
	)
	(segment
		(start -385.577237 16.9799)
		(end -401.653035 16.9799)
		(width 0.127)
		(layer "In2.Cu")
		(net "CLK_100M_B1_N<1>")
	)
	(segment
		(start -401.653035 16.9799)
		(end -407.5903 22.917165)
		(width 0.127)
		(layer "In2.Cu")
		(net "CLK_100M_B1_N<1>")
	)
	(segment
		(start -407.5903 22.917165)
		(end -407.5903 40.080575)
		(width 0.127)
		(layer "In2.Cu")
		(net "CLK_100M_B1_N<1>")
	)
	(segment
		(start -407.723678 40.213953)
		(end -407.90605 40.213953)
		(width 0.127)
		(layer "In2.Cu")
		(net "CLK_100M_B1_N<1>")
	)
	(segment
		(start -376.349999 20.799999)
		(end -376.838949 21.288949)
		(width 0.127)
		(layer "In2.Cu")
		(net "CLK_100M_B1_N<1>")
	)
	(segment
		(start -376.838949 21.288949)
		(end -381.268188 21.288949)
		(width 0.127)
		(layer "In2.Cu")
		(net "CLK_100M_B1_N<1>")
	)
	(segment
		(start -407.90605 40.213953)
		(end -408.460001 39.660002)
		(width 0.127)
		(layer "In2.Cu")
		(net "CLK_100M_B1_N<1>")
	)
	(segment
		(start -380.175816 21.917599)
		(end -386.218415 15.875)
		(width 0.127)
		(layer "F.Cu")
		(net "CLK_100M_B1_N<0>")
	)
	(segment
		(start -407.619129 44.241331)
		(end -407.7854 44.407602)
		(width 0.127)
		(layer "F.Cu")
		(net "CLK_100M_B1_N<0>")
	)
	(segment
		(start -378.254999 21.434999)
		(end -378.737599 21.917599)
		(width 0.127)
		(layer "F.Cu")
		(net "CLK_100M_B1_N<0>")
	)
	(segment
		(start -378.737599 21.917599)
		(end -380.175816 21.917599)
		(width 0.127)
		(layer "F.Cu")
		(net "CLK_100M_B1_N<0>")
	)
	(segment
		(start -400.619991 15.875)
		(end -407.619129 22.874138)
		(width 0.127)
		(layer "F.Cu")
		(net "CLK_100M_B1_N<0>")
	)
	(segment
		(start -407.619129 22.874138)
		(end -407.619129 44.241331)
		(width 0.127)
		(layer "F.Cu")
		(net "CLK_100M_B1_N<0>")
	)
	(segment
		(start -386.218415 15.875)
		(end -400.619991 15.875)
		(width 0.127)
		(layer "F.Cu")
		(net "CLK_100M_B1_N<0>")
	)
	(segment
		(start -407.9124 44.407602)
		(end -408.460001 43.860001)
		(width 0.127)
		(layer "F.Cu")
		(net "CLK_100M_B1_N<0>")
	)
	(segment
		(start -407.7854 44.407602)
		(end -407.9124 44.407602)
		(width 0.127)
		(layer "F.Cu")
		(net "CLK_100M_B1_N<0>")
	)
	(segment
		(start -80.787001 10.668)
		(end -81.7118 10.668)
		(width 0.1016)
		(layer "F.Cu")
		(net "BLADE_B2_MATED_N")
	)
	(via
		(at -81.7118 10.668)
		(size 0.5588)
		(drill 0.254)
		(layers "F.Cu" "B.Cu")
		(net "BLADE_B2_MATED_N")
	)
	(segment
		(start -84.4042 13.3604)
		(end -81.7118 10.668)
		(width 0.12954)
		(layer "In2.Cu")
		(net "BLADE_B2_MATED_N")
	)
	(segment
		(start -81.04 34.16)
		(end -81.04 32.879)
		(width 0.12954)
		(layer "In2.Cu")
		(net "BLADE_B2_MATED_N")
	)
	(segment
		(start -84.4042 29.5148)
		(end -84.4042 13.3604)
		(width 0.12954)
		(layer "In2.Cu")
		(net "BLADE_B2_MATED_N")
	)
	(segment
		(start -81.04 32.879)
		(end -84.4042 29.5148)
		(width 0.12954)
		(layer "In2.Cu")
		(net "BLADE_B2_MATED_N")
	)
	(segment
		(start -301.640001 10.287)
		(end -302.5648 10.287)
		(width 0.1016)
		(layer "F.Cu")
		(net "BLADE_B1_MATED_N<1>")
	)
	(via
		(at -302.5648 10.287)
		(size 0.5588)
		(drill 0.254)
		(layers "F.Cu" "B.Cu")
		(net "BLADE_B1_MATED_N<1>")
	)
	(segment
		(start -304.546 28.8798)
		(end -304.546 25.9334)
		(width 0.12954)
		(layer "In2.Cu")
		(net "BLADE_B1_MATED_N<1>")
	)
	(segment
		(start -305.5112 12.7254)
		(end -303.0728 10.287)
		(width 0.12954)
		(layer "In2.Cu")
		(net "BLADE_B1_MATED_N<1>")
	)
	(segment
		(start -302.04 34.16)
		(end -302.04 31.3858)
		(width 0.12954)
		(layer "In2.Cu")
		(net "BLADE_B1_MATED_N<1>")
	)
	(segment
		(start -303.0728 10.287)
		(end -302.5648 10.287)
		(width 0.12954)
		(layer "In2.Cu")
		(net "BLADE_B1_MATED_N<1>")
	)
	(segment
		(start -305.5112 24.9682)
		(end -305.5112 12.7254)
		(width 0.12954)
		(layer "In2.Cu")
		(net "BLADE_B1_MATED_N<1>")
	)
	(segment
		(start -302.04 31.3858)
		(end -304.546 28.8798)
		(width 0.12954)
		(layer "In2.Cu")
		(net "BLADE_B1_MATED_N<1>")
	)
	(segment
		(start -304.546 25.9334)
		(end -305.5112 24.9682)
		(width 0.12954)
		(layer "In2.Cu")
		(net "BLADE_B1_MATED_N<1>")
	)
	(zone
		(layer "F.Cu")
		(hatch none 0.5)
		(connect_pads
			(clearance 0)
		)
		(min_thickness 0.25)
		(keepout
			(tracks allowed)
			(vias allowed)
			(pads allowed)
			(copperpour allowed)
			(footprints allowed)
		)
		(placement
			(enabled no)
			(sheetname "")
		)
		(fill
			(thermal_gap 0.5)
			(thermal_bridge_width 0.5)
			(island_removal_mode 0)
		)
		(polygon
			(pts
				(arc
					(start -160.117401 39.359611)
					(mid -171.438481 39.359611)
					(end -160.117401 39.359611)
				)
			)
		)
	)
	(zone
		(layer "F.Cu")
		(hatch none 0.5)
		(connect_pads
			(clearance 0)
		)
		(min_thickness 0.25)
		(keepout
			(tracks allowed)
			(vias allowed)
			(pads allowed)
			(copperpour allowed)
			(footprints not_allowed)
		)
		(placement
			(enabled no)
			(sheetname "")
		)
		(fill
			(thermal_gap 0.5)
			(thermal_bridge_width 0.5)
			(island_removal_mode 0)
		)
		(polygon
			(pts
				(arc
					(start -383.020001 39.36)
					(mid -386.770001 35.61)
					(end -390.519999 39.36)
				)
				(arc
					(start -390.519999 39.36)
					(mid -386.770001 43.109998)
					(end -383.020001 39.36)
				)
			)
		)
	)
	(zone
		(net "P12V")
		(layer "F.Cu")
		(hatch none 0.5)
		(connect_pads
			(clearance 0.5)
		)
		(min_thickness 0.25)
		(fill yes
			(thermal_gap 0.5)
			(thermal_bridge_width 0.5)
			(island_removal_mode 0)
		)
		(polygon
			(pts
				(xy -369.2271 46.6979) (xy -369.697 46.228) (xy -369.697 17.1704) (xy -371.856 15.0114) (xy -410.6418 15.0114)
				(xy -411.2006 14.4526)
				(arc
					(start -411.2006 5.5372)
					(mid -410.908184 5.22464)
					(end -410.801998 4.810001)
				)
				(xy -410.801998 -4.129578) (xy -410.593256 -4.33832) (xy -391.69594 -4.33832) (xy -391.69594 4.46786)
				(xy -391.69467 4.46913) (xy -391.69467 5.33019) (xy -390.4742 6.55066) (xy -371.729 6.55066) (xy -371.54866 6.55066)
				(xy -370.967 5.969) (xy -370.713 5.969) (xy -367.091199 5.969) (xy -366.903 5.969) (xy -365.567199 4.633199)
				(xy -365.567199 4.445)
				(arc
					(start -365.567199 -2.34)
					(mid -365.07303 -3.53303)
					(end -363.880001 -4.0272)
				)
				(xy -336.677 -4.0272) (xy -336.677 20.701) (xy -335.915 21.463) (xy -332.105 21.463) (xy -327.0758 26.4922)
				(xy -327.0758 46.1137) (xy -327.66 46.6979)
			)
		)
		(polygon
			(pts
				(arc
					(start -336.131002 34.132657)
					(mid -336.250049 34.215422)
					(end -336.369096 34.132657)
				)
				(arc
					(start -336.369096 34.132657)
					(mid -336.537553 33.847154)
					(end -336.794658 33.637901)
				)
				(arc
					(start -336.794658 33.637901)
					(mid -336.856079 33.495025)
					(end -336.733119 33.399806)
				)
				(xy -336.310244 33.399806)
				(arc
					(start -336.310244 32.976932)
					(mid -336.215025 32.853973)
					(end -336.07215 32.915393)
				)
				(arc
					(start -336.07215 32.915393)
					(mid -335.862896 33.172497)
					(end -335.577393 33.340954)
				)
				(arc
					(start -335.577393 33.340954)
					(mid -335.494627 33.460002)
					(end -335.577393 33.579049)
				)
				(arc
					(start -335.577393 33.579049)
					(mid -335.91459 33.79546)
					(end -336.131002 34.132657)
				)
			)
		)
		(polygon
			(pts
				(arc
					(start -336.131002 36.132656)
					(mid -336.250049 36.215421)
					(end -336.369096 36.132656)
				)
				(arc
					(start -336.369096 36.132656)
					(mid -336.585506 35.795459)
					(end -336.922702 35.579047)
				)
				(arc
					(start -336.922702 35.579047)
					(mid -337.005463 35.460002)
					(end -336.922702 35.340955)
				)
				(arc
					(start -336.922702 35.340955)
					(mid -336.585506 35.124544)
					(end -336.369096 34.787347)
				)
				(arc
					(start -336.369096 34.787347)
					(mid -336.250049 34.704582)
					(end -336.131002 34.787347)
				)
				(arc
					(start -336.131002 34.787347)
					(mid -335.914592 35.124544)
					(end -335.577396 35.340955)
				)
				(arc
					(start -335.577396 35.340955)
					(mid -335.494632 35.460002)
					(end -335.577396 35.579047)
				)
				(arc
					(start -335.577396 35.579047)
					(mid -335.914593 35.795458)
					(end -336.131002 36.132656)
				)
			)
		)
		(polygon
			(pts
				(arc
					(start -336.131002 42.132656)
					(mid -336.250049 42.215421)
					(end -336.369096 42.132656)
				)
				(arc
					(start -336.369096 42.132656)
					(mid -336.585507 41.795459)
					(end -336.922704 41.579048)
				)
				(arc
					(start -336.922704 41.579048)
					(mid -337.005469 41.460001)
					(end -336.922704 41.340954)
				)
				(arc
					(start -336.922704 41.340954)
					(mid -336.585506 41.124543)
					(end -336.369096 40.787345)
				)
				(arc
					(start -336.369096 40.787345)
					(mid -336.250049 40.70458)
					(end -336.131002 40.787345)
				)
				(arc
					(start -336.131002 40.787345)
					(mid -335.914591 41.124543)
					(end -335.577393 41.340954)
				)
				(arc
					(start -335.577393 41.340954)
					(mid -335.494628 41.460001)
					(end -335.577393 41.579048)
				)
				(arc
					(start -335.577393 41.579048)
					(mid -335.91459 41.795459)
					(end -336.131002 42.132656)
				)
			)
		)
		(polygon
			(pts
				(arc
					(start -336.131002 44.132655)
					(mid -336.250049 44.21542)
					(end -336.369096 44.132655)
				)
				(arc
					(start -336.369096 44.132655)
					(mid -336.585506 43.795458)
					(end -336.922702 43.579047)
				)
				(arc
					(start -336.922702 43.579047)
					(mid -337.005464 43.460002)
					(end -336.922702 43.340955)
				)
				(arc
					(start -336.922702 43.340955)
					(mid -336.585505 43.124544)
					(end -336.369096 42.787346)
				)
				(arc
					(start -336.369096 42.787346)
					(mid -336.250049 42.704581)
					(end -336.131002 42.787346)
				)
				(arc
					(start -336.131002 42.787346)
					(mid -335.914592 43.124543)
					(end -335.577396 43.340955)
				)
				(arc
					(start -335.577396 43.340955)
					(mid -335.494633 43.460002)
					(end -335.577396 43.579047)
				)
				(arc
					(start -335.577396 43.579047)
					(mid -335.914592 43.795458)
					(end -336.131002 44.132655)
				)
			)
		)
	)
	(zone
		(net "GND")
		(layer "F.Cu")
		(hatch none 0.5)
		(connect_pads
			(clearance 0.5)
		)
		(min_thickness 0.25)
		(fill yes
			(thermal_gap 0.5)
			(thermal_bridge_width 0.5)
			(island_removal_mode 0)
		)
		(polygon
			(pts
				(arc
					(start -169.849117 38.193924)
					(mid -161.5282 39.357405)
					(end -169.849117 40.520882)
				)
			)
		)
	)
	(zone
		(layer "F.Cu")
		(hatch none 0.5)
		(connect_pads
			(clearance 0.5)
		)
		(min_thickness 0.25)
		(fill
			(thermal_gap 0.5)
			(thermal_bridge_width 0.5)
			(island_removal_mode 0)
		)
		(polygon
			(pts
				(xy -63.4238 45.974) (xy -63.42126 41.69918) (xy -63.4238 41.69664) (xy -61.722 41.69664) (xy -61.40704 42.0116)
				(xy -61.40704 44.57446) (xy -62.48908 44.57446) (xy -62.484 45.212) (xy -62.738 45.466) (xy -62.738 45.974)
			)
		)
	)
	(zone
		(net "P3V3_40G_B1_VCC_RX")
		(layer "F.Cu")
		(hatch none 0.5)
		(connect_pads
			(clearance 0.5)
		)
		(min_thickness 0.25)
		(fill yes
			(thermal_gap 0.5)
			(thermal_bridge_width 0.5)
			(island_removal_mode 0)
		)
		(polygon
			(pts
				(xy -316.27064 41.34104) (xy -316.62624 41.34104) (xy -316.62624 39.39286) (xy -316.9158 39.1033)
				(xy -316.9158 38.8366) (xy -316.6872 38.608) (xy -316.2046 38.608) (xy -316.2046 39.3065) (xy -316.27064 39.37254)
			)
		)
	)
	(zone
		(layer "F.Cu")
		(hatch none 0.5)
		(connect_pads
			(clearance 0)
		)
		(min_thickness 0.25)
		(keepout
			(tracks allowed)
			(vias allowed)
			(pads allowed)
			(copperpour allowed)
			(footprints allowed)
		)
		(placement
			(enabled no)
			(sheetname "")
		)
		(fill
			(thermal_gap 0.5)
			(thermal_bridge_width 0.5)
			(island_removal_mode 0)
		)
		(polygon
			(pts
				(xy -380.79172 17.49044) (xy -370.1415 17.49044) (xy -370.1415 43.87342) (xy -380.79172 43.87342)
			)
		)
	)
	(zone
		(layer "F.Cu")
		(hatch none 0.5)
		(connect_pads
			(clearance 0.5)
		)
		(min_thickness 0.25)
		(fill
			(thermal_gap 0.5)
			(thermal_bridge_width 0.5)
			(island_removal_mode 0)
		)
		(polygon
			(pts
				(xy -58.80608 45.974) (xy -58.80608 41.70934) (xy -58.80354 41.7068) (xy -60.50534 41.7068) (xy -60.8203 42.02176)
				(xy -60.8203 44.58462) (xy -60.198 44.577) (xy -59.563 45.212) (xy -59.563 45.974)
			)
		)
	)
	(zone
		(layer "F.Cu")
		(hatch none 0.5)
		(connect_pads
			(clearance 0)
		)
		(min_thickness 0.25)
		(keepout
			(tracks allowed)
			(vias allowed)
			(pads allowed)
			(copperpour allowed)
			(footprints not_allowed)
		)
		(placement
			(enabled no)
			(sheetname "")
		)
		(fill
			(thermal_gap 0.5)
			(thermal_bridge_width 0.5)
			(island_removal_mode 0)
		)
		(polygon
			(pts
				(arc
					(start -358.459999 30.999999)
					(mid -361.460001 27.999997)
					(end -364.46 30.999999)
				)
				(arc
					(start -364.46 37)
					(mid -361.460001 39.999999)
					(end -358.459999 37)
				)
			)
		)
	)
	(zone
		(net "P3V3_10G_B2_VCCR")
		(layer "F.Cu")
		(hatch none 0.5)
		(connect_pads
			(clearance 0.5)
		)
		(min_thickness 0.25)
		(fill yes
			(thermal_gap 0.5)
			(thermal_bridge_width 0.5)
			(island_removal_mode 0)
		)
		(polygon
			(pts
				(xy -62.20206 36.17468) (xy -61.69914 36.17468) (xy -61.69914 32.62122) (xy -61.849 32.47136) (xy -62.31636 32.47136)
				(xy -62.4586 32.6136) (xy -62.4586 33.89376) (xy -62.20206 34.1503)
			)
		)
	)
	(zone
		(net "P3V3_40G_B1_VCC_RX")
		(layer "F.Cu")
		(hatch none 0.5)
		(connect_pads
			(clearance 0.5)
		)
		(min_thickness 0.25)
		(fill yes
			(thermal_gap 0.5)
			(thermal_bridge_width 0.5)
			(island_removal_mode 0)
		)
		(polygon
			(pts
				(xy -270.1671 -0.0889) (xy -267.97 -0.0889) (xy -267.373105 0.507995) (xy -266.954005 0.507995)
				(xy -266.5857 0.8763) (xy -266.5857 1.8415) (xy -266.4587 1.9685) (xy -266.4587 2.9464) (xy -267.6906 2.9464)
				(xy -267.8811 2.7559) (xy -270.256 2.7559) (xy -270.383 2.6289) (xy -270.383 0.127)
			)
		)
	)
	(zone
		(layer "F.Cu")
		(hatch none 0.5)
		(connect_pads
			(clearance 0)
		)
		(min_thickness 0.25)
		(keepout
			(tracks not_allowed)
			(vias allowed)
			(pads allowed)
			(copperpour not_allowed)
			(footprints allowed)
		)
		(placement
			(enabled no)
			(sheetname "")
		)
		(fill
			(thermal_gap 0.5)
			(thermal_bridge_width 0.5)
			(island_removal_mode 0)
		)
		(polygon
			(pts
				(arc
					(start -145.460001 29.46)
					(mid -142.460002 32.459999)
					(end -139.46 29.46)
				)
				(arc
					(start -139.46 23.459999)
					(mid -142.460002 20.459997)
					(end -145.460001 23.459999)
				)
			)
		)
	)
	(zone
		(net "P3V3_10G_B1_VCCR")
		(layer "F.Cu")
		(hatch none 0.5)
		(connect_pads
			(clearance 0.5)
		)
		(min_thickness 0.25)
		(fill yes
			(thermal_gap 0.5)
			(thermal_bridge_width 0.5)
			(island_removal_mode 0)
		)
		(polygon
			(pts
				(xy -283.1973 36.1696) (xy -282.69438 36.1696) (xy -282.69438 32.6263) (xy -282.8544 32.46628) (xy -283.29128 32.46628)
				(xy -283.464 32.639) (xy -283.464 33.88868) (xy -283.1973 34.15538)
			)
		)
	)
	(zone
		(net "GND")
		(layer "F.Cu")
		(hatch none 0.5)
		(connect_pads
			(clearance 0.5)
		)
		(min_thickness 0.25)
		(fill yes
			(thermal_gap 0.5)
			(thermal_bridge_width 0.5)
			(island_removal_mode 0)
		)
		(polygon
			(pts
				(arc
					(start -103.759 46.775479)
					(mid -104.034822 46.679671)
					(end -104.324998 46.647199)
				)
				(xy -148.082 46.647199) (xy -148.082 15.621) (xy -149.098 14.605) (xy -182.118 14.605) (xy -190.5 22.987)
				(xy -190.5 45.593) (xy -191.554199 46.647199) (xy -274.9931 46.647199) (xy -274.9931 44.9961) (xy -275.0058 44.9834)
				(xy -279.273 44.9834) (xy -279.273 41.275) (xy -284.988 41.275) (xy -284.988 45.0977) (xy -288.6837 45.0977)
				(xy -288.6837 46.647199) (xy -305.07178 46.647199) (xy -305.07178 34.02076) (xy -307.55082 34.02076)
				(xy -307.55082 34.036) (xy -311.3532 34.036) (xy -311.3532 33.1089) (xy -311.35574 33.1089) (xy -311.35574 33.09874)
				(xy -314.31738 33.09874) (xy -314.31738 34.036) (xy -326.644 34.036) (xy -326.644 26.289) (xy -331.851 21.082)
				(xy -334.55864 21.082) (xy -335.661 19.97964) (xy -335.661 -4.0272)
				(arc
					(start 1.38 -4.0272)
					(mid 2.926584 -3.386584)
					(end 3.567199 -1.839999)
				)
				(arc
					(start 3.567199 34.5)
					(mid 3.899173 35.372596)
					(end 4.727199 35.803878)
				)
				(arc
					(start 4.727199 44.46)
					(mid 4.086583 46.006583)
					(end 2.54 46.647199)
				)
				(xy -24.345801 46.647199) (xy -24.892 46.101) (xy -24.892 33.782) (xy -26.797 31.877) (xy -37.592 31.877)
				(xy -38.735 33.02) (xy -38.735 46.012199) (xy -39.37 46.647199) (xy -84.328 46.647199) (xy -84.328 33.909)
				(xy -97.34296 33.909) (xy -97.34296 33.13176) (xy -98.30816 32.16656) (xy -98.57994 32.16656) (xy -98.87712 32.46374)
				(xy -98.87712 32.87522) (xy -98.8822 32.8803) (xy -98.87458 32.8803) (xy -98.87458 33.909) (xy -103.759 33.909)
			)
		)
		(polygon
			(pts
				(xy -276.76094 24.93772) (xy -276.76094 40.5384) (xy -288.64052 40.5384) (xy -288.64052 24.93772)
			)
		)
		(polygon
			(pts
				(xy -55.8292 40.61206) (xy -67.59448 40.61206) (xy -67.59448 24.9301) (xy -67.47002 24.9301) (xy -55.8292 24.9301)
			)
		)
		(polygon
			(pts
				(xy -213.233 33.147) (xy -231.521 33.147) (xy -231.521 28.829) (xy -213.233 28.829)
			)
		)
		(polygon
			(pts
				(xy -252.8951 34.06648) (xy -254.95758 34.06648) (xy -254.95758 33.02254) (xy -255.63576 33.02254)
				(xy -255.63576 32.28848) (xy -255.98882 32.28848) (xy -255.98882 31.98622) (xy -255.36906 31.98622)
				(xy -255.36906 32.03956) (xy -252.8951 32.03956)
			)
		)
		(polygon
			(pts
				(xy -253.02464 38.42766) (xy -254.55372 38.42766) (xy -254.55372 35.74542) (xy -253.02464 35.74542)
			)
		)
		(polygon
			(pts
				(xy -209.804 40.132) (xy -236.22 40.132) (xy -236.22 35.56) (xy -209.804 35.56)
			)
		)
		(polygon
			(pts
				(xy -253.0348 42.16908) (xy -254.4953 42.16908) (xy -254.4953 41.94302) (xy -254.50292 41.94302)
				(xy -254.50292 39.88816) (xy -252.92558 39.88816) (xy -252.92558 41.94302) (xy -253.0348 41.94302)
			)
		)
		(polygon
			(pts
				(arc
					(start -60.799937 46.472201)
					(mid -60.811786 46.590554)
					(end -60.916381 46.647194)
				)
				(arc
					(start -61.267404 46.647194)
					(mid -61.373517 46.588219)
					(end -61.38163 46.46709)
				)
				(arc
					(start -61.38163 46.46709)
					(mid -61.351199 46.376352)
					(end -61.340896 46.281203)
				)
				(xy -61.340896 46.027208) (xy -61.226596 46.027208) (xy -61.226596 45.011198) (xy -62.231588 45.011198)
				(xy -62.233043 44.828465) (xy -61.074305 44.828465) (xy -61.074305 44.841754) (xy -60.301922 44.832295)
				(arc
					(start -60.231421 44.902796)
					(mid -60.217655 44.971998)
					(end -60.276321 45.011198)
				)
				(xy -60.947206 45.011198) (xy -60.947206 46.027208) (xy -60.832906 46.027208)
				(arc
					(start -60.832906 46.3042)
					(mid -60.824586 46.389803)
					(end -60.799937 46.472201)
				)
			)
		)
	)
	(zone
		(layer "F.Cu")
		(hatch none 0.5)
		(connect_pads
			(clearance 0)
		)
		(min_thickness 0.25)
		(keepout
			(tracks allowed)
			(vias allowed)
			(pads allowed)
			(copperpour allowed)
			(footprints not_allowed)
		)
		(placement
			(enabled no)
			(sheetname "")
		)
		(fill
			(thermal_gap 0.5)
			(thermal_bridge_width 0.5)
			(island_removal_mode 0)
		)
		(polygon
			(pts
				(arc
					(start -414.459999 12.999999)
					(mid -417.460001 9.999997)
					(end -420.46 12.999999)
				)
				(arc
					(start -420.46 19)
					(mid -417.460001 21.999999)
					(end -414.459999 19)
				)
			)
		)
	)
	(zone
		(net "P3V3_10G_B1_VCCT")
		(layer "F.Cu")
		(hatch none 0.5)
		(connect_pads
			(clearance 0.5)
		)
		(min_thickness 0.25)
		(fill yes
			(thermal_gap 0.5)
			(thermal_bridge_width 0.5)
			(island_removal_mode 0)
		)
		(polygon
			(pts
				(xy -281.90698 36.16198) (xy -282.4099 36.16198) (xy -282.4099 32.61868) (xy -282.24988 32.45866)
				(xy -281.86634 32.45866) (xy -281.686 32.639) (xy -281.686 33.92678) (xy -281.90698 34.14776)
			)
		)
	)
	(zone
		(layer "F.Cu")
		(hatch none 0.5)
		(connect_pads
			(clearance 0)
		)
		(min_thickness 0.25)
		(keepout
			(tracks not_allowed)
			(vias allowed)
			(pads allowed)
			(copperpour not_allowed)
			(footprints allowed)
		)
		(placement
			(enabled no)
			(sheetname "")
		)
		(fill
			(thermal_gap 0.5)
			(thermal_bridge_width 0.5)
			(island_removal_mode 0)
		)
		(polygon
			(pts
				(arc
					(start -364.46 37)
					(mid -361.460001 39.999999)
					(end -358.459999 37)
				)
				(arc
					(start -358.459999 30.999999)
					(mid -361.460001 27.999997)
					(end -364.46 30.999999)
				)
			)
		)
	)
	(zone
		(layer "F.Cu")
		(hatch none 0.5)
		(connect_pads
			(clearance 0)
		)
		(min_thickness 0.25)
		(keepout
			(tracks not_allowed)
			(vias allowed)
			(pads allowed)
			(copperpour not_allowed)
			(footprints allowed)
		)
		(placement
			(enabled no)
			(sheetname "")
		)
		(fill
			(thermal_gap 0.5)
			(thermal_bridge_width 0.5)
			(island_removal_mode 0)
		)
		(polygon
			(pts
				(arc
					(start -80.459999 23.459999)
					(mid -77.46 26.459998)
					(end -74.460001 23.459999)
				)
				(arc
					(start -74.460001 17.460001)
					(mid -77.46 14.460002)
					(end -80.459999 17.460001)
				)
			)
		)
	)
	(zone
		(net "P3V3_40G_B2_VCC_TX")
		(layer "F.Cu")
		(hatch none 0.5)
		(connect_pads
			(clearance 0.5)
		)
		(min_thickness 0.25)
		(fill yes
			(thermal_gap 0.5)
			(thermal_bridge_width 0.5)
			(island_removal_mode 0)
		)
		(polygon
			(pts
				(xy -49.0274 6.1341) (xy -46.1953 6.1341) (xy -45.2301 7.0993) (xy -45.2301 8.0645) (xy -45.1031 8.1915)
				(xy -45.1031 9.1694) (xy -46.335 9.1694) (xy -46.5255 8.9789) (xy -49.0274 8.9789)
			)
		)
	)
	(zone
		(layer "F.Cu")
		(hatch none 0.5)
		(connect_pads
			(clearance 0)
		)
		(min_thickness 0.25)
		(keepout
			(tracks not_allowed)
			(vias allowed)
			(pads allowed)
			(copperpour not_allowed)
			(footprints allowed)
		)
		(placement
			(enabled no)
			(sheetname "")
		)
		(fill
			(thermal_gap 0.5)
			(thermal_bridge_width 0.5)
			(island_removal_mode 0)
		)
		(polygon
			(pts
				(arc
					(start -420.46 19)
					(mid -417.460001 21.999999)
					(end -414.459999 19)
				)
				(arc
					(start -414.459999 12.999999)
					(mid -417.460001 9.999997)
					(end -420.46 12.999999)
				)
			)
		)
	)
	(zone
		(layer "F.Cu")
		(hatch none 0.5)
		(connect_pads
			(clearance 0)
		)
		(min_thickness 0.25)
		(keepout
			(tracks allowed)
			(vias allowed)
			(pads allowed)
			(copperpour allowed)
			(footprints not_allowed)
		)
		(placement
			(enabled no)
			(sheetname "")
		)
		(fill
			(thermal_gap 0.5)
			(thermal_bridge_width 0.5)
			(island_removal_mode 0)
		)
		(polygon
			(pts
				(arc
					(start -139.46 23.459999)
					(mid -142.460002 20.459997)
					(end -145.460001 23.459999)
				)
				(arc
					(start -145.460001 29.46)
					(mid -142.460002 32.459999)
					(end -139.46 29.46)
				)
			)
		)
	)
	(zone
		(layer "F.Cu")
		(hatch none 0.5)
		(connect_pads
			(clearance 0.5)
		)
		(min_thickness 0.25)
		(fill
			(thermal_gap 0.5)
			(thermal_bridge_width 0.5)
			(island_removal_mode 0)
		)
		(polygon
			(pts
				(xy -279.80608 45.974) (xy -279.80608 41.70934) (xy -279.80354 41.7068) (xy -281.50534 41.7068)
				(xy -281.8203 42.02176) (xy -281.8203 44.58462) (xy -281.198 44.577) (xy -280.563 45.212) (xy -280.563 45.974)
			)
		)
	)
	(zone
		(net "P3V3_40G_B2_VCC1")
		(layer "F.Cu")
		(hatch none 0.5)
		(connect_pads
			(clearance 0.5)
		)
		(min_thickness 0.25)
		(fill yes
			(thermal_gap 0.5)
			(thermal_bridge_width 0.5)
			(island_removal_mode 0)
		)
		(polygon
			(pts
				(xy -49.129 12.954) (xy -47.478 12.954) (xy -46.9446 12.4206) (xy -46.9446 11.9888) (xy -46.6398 11.684)
				(xy -45.9286 11.684) (xy -45.7508 11.8618) (xy -45.7508 14.605) (xy -46.0302 14.8844) (xy -48.6464 14.8844)
				(xy -49.129 14.4018)
			)
		)
	)
	(zone
		(layer "F.Cu")
		(hatch none 0.5)
		(connect_pads
			(clearance 0)
		)
		(min_thickness 0.25)
		(keepout
			(tracks allowed)
			(vias allowed)
			(pads allowed)
			(copperpour allowed)
			(footprints not_allowed)
		)
		(placement
			(enabled no)
			(sheetname "")
		)
		(fill
			(thermal_gap 0.5)
			(thermal_bridge_width 0.5)
			(island_removal_mode 0)
		)
		(polygon
			(pts
				(arc
					(start -162.020001 39.36)
					(mid -165.770001 35.61)
					(end -169.519999 39.36)
				)
				(arc
					(start -169.519999 39.36)
					(mid -165.770001 43.109998)
					(end -162.020001 39.36)
				)
			)
		)
	)
	(zone
		(layer "F.Cu")
		(hatch none 0.5)
		(connect_pads
			(clearance 0)
		)
		(min_thickness 0.25)
		(keepout
			(tracks not_allowed)
			(vias allowed)
			(pads allowed)
			(copperpour not_allowed)
			(footprints allowed)
		)
		(placement
			(enabled no)
			(sheetname "")
		)
		(fill
			(thermal_gap 0.5)
			(thermal_bridge_width 0.5)
			(island_removal_mode 0)
		)
		(polygon
			(pts
				(arc
					(start -11.31 32.86)
					(mid -8.310001 35.859999)
					(end -5.31 32.86)
				)
				(arc
					(start -5.31 26.86)
					(mid -8.310001 23.859999)
					(end -11.31 26.86)
				)
			)
		)
	)
	(zone
		(layer "F.Cu")
		(hatch none 0.5)
		(connect_pads
			(clearance 0)
		)
		(min_thickness 0.25)
		(keepout
			(tracks not_allowed)
			(vias allowed)
			(pads allowed)
			(copperpour not_allowed)
			(footprints allowed)
		)
		(placement
			(enabled no)
			(sheetname "")
		)
		(fill
			(thermal_gap 0.5)
			(thermal_bridge_width 0.5)
			(island_removal_mode 0)
		)
		(polygon
			(pts
				(arc
					(start -302.46 23.459999)
					(mid -299.460001 26.459998)
					(end -296.459999 23.459999)
				)
				(arc
					(start -296.459999 17.460001)
					(mid -299.460001 14.459999)
					(end -302.46 17.460001)
				)
			)
		)
	)
	(zone
		(net "P3V3_40G_B1_VCC1")
		(layer "F.Cu")
		(hatch none 0.5)
		(connect_pads
			(clearance 0.5)
		)
		(min_thickness 0.25)
		(fill yes
			(thermal_gap 0.5)
			(thermal_bridge_width 0.5)
			(island_removal_mode 0)
		)
		(polygon
			(pts
				(xy -270.51 13.081) (xy -268.859 13.081) (xy -268.3256 12.5476) (xy -268.3256 12.1158) (xy -268.0208 11.811)
				(xy -267.3096 11.811) (xy -267.1318 11.9888) (xy -267.1318 14.732) (xy -267.4112 15.0114) (xy -270.0274 15.0114)
				(xy -270.51 14.5288)
			)
		)
	)
	(zone
		(layer "F.Cu")
		(hatch none 0.5)
		(connect_pads
			(clearance 0.5)
		)
		(min_thickness 0.25)
		(fill
			(thermal_gap 0.5)
			(thermal_bridge_width 0.5)
			(island_removal_mode 0)
		)
		(polygon
			(pts
				(xy -284.4238 45.974) (xy -284.42126 41.69918) (xy -284.4238 41.69664) (xy -282.722 41.69664) (xy -282.40704 42.0116)
				(xy -282.40704 44.57446) (xy -283.48908 44.57446) (xy -283.484 45.212) (xy -283.738 45.466) (xy -283.738 45.974)
			)
		)
	)
	(zone
		(net "P3V3_40G_B2_VCC_RX")
		(layer "F.Cu")
		(hatch none 0.5)
		(connect_pads
			(clearance 0.5)
		)
		(min_thickness 0.25)
		(fill yes
			(thermal_gap 0.5)
			(thermal_bridge_width 0.5)
			(island_removal_mode 0)
		)
		(polygon
			(pts
				(xy -49.002 -0.0889) (xy -46.1699 -0.0889) (xy -45.2047 0.8763) (xy -45.2047 1.8415) (xy -45.0777 1.9685)
				(xy -45.0777 2.9464) (xy -46.3096 2.9464) (xy -46.5001 2.7559) (xy -49.002 2.7559)
			)
		)
	)
	(zone
		(layer "F.Cu")
		(hatch none 0.5)
		(connect_pads
			(clearance 0)
		)
		(min_thickness 0.25)
		(keepout
			(tracks allowed)
			(vias allowed)
			(pads allowed)
			(copperpour allowed)
			(footprints not_allowed)
		)
		(placement
			(enabled no)
			(sheetname "")
		)
		(fill
			(thermal_gap 0.5)
			(thermal_bridge_width 0.5)
			(island_removal_mode 0)
		)
		(polygon
			(pts
				(arc
					(start -5.31 26.86)
					(mid -8.310001 23.859999)
					(end -11.31 26.86)
				)
				(arc
					(start -11.31 32.86)
					(mid -8.310001 35.859999)
					(end -5.31 32.86)
				)
			)
		)
	)
	(zone
		(layer "F.Cu")
		(hatch none 0.5)
		(connect_pads
			(clearance 0)
		)
		(min_thickness 0.25)
		(keepout
			(tracks allowed)
			(vias allowed)
			(pads allowed)
			(copperpour allowed)
			(footprints allowed)
		)
		(placement
			(enabled no)
			(sheetname "")
		)
		(fill
			(thermal_gap 0.5)
			(thermal_bridge_width 0.5)
			(island_removal_mode 0)
		)
		(polygon
			(pts
				(xy -66.182814 40.036242) (xy -66.182814 29.386022) (xy -66.182814 23.868126) (xy -56.973282 23.868126)
				(xy -56.973282 29.386022) (xy -56.973282 40.036242)
			)
		)
	)
	(zone
		(layer "F.Cu")
		(hatch none 0.5)
		(connect_pads
			(clearance 0)
		)
		(min_thickness 0.25)
		(keepout
			(tracks allowed)
			(vias allowed)
			(pads allowed)
			(copperpour allowed)
			(footprints allowed)
		)
		(placement
			(enabled no)
			(sheetname "")
		)
		(fill
			(thermal_gap 0.5)
			(thermal_bridge_width 0.5)
			(island_removal_mode 0)
		)
		(polygon
			(pts
				(xy -159.79172 17.49044) (xy -149.1415 17.49044) (xy -149.1415 43.87342) (xy -159.79172 43.87342)
			)
		)
	)
	(zone
		(layer "F.Cu")
		(hatch none 0.5)
		(connect_pads
			(clearance 0)
		)
		(min_thickness 0.25)
		(keepout
			(tracks allowed)
			(vias allowed)
			(pads allowed)
			(copperpour allowed)
			(footprints not_allowed)
		)
		(placement
			(enabled no)
			(sheetname "")
		)
		(fill
			(thermal_gap 0.5)
			(thermal_bridge_width 0.5)
			(island_removal_mode 0)
		)
		(polygon
			(pts
				(arc
					(start -41.359699 20.000001)
					(mid -45.109699 16.250001)
					(end -48.859699 20.000001)
				)
				(arc
					(start -48.859699 20.000001)
					(mid -45.109699 23.750001)
					(end -41.359699 20.000001)
				)
			)
		)
	)
	(zone
		(layer "F.Cu")
		(hatch none 0.5)
		(connect_pads
			(clearance 0)
		)
		(min_thickness 0.25)
		(keepout
			(tracks allowed)
			(vias allowed)
			(pads allowed)
			(copperpour allowed)
			(footprints allowed)
		)
		(placement
			(enabled no)
			(sheetname "")
		)
		(fill
			(thermal_gap 0.5)
			(thermal_bridge_width 0.5)
			(island_removal_mode 0)
		)
		(polygon
			(pts
				(xy -324.452742 38.33114) (xy -313.802522 38.33114) (xy -308.284626 38.33114) (xy -308.284626 47.540672)
				(xy -313.802522 47.540672) (xy -324.452742 47.540672)
			)
		)
	)
	(zone
		(net "GND")
		(layer "F.Cu")
		(hatch none 0.5)
		(connect_pads
			(clearance 0.5)
		)
		(min_thickness 0.25)
		(fill yes
			(thermal_gap 0.5)
			(thermal_bridge_width 0.5)
			(island_removal_mode 0)
		)
		(polygon
			(pts
				(xy -390.9822 5.04444) (xy -390.9822 -4.35356) (xy -390.96696 -4.33832) (xy -390.306276 -4.33832)
				(xy -371.40896 -4.33832) (xy -371.40896 3.24612) (xy -371.40896 5.3213) (xy -371.40896 5.64896)
				(xy -371.82552 6.06552) (xy -372.15318 6.06552) (xy -389.96112 6.06552)
			)
		)
	)
	(zone
		(layer "F.Cu")
		(hatch none 0.5)
		(connect_pads
			(clearance 0)
		)
		(min_thickness 0.25)
		(keepout
			(tracks allowed)
			(vias allowed)
			(pads allowed)
			(copperpour allowed)
			(footprints not_allowed)
		)
		(placement
			(enabled no)
			(sheetname "")
		)
		(fill
			(thermal_gap 0.5)
			(thermal_bridge_width 0.5)
			(island_removal_mode 0)
		)
		(polygon
			(pts
				(arc
					(start -74.460001 17.460001)
					(mid -77.46 14.460002)
					(end -80.459999 17.460001)
				)
				(arc
					(start -80.459999 23.459999)
					(mid -77.46 26.459998)
					(end -74.460001 23.459999)
				)
			)
		)
	)
	(zone
		(layer "F.Cu")
		(hatch none 0.5)
		(connect_pads
			(clearance 0)
		)
		(min_thickness 0.25)
		(keepout
			(tracks allowed)
			(vias allowed)
			(pads allowed)
			(copperpour allowed)
			(footprints allowed)
		)
		(placement
			(enabled no)
			(sheetname "")
		)
		(fill
			(thermal_gap 0.5)
			(thermal_bridge_width 0.5)
			(island_removal_mode 0)
		)
		(polygon
			(pts
				(xy -287.411414 40.341042) (xy -287.411414 29.690822) (xy -287.411414 24.172926) (xy -278.201882 24.172926)
				(xy -278.201882 29.690822) (xy -278.201882 40.341042)
			)
		)
	)
	(zone
		(net "P3V3_40G_B1_VCC_TX")
		(layer "F.Cu")
		(hatch none 0.5)
		(connect_pads
			(clearance 0.5)
		)
		(min_thickness 0.25)
		(fill yes
			(thermal_gap 0.5)
			(thermal_bridge_width 0.5)
			(island_removal_mode 0)
		)
		(polygon
			(pts
				(xy -270.256 6.0071) (xy -268.351 6.0071) (xy -267.1572 7.2009) (xy -266.6111 7.2009) (xy -266.6111 7.4549)
				(xy -266.6111 7.9375) (xy -266.4841 8.0645) (xy -266.4841 9.0424) (xy -267.716 9.0424) (xy -267.9065 8.8519)
				(xy -270.256 8.8519) (xy -270.4084 8.6995) (xy -270.4084 6.1595)
			)
		)
	)
	(zone
		(net "P3V3_10G_B2_VCCT")
		(layer "F.Cu")
		(hatch none 0.5)
		(connect_pads
			(clearance 0.5)
		)
		(min_thickness 0.25)
		(fill yes
			(thermal_gap 0.5)
			(thermal_bridge_width 0.5)
			(island_removal_mode 0)
		)
		(polygon
			(pts
				(xy -60.90158 36.16706) (xy -61.39942 36.16706) (xy -61.39942 32.61868) (xy -61.24448 32.46374)
				(xy -60.88126 32.46374) (xy -60.6552 32.6898) (xy -60.6552 33.90646) (xy -60.90158 34.15284)
			)
		)
	)
	(zone
		(layer "F.Cu")
		(hatch none 0.5)
		(connect_pads
			(clearance 0)
		)
		(min_thickness 0.25)
		(keepout
			(tracks allowed)
			(vias allowed)
			(pads allowed)
			(copperpour allowed)
			(footprints not_allowed)
		)
		(placement
			(enabled no)
			(sheetname "")
		)
		(fill
			(thermal_gap 0.5)
			(thermal_bridge_width 0.5)
			(island_removal_mode 0)
		)
		(polygon
			(pts
				(arc
					(start -296.459999 17.460001)
					(mid -299.460001 14.459999)
					(end -302.46 17.460001)
				)
				(arc
					(start -302.46 23.459999)
					(mid -299.460001 26.459998)
					(end -296.459999 23.459999)
				)
			)
		)
	)
	(zone
		(layer "F.Cu")
		(hatch none 0.5)
		(connect_pads
			(clearance 0)
		)
		(min_thickness 0.25)
		(keepout
			(tracks allowed)
			(vias allowed)
			(pads allowed)
			(copperpour allowed)
			(footprints allowed)
		)
		(placement
			(enabled no)
			(sheetname "")
		)
		(fill
			(thermal_gap 0.5)
			(thermal_bridge_width 0.5)
			(island_removal_mode 0)
		)
		(polygon
			(pts
				(xy -103.554342 38.33114) (xy -92.904122 38.33114) (xy -87.386226 38.33114) (xy -87.386226 47.540672)
				(xy -92.904122 47.540672) (xy -103.554342 47.540672)
			)
		)
	)
	(zone
		(layer "F.Cu")
		(hatch none 0.5)
		(connect_pads
			(clearance 0)
		)
		(min_thickness 0.25)
		(keepout
			(tracks allowed)
			(vias allowed)
			(pads allowed)
			(copperpour allowed)
			(footprints not_allowed)
		)
		(placement
			(enabled no)
			(sheetname "")
		)
		(fill
			(thermal_gap 0.5)
			(thermal_bridge_width 0.5)
			(island_removal_mode 0)
		)
		(polygon
			(pts
				(arc
					(start -262.359699 20.000001)
					(mid -266.109699 16.250001)
					(end -269.859699 20.000001)
				)
				(arc
					(start -269.859699 20.000001)
					(mid -266.109699 23.750001)
					(end -262.359699 20.000001)
				)
			)
		)
	)
	(zone
		(layers "F.Cu" "B.Cu")
		(hatch none 0.5)
		(connect_pads
			(clearance 0)
		)
		(min_thickness 0.25)
		(keepout
			(tracks allowed)
			(vias allowed)
			(pads allowed)
			(copperpour allowed)
			(footprints allowed)
		)
		(placement
			(enabled no)
			(sheetname "")
		)
		(fill yes
			(thermal_gap 0.5)
			(thermal_bridge_width 0.5)
			(island_removal_mode 0)
		)
		(polygon
			(pts
				(arc
					(start -381.117401 39.359611)
					(mid -392.438481 39.359611)
					(end -381.117401 39.359611)
				)
			)
		)
	)
	(zone
		(layers "F.Cu" "B.Cu" "In1.Cu" "In2.Cu" "In3.Cu" "In4.Cu" "In5.Cu" "In6.Cu")
		(hatch none 0.5)
		(connect_pads
			(clearance 0)
		)
		(min_thickness 0.25)
		(keepout
			(tracks not_allowed)
			(vias allowed)
			(pads allowed)
			(copperpour not_allowed)
			(footprints allowed)
		)
		(placement
			(enabled no)
			(sheetname "")
		)
		(fill
			(thermal_gap 0.5)
			(thermal_bridge_width 0.5)
			(island_removal_mode 0)
		)
		(polygon
			(pts
				(arc
					(start -342.391459 41.766881)
					(mid -342.287489 42.45998)
					(end -342.391459 43.153079)
				)
			)
		)
	)
	(zone
		(layers "F.Cu" "B.Cu" "In1.Cu" "In2.Cu" "In3.Cu" "In4.Cu" "In5.Cu" "In6.Cu")
		(hatch none 0.5)
		(connect_pads
			(clearance 0)
		)
		(min_thickness 0.25)
		(keepout
			(tracks not_allowed)
			(vias allowed)
			(pads allowed)
			(copperpour not_allowed)
			(footprints allowed)
		)
		(placement
			(enabled no)
			(sheetname "")
		)
		(fill
			(thermal_gap 0.5)
			(thermal_bridge_width 0.5)
			(island_removal_mode 0)
		)
		(polygon
			(pts
				(arc
					(start -342.391459 29.51688)
					(mid -342.287489 30.209979)
					(end -342.391459 30.903078)
				)
			)
		)
	)
	(zone
		(layers "F.Cu" "B.Cu" "In1.Cu" "In2.Cu" "In3.Cu" "In4.Cu" "In5.Cu" "In6.Cu")
		(hatch none 0.5)
		(connect_pads
			(clearance 0)
		)
		(min_thickness 0.25)
		(keepout
			(tracks not_allowed)
			(vias allowed)
			(pads allowed)
			(copperpour not_allowed)
			(footprints allowed)
		)
		(placement
			(enabled no)
			(sheetname "")
		)
		(fill
			(thermal_gap 0.5)
			(thermal_bridge_width 0.5)
			(island_removal_mode 0)
		)
		(polygon
			(pts
				(arc
					(start -364.43 34.067897)
					(mid -361.460002 26.73)
					(end -358.489999 34.067897)
				)
				(arc
					(start -358.489999 37)
					(mid -361.460001 39.970002)
					(end -364.43 37)
				)
			)
		)
	)
	(zone
		(layers "F.Cu" "B.Cu" "In1.Cu" "In2.Cu" "In3.Cu" "In4.Cu" "In5.Cu" "In6.Cu")
		(hatch none 0.5)
		(connect_pads
			(clearance 0)
		)
		(min_thickness 0.25)
		(keepout
			(tracks not_allowed)
			(vias allowed)
			(pads allowed)
			(copperpour not_allowed)
			(footprints allowed)
		)
		(placement
			(enabled no)
			(sheetname "")
		)
		(fill
			(thermal_gap 0.5)
			(thermal_bridge_width 0.5)
			(island_removal_mode 0)
		)
		(polygon
			(pts
				(arc
					(start -302.43 20.527896)
					(mid -299.460002 13.189999)
					(end -296.489999 20.527896)
				)
				(arc
					(start -296.489999 23.459999)
					(mid -299.460001 26.430001)
					(end -302.43 23.459999)
				)
			)
		)
	)
	(zone
		(layers "F.Cu" "B.Cu" "In1.Cu" "In2.Cu" "In3.Cu" "In4.Cu" "In5.Cu" "In6.Cu")
		(hatch none 0.5)
		(connect_pads
			(clearance 0)
		)
		(min_thickness 0.25)
		(keepout
			(tracks not_allowed)
			(vias allowed)
			(pads allowed)
			(copperpour not_allowed)
			(footprints allowed)
		)
		(placement
			(enabled no)
			(sheetname "")
		)
		(fill
			(thermal_gap 0.5)
			(thermal_bridge_width 0.5)
			(island_removal_mode 0)
		)
		(polygon
			(pts
				(arc
					(start -80.429999 20.527896)
					(mid -77.46 13.189999)
					(end -74.490001 20.527896)
				)
				(arc
					(start -74.490001 23.459999)
					(mid -77.46 26.429998)
					(end -80.429999 23.459999)
				)
			)
		)
	)
	(zone
		(layers "F.Cu" "B.Cu" "In1.Cu" "In2.Cu" "In3.Cu" "In4.Cu" "In5.Cu" "In6.Cu")
		(name "Package Keepin")
		(hatch none 0.5)
		(connect_pads
			(clearance 0)
		)
		(min_thickness 0.25)
		(keepout
			(tracks allowed)
			(vias allowed)
			(pads allowed)
			(copperpour allowed)
			(footprints allowed)
		)
		(placement
			(enabled no)
			(sheetname "")
		)
		(fill
			(thermal_gap 0.5)
			(thermal_bridge_width 0.5)
			(island_removal_mode 0)
		)
		(polygon
			(pts
				(arc
					(start -367.879998 6.43)
					(mid -365.921312 5.618686)
					(end -365.109999 3.66)
				)
				(arc
					(start -365.109999 -2.34)
					(mid -364.749741 -3.209741)
					(end -363.880001 -3.57)
				)
				(arc
					(start 1.38 -3.57)
					(mid 2.603295 -3.063294)
					(end 3.109999 -1.839999)
				)
				(arc
					(start 3.109999 34.5)
					(mid 3.428689 35.513213)
					(end 4.269999 36.161566)
				)
				(arc
					(start 4.269999 44.46)
					(mid 3.763294 45.683294)
					(end 2.54 46.189999)
				)
				(arc
					(start -85.175001 46.189999)
					(mid -86.42658 46.708421)
					(end -86.945 47.960001)
				)
				(xy -86.945 48.729999) (xy -102.554999 48.729999)
				(arc
					(start -102.554999 47.960001)
					(mid -103.073421 46.708421)
					(end -104.325001 46.189999)
				)
				(arc
					(start -306.175001 46.189999)
					(mid -307.42658 46.708421)
					(end -307.945 47.960001)
				)
				(xy -307.945 48.729999) (xy -323.554999 48.729999)
				(arc
					(start -323.554999 47.960001)
					(mid -324.073421 46.708421)
					(end -325.325001 46.189999)
				)
				(arc
					(start -420.960001 46.189999)
					(mid -421.122635 46.122634)
					(end -421.190001 45.96)
				)
				(xy -421.190001 -3.813947) (xy -420.933949 -4.069999) (xy -413.536051 -4.069999) (xy -413.279999 -3.813947)
				(arc
					(start -413.279999 4.810001)
					(mid -411.66 6.43)
					(end -410.04 4.810001)
				)
				(xy -410.04 -3.813947) (xy -409.783948 -4.069999) (xy -371.906051 -4.069999) (xy -371.650001 -3.81395)
				(arc
					(start -371.650001 3.66)
					(mid -370.838686 5.618686)
					(end -368.879999 6.43)
				)
			)
		)
	)
	(zone
		(layers "F.Cu" "B.Cu" "In1.Cu" "In2.Cu" "In3.Cu" "In4.Cu" "In5.Cu" "In6.Cu")
		(name "Route Keepin")
		(hatch none 0.5)
		(connect_pads
			(clearance 0)
		)
		(min_thickness 0.25)
		(keepout
			(tracks allowed)
			(vias allowed)
			(pads allowed)
			(copperpour allowed)
			(footprints allowed)
		)
		(placement
			(enabled no)
			(sheetname "")
		)
		(fill
			(thermal_gap 0.5)
			(thermal_bridge_width 0.5)
			(island_removal_mode 0)
		)
		(polygon
			(pts
				(arc
					(start -367.879998 5.668)
					(mid -366.460128 5.07987)
					(end -365.871999 3.66)
				)
				(arc
					(start -365.871999 -2.34)
					(mid -365.288556 -3.748556)
					(end -363.880001 -4.332)
				)
				(arc
					(start 1.38 -4.332)
					(mid 3.14211 -3.60211)
					(end 3.871999 -1.839999)
				)
				(arc
					(start 3.871999 34.5)
					(mid 4.167236 35.212764)
					(end 4.88 35.508001)
				)
				(xy 5.031999 35.508001)
				(arc
					(start 5.031999 44.46)
					(mid 4.302109 46.222109)
					(end 2.54 46.951999)
				)
				(arc
					(start -85.175001 46.951999)
					(mid -85.887765 47.247237)
					(end -86.183 47.960001)
				)
				(xy -86.183 49.491999) (xy -103.316999 49.491999)
				(arc
					(start -103.316999 47.960001)
					(mid -103.612236 47.247236)
					(end -104.325001 46.951999)
				)
				(xy -219.8878 46.951999) (xy -219.8878 47.4726) (xy -229.5906 47.4726) (xy -229.5906 46.951999)
				(arc
					(start -306.175001 46.951999)
					(mid -306.887765 47.247237)
					(end -307.183 47.960001)
				)
				(xy -307.183 49.491999) (xy -324.316999 49.491999)
				(arc
					(start -324.316999 47.960001)
					(mid -324.612236 47.247236)
					(end -325.325001 46.951999)
				)
				(arc
					(start -420.960001 46.951999)
					(mid -421.66145 46.661449)
					(end -421.952001 45.96)
				)
				(xy -421.952001 -4.129578) (xy -421.249579 -4.831999) (xy -413.220421 -4.831999) (xy -412.517999 -4.129578)
				(arc
					(start -412.517999 4.810001)
					(mid -411.66 5.668)
					(end -410.802 4.810001)
				)
				(xy -410.802 -4.129578) (xy -410.099579 -4.831999) (xy -371.59042 -4.831999) (xy -370.888001 -4.129578)
				(arc
					(start -370.888001 3.66)
					(mid -370.299871 5.079871)
					(end -368.879999 5.668)
				)
			)
		)
	)
	(zone
		(layers "F.Cu" "B.Cu" "In1.Cu" "In2.Cu" "In3.Cu" "In4.Cu" "In5.Cu" "In6.Cu")
		(hatch none 0.5)
		(connect_pads
			(clearance 0)
		)
		(min_thickness 0.25)
		(keepout
			(tracks not_allowed)
			(vias allowed)
			(pads allowed)
			(copperpour not_allowed)
			(footprints allowed)
		)
		(placement
			(enabled no)
			(sheetname "")
		)
		(fill
			(thermal_gap 0.5)
			(thermal_bridge_width 0.5)
			(island_removal_mode 0)
		)
		(polygon
			(pts
				(arc
					(start -420.43 16.067898)
					(mid -417.460002 8.729999)
					(end -414.489999 16.067898)
				)
				(arc
					(start -414.489999 19)
					(mid -417.460001 21.970002)
					(end -420.43 19)
				)
			)
		)
	)
	(zone
		(layers "F.Cu" "B.Cu" "In1.Cu" "In2.Cu" "In3.Cu" "In4.Cu" "In5.Cu" "In6.Cu")
		(hatch none 0.5)
		(connect_pads
			(clearance 0)
		)
		(min_thickness 0.25)
		(keepout
			(tracks not_allowed)
			(vias allowed)
			(pads allowed)
			(copperpour not_allowed)
			(footprints allowed)
		)
		(placement
			(enabled no)
			(sheetname "")
		)
		(fill
			(thermal_gap 0.5)
			(thermal_bridge_width 0.5)
			(island_removal_mode 0)
		)
		(polygon
			(pts
				(arc
					(start -145.430001 26.527897)
					(mid -142.460003 19.19)
					(end -139.49 26.527897)
				)
				(arc
					(start -139.49 29.46)
					(mid -142.460002 32.430002)
					(end -145.430001 29.46)
				)
			)
		)
	)
	(zone
		(layers "F.Cu" "B.Cu" "In1.Cu" "In2.Cu" "In3.Cu" "In4.Cu" "In5.Cu" "In6.Cu")
		(hatch none 0.5)
		(connect_pads
			(clearance 0)
		)
		(min_thickness 0.25)
		(keepout
			(tracks not_allowed)
			(vias allowed)
			(pads allowed)
			(copperpour not_allowed)
			(footprints allowed)
		)
		(placement
			(enabled no)
			(sheetname "")
		)
		(fill
			(thermal_gap 0.5)
			(thermal_bridge_width 0.5)
			(island_removal_mode 0)
		)
		(polygon
			(pts
				(arc
					(start -11.28 29.927898)
					(mid -8.310002 22.590001)
					(end -5.339999 29.927898)
				)
				(arc
					(start -5.339999 32.86)
					(mid -8.310001 35.830002)
					(end -11.28 32.86)
				)
			)
		)
	)
	(zone
		(layers "F.Cu" "B.Cu" "In1.Cu" "In2.Cu" "In3.Cu" "In4.Cu" "In6.Cu")
		(hatch none 0.5)
		(connect_pads
			(clearance 0)
		)
		(min_thickness 0.25)
		(keepout
			(tracks not_allowed)
			(vias allowed)
			(pads allowed)
			(copperpour not_allowed)
			(footprints allowed)
		)
		(placement
			(enabled no)
			(sheetname "")
		)
		(fill yes
			(thermal_gap 0.5)
			(thermal_bridge_width 0.5)
			(island_removal_mode 0)
		)
		(polygon
			(pts
				(xy -250.251501 44.884005) (xy -249.108501 44.884005) (xy -249.108501 41.836005) (xy -250.251501 41.836005)
			)
		)
	)
	(zone
		(layers "F.Cu" "B.Cu" "In1.Cu" "In2.Cu" "In3.Cu" "In4.Cu" "In6.Cu")
		(hatch none 0.5)
		(connect_pads
			(clearance 0)
		)
		(min_thickness 0.25)
		(keepout
			(tracks not_allowed)
			(vias allowed)
			(pads allowed)
			(copperpour not_allowed)
			(footprints allowed)
		)
		(placement
			(enabled no)
			(sheetname "")
		)
		(fill yes
			(thermal_gap 0.5)
			(thermal_bridge_width 0.5)
			(island_removal_mode 0)
		)
		(polygon
			(pts
				(xy -37.2515 36.484001) (xy -36.1085 36.484001) (xy -36.1085 33.436001) (xy -37.2515 33.436001)
			)
		)
	)
	(zone
		(layers "F.Cu" "B.Cu" "In1.Cu" "In2.Cu" "In3.Cu" "In4.Cu" "In6.Cu")
		(hatch none 0.5)
		(connect_pads
			(clearance 0)
		)
		(min_thickness 0.25)
		(keepout
			(tracks not_allowed)
			(vias allowed)
			(pads allowed)
			(copperpour not_allowed)
			(footprints allowed)
		)
		(placement
			(enabled no)
			(sheetname "")
		)
		(fill yes
			(thermal_gap 0.5)
			(thermal_bridge_width 0.5)
			(island_removal_mode 0)
		)
		(polygon
			(pts
				(xy -258.2515 44.884005) (xy -257.1085 44.884005) (xy -257.1085 41.836005) (xy -258.2515 41.836005)
			)
		)
	)
	(zone
		(layers "F.Cu" "B.Cu" "In1.Cu" "In2.Cu" "In3.Cu" "In4.Cu" "In6.Cu")
		(hatch none 0.5)
		(connect_pads
			(clearance 0)
		)
		(min_thickness 0.25)
		(keepout
			(tracks not_allowed)
			(vias allowed)
			(pads allowed)
			(copperpour not_allowed)
			(footprints allowed)
		)
		(placement
			(enabled no)
			(sheetname "")
		)
		(fill yes
			(thermal_gap 0.5)
			(thermal_bridge_width 0.5)
			(island_removal_mode 0)
		)
		(polygon
			(pts
				(xy -395.031938 27.983998) (xy -393.888938 27.983998) (xy -393.888938 24.935998) (xy -395.031938 24.935998)
			)
		)
	)
	(zone
		(layers "F.Cu" "B.Cu" "In1.Cu" "In2.Cu" "In3.Cu" "In4.Cu" "In6.Cu")
		(hatch none 0.5)
		(connect_pads
			(clearance 0)
		)
		(min_thickness 0.25)
		(keepout
			(tracks not_allowed)
			(vias allowed)
			(pads allowed)
			(copperpour not_allowed)
			(footprints allowed)
		)
		(placement
			(enabled no)
			(sheetname "")
		)
		(fill yes
			(thermal_gap 0.5)
			(thermal_bridge_width 0.5)
			(island_removal_mode 0)
		)
		(polygon
			(pts
				(xy -393.031937 29.283998) (xy -391.888937 29.283998) (xy -391.888937 26.235998) (xy -393.031937 26.235998)
			)
		)
	)
	(zone
		(layers "F.Cu" "B.Cu" "In1.Cu" "In2.Cu" "In3.Cu" "In4.Cu" "In6.Cu")
		(hatch none 0.5)
		(connect_pads
			(clearance 0)
		)
		(min_thickness 0.25)
		(keepout
			(tracks not_allowed)
			(vias allowed)
			(pads allowed)
			(copperpour not_allowed)
			(footprints allowed)
		)
		(placement
			(enabled no)
			(sheetname "")
		)
		(fill yes
			(thermal_gap 0.5)
			(thermal_bridge_width 0.5)
			(island_removal_mode 0)
		)
		(polygon
			(pts
				(xy -36.516346 15.473383) (xy -36.153776 15.304313) (xy -35.505136 15.553395) (xy -35.209295 16.187831)
				(xy -35.290435 16.445954) (xy -36.196742 16.868572) (xy -36.44663 16.764813) (xy -36.742474 16.130374)
			)
		)
	)
	(zone
		(layers "F.Cu" "B.Cu" "In1.Cu" "In2.Cu" "In3.Cu" "In4.Cu" "In6.Cu")
		(hatch none 0.5)
		(connect_pads
			(clearance 0)
		)
		(min_thickness 0.25)
		(keepout
			(tracks not_allowed)
			(vias allowed)
			(pads allowed)
			(copperpour not_allowed)
			(footprints allowed)
		)
		(placement
			(enabled no)
			(sheetname "")
		)
		(fill yes
			(thermal_gap 0.5)
			(thermal_bridge_width 0.5)
			(island_removal_mode 0)
		)
		(polygon
			(pts
				(xy -23.915202 25.564559) (xy -24.273873 25.741749) (xy -24.927954 25.50733) (xy -25.238004 24.879714)
				(xy -25.162693 24.619831) (xy -24.266131 24.176919) (xy -24.01397 24.275024) (xy -23.703923 24.90264)
			)
		)
	)
	(zone
		(layers "F.Cu" "B.Cu" "In1.Cu" "In2.Cu" "In3.Cu" "In4.Cu" "In6.Cu")
		(hatch none 0.5)
		(connect_pads
			(clearance 0)
		)
		(min_thickness 0.25)
		(keepout
			(tracks not_allowed)
			(vias allowed)
			(pads allowed)
			(copperpour not_allowed)
			(footprints allowed)
		)
		(placement
			(enabled no)
			(sheetname "")
		)
		(fill yes
			(thermal_gap 0.5)
			(thermal_bridge_width 0.5)
			(island_removal_mode 0)
		)
		(polygon
			(pts
				(xy -403.031937 27.983998) (xy -401.888937 27.983998) (xy -401.888937 24.935998) (xy -403.031937 24.935998)
			)
		)
	)
	(zone
		(layers "F.Cu" "B.Cu" "In1.Cu" "In2.Cu" "In3.Cu" "In4.Cu" "In6.Cu")
		(hatch none 0.5)
		(connect_pads
			(clearance 0)
		)
		(min_thickness 0.25)
		(keepout
			(tracks not_allowed)
			(vias allowed)
			(pads allowed)
			(copperpour not_allowed)
			(footprints allowed)
		)
		(placement
			(enabled no)
			(sheetname "")
		)
		(fill yes
			(thermal_gap 0.5)
			(thermal_bridge_width 0.5)
			(island_removal_mode 0)
		)
		(polygon
			(pts
				(xy -255.915203 25.564559) (xy -256.273874 25.741749) (xy -256.927955 25.50733) (xy -257.238005 24.879714)
				(xy -257.162694 24.619831) (xy -256.266132 24.176919) (xy -256.013971 24.275024) (xy -255.703923 24.90264)
			)
		)
	)
	(zone
		(layers "F.Cu" "B.Cu" "In1.Cu" "In2.Cu" "In3.Cu" "In4.Cu" "In6.Cu")
		(hatch none 0.5)
		(connect_pads
			(clearance 0)
		)
		(min_thickness 0.25)
		(keepout
			(tracks not_allowed)
			(vias allowed)
			(pads allowed)
			(copperpour not_allowed)
			(footprints allowed)
		)
		(placement
			(enabled no)
			(sheetname "")
		)
		(fill yes
			(thermal_gap 0.5)
			(thermal_bridge_width 0.5)
			(island_removal_mode 0)
		)
		(polygon
			(pts
				(xy -36.516346 19.273383) (xy -36.153776 19.104313) (xy -35.505136 19.353395) (xy -35.209295 19.987832)
				(xy -35.290435 20.245954) (xy -36.196742 20.668572) (xy -36.44663 20.564813) (xy -36.742474 19.930374)
			)
		)
	)
	(zone
		(layers "F.Cu" "B.Cu" "In1.Cu" "In2.Cu" "In3.Cu" "In4.Cu" "In6.Cu")
		(hatch none 0.5)
		(connect_pads
			(clearance 0)
		)
		(min_thickness 0.25)
		(keepout
			(tracks not_allowed)
			(vias allowed)
			(pads allowed)
			(copperpour not_allowed)
			(footprints allowed)
		)
		(placement
			(enabled no)
			(sheetname "")
		)
		(fill yes
			(thermal_gap 0.5)
			(thermal_bridge_width 0.5)
			(island_removal_mode 0)
		)
		(polygon
			(pts
				(xy -31.2515 37.784001) (xy -30.1085 37.784001) (xy -30.1085 34.736001) (xy -31.2515 34.736001)
			)
		)
	)
	(zone
		(layers "F.Cu" "B.Cu" "In1.Cu" "In2.Cu" "In3.Cu" "In4.Cu" "In6.Cu")
		(hatch none 0.5)
		(connect_pads
			(clearance 0)
		)
		(min_thickness 0.25)
		(keepout
			(tracks not_allowed)
			(vias allowed)
			(pads allowed)
			(copperpour not_allowed)
			(footprints allowed)
		)
		(placement
			(enabled no)
			(sheetname "")
		)
		(fill yes
			(thermal_gap 0.5)
			(thermal_bridge_width 0.5)
			(island_removal_mode 0)
		)
		(polygon
			(pts
				(xy -37.2515 40.684003) (xy -36.1085 40.684003) (xy -36.1085 37.636003) (xy -37.2515 37.636003)
			)
		)
	)
	(zone
		(layers "F.Cu" "B.Cu" "In1.Cu" "In2.Cu" "In3.Cu" "In4.Cu" "In6.Cu")
		(hatch none 0.5)
		(connect_pads
			(clearance 0)
		)
		(min_thickness 0.25)
		(keepout
			(tracks not_allowed)
			(vias allowed)
			(pads allowed)
			(copperpour not_allowed)
			(footprints allowed)
		)
		(placement
			(enabled no)
			(sheetname "")
		)
		(fill yes
			(thermal_gap 0.5)
			(thermal_bridge_width 0.5)
			(island_removal_mode 0)
		)
		(polygon
			(pts
				(xy -25.516345 19.273383) (xy -25.153775 19.104313) (xy -24.505135 19.353395) (xy -24.209294 19.987832)
				(xy -24.290434 20.245954) (xy -25.196742 20.668572) (xy -25.446629 20.564813) (xy -25.742473 19.930374)
			)
		)
	)
	(zone
		(layers "F.Cu" "B.Cu" "In1.Cu" "In2.Cu" "In3.Cu" "In4.Cu" "In6.Cu")
		(hatch none 0.5)
		(connect_pads
			(clearance 0)
		)
		(min_thickness 0.25)
		(keepout
			(tracks not_allowed)
			(vias allowed)
			(pads allowed)
			(copperpour not_allowed)
			(footprints allowed)
		)
		(placement
			(enabled no)
			(sheetname "")
		)
		(fill yes
			(thermal_gap 0.5)
			(thermal_bridge_width 0.5)
			(island_removal_mode 0)
		)
		(polygon
			(pts
				(xy -34.915203 21.764559) (xy -35.273874 21.941749) (xy -35.927955 21.70733) (xy -36.238005 21.079714)
				(xy -36.162694 20.819831) (xy -35.266132 20.376919) (xy -35.013971 20.475024) (xy -34.703923 21.10264)
			)
		)
	)
	(zone
		(layers "F.Cu" "B.Cu" "In1.Cu" "In2.Cu" "In3.Cu" "In4.Cu" "In6.Cu")
		(hatch none 0.5)
		(connect_pads
			(clearance 0)
		)
		(min_thickness 0.25)
		(keepout
			(tracks not_allowed)
			(vias allowed)
			(pads allowed)
			(copperpour not_allowed)
			(footprints allowed)
		)
		(placement
			(enabled no)
			(sheetname "")
		)
		(fill yes
			(thermal_gap 0.5)
			(thermal_bridge_width 0.5)
			(island_removal_mode 0)
		)
		(polygon
			(pts
				(xy -258.2515 40.684003) (xy -257.1085 40.684003) (xy -257.1085 37.636003) (xy -258.2515 37.636003)
			)
		)
	)
	(zone
		(layers "F.Cu" "B.Cu" "In1.Cu" "In2.Cu" "In3.Cu" "In4.Cu" "In6.Cu")
		(hatch none 0.5)
		(connect_pads
			(clearance 0)
		)
		(min_thickness 0.25)
		(keepout
			(tracks not_allowed)
			(vias allowed)
			(pads allowed)
			(copperpour not_allowed)
			(footprints allowed)
		)
		(placement
			(enabled no)
			(sheetname "")
		)
		(fill yes
			(thermal_gap 0.5)
			(thermal_bridge_width 0.5)
			(island_removal_mode 0)
		)
		(polygon
			(pts
				(xy -23.915202 17.964559) (xy -24.273873 18.141749) (xy -24.927954 17.90733) (xy -25.238004 17.279714)
				(xy -25.162693 17.019831) (xy -24.266131 16.576919) (xy -24.01397 16.675024) (xy -23.703923 17.30264)
			)
		)
	)
	(zone
		(layers "F.Cu" "B.Cu" "In1.Cu" "In2.Cu" "In3.Cu" "In4.Cu" "In6.Cu")
		(hatch none 0.5)
		(connect_pads
			(clearance 0)
		)
		(min_thickness 0.25)
		(keepout
			(tracks not_allowed)
			(vias allowed)
			(pads allowed)
			(copperpour not_allowed)
			(footprints allowed)
		)
		(placement
			(enabled no)
			(sheetname "")
		)
		(fill yes
			(thermal_gap 0.5)
			(thermal_bridge_width 0.5)
			(island_removal_mode 0)
		)
		(polygon
			(pts
				(xy -242.665202 25.564559) (xy -243.023873 25.741749) (xy -243.677953 25.50733) (xy -243.988003 24.879714)
				(xy -243.912692 24.619831) (xy -243.016131 24.176919) (xy -242.76397 24.275024) (xy -242.453922 24.90264)
			)
		)
	)
	(zone
		(layers "F.Cu" "B.Cu" "In1.Cu" "In2.Cu" "In3.Cu" "In4.Cu" "In6.Cu")
		(hatch none 0.5)
		(connect_pads
			(clearance 0)
		)
		(min_thickness 0.25)
		(keepout
			(tracks not_allowed)
			(vias allowed)
			(pads allowed)
			(copperpour not_allowed)
			(footprints allowed)
		)
		(placement
			(enabled no)
			(sheetname "")
		)
		(fill yes
			(thermal_gap 0.5)
			(thermal_bridge_width 0.5)
			(island_removal_mode 0)
		)
		(polygon
			(pts
				(xy -252.2515 37.784001) (xy -251.1085 37.784001) (xy -251.1085 34.736001) (xy -252.2515 34.736001)
			)
		)
	)
	(zone
		(layers "F.Cu" "B.Cu" "In1.Cu" "In2.Cu" "In3.Cu" "In4.Cu" "In6.Cu")
		(hatch none 0.5)
		(connect_pads
			(clearance 0)
		)
		(min_thickness 0.25)
		(keepout
			(tracks not_allowed)
			(vias allowed)
			(pads allowed)
			(copperpour not_allowed)
			(footprints allowed)
		)
		(placement
			(enabled no)
			(sheetname "")
		)
		(fill yes
			(thermal_gap 0.5)
			(thermal_bridge_width 0.5)
			(island_removal_mode 0)
		)
		(polygon
			(pts
				(xy -178.031938 27.983998) (xy -176.888938 27.983998) (xy -176.888938 24.935998) (xy -178.031938 24.935998)
			)
		)
	)
	(zone
		(layers "F.Cu" "B.Cu" "In1.Cu" "In2.Cu" "In3.Cu" "In4.Cu" "In6.Cu")
		(hatch none 0.5)
		(connect_pads
			(clearance 0)
		)
		(min_thickness 0.25)
		(keepout
			(tracks not_allowed)
			(vias allowed)
			(pads allowed)
			(copperpour not_allowed)
			(footprints allowed)
		)
		(placement
			(enabled no)
			(sheetname "")
		)
		(fill yes
			(thermal_gap 0.5)
			(thermal_bridge_width 0.5)
			(island_removal_mode 0)
		)
		(polygon
			(pts
				(xy -27.2515 46.184005) (xy -26.1085 46.184005) (xy -26.1085 43.136005) (xy -27.2515 43.136005)
			)
		)
	)
	(zone
		(layers "F.Cu" "B.Cu" "In1.Cu" "In2.Cu" "In3.Cu" "In4.Cu" "In6.Cu")
		(hatch none 0.5)
		(connect_pads
			(clearance 0)
		)
		(min_thickness 0.25)
		(keepout
			(tracks not_allowed)
			(vias allowed)
			(pads allowed)
			(copperpour not_allowed)
			(footprints allowed)
		)
		(placement
			(enabled no)
			(sheetname "")
		)
		(fill yes
			(thermal_gap 0.5)
			(thermal_bridge_width 0.5)
			(island_removal_mode 0)
		)
		(polygon
			(pts
				(xy -255.915203 21.764559) (xy -256.273874 21.941749) (xy -256.927955 21.70733) (xy -257.238005 21.079714)
				(xy -257.162694 20.819831) (xy -256.266132 20.376919) (xy -256.013971 20.475024) (xy -255.703923 21.10264)
			)
		)
	)
	(zone
		(layers "F.Cu" "B.Cu" "In1.Cu" "In2.Cu" "In3.Cu" "In4.Cu" "In6.Cu")
		(hatch none 0.5)
		(connect_pads
			(clearance 0)
		)
		(min_thickness 0.25)
		(keepout
			(tracks not_allowed)
			(vias allowed)
			(pads allowed)
			(copperpour not_allowed)
			(footprints allowed)
		)
		(placement
			(enabled no)
			(sheetname "")
		)
		(fill yes
			(thermal_gap 0.5)
			(thermal_bridge_width 0.5)
			(island_removal_mode 0)
		)
		(polygon
			(pts
				(xy -256.251499 37.784001) (xy -255.108499 37.784001) (xy -255.108499 34.736001) (xy -256.251499 34.736001)
			)
		)
	)
	(zone
		(layers "F.Cu" "B.Cu" "In1.Cu" "In2.Cu" "In3.Cu" "In4.Cu" "In6.Cu")
		(hatch none 0.5)
		(connect_pads
			(clearance 0)
		)
		(min_thickness 0.25)
		(keepout
			(tracks not_allowed)
			(vias allowed)
			(pads allowed)
			(copperpour not_allowed)
			(footprints allowed)
		)
		(placement
			(enabled no)
			(sheetname "")
		)
		(fill yes
			(thermal_gap 0.5)
			(thermal_bridge_width 0.5)
			(island_removal_mode 0)
		)
		(polygon
			(pts
				(xy -248.2515 46.184005) (xy -247.1085 46.184005) (xy -247.1085 43.136005) (xy -248.2515 43.136005)
			)
		)
	)
	(zone
		(layers "F.Cu" "B.Cu" "In1.Cu" "In2.Cu" "In3.Cu" "In4.Cu" "In6.Cu")
		(hatch none 0.5)
		(connect_pads
			(clearance 0)
		)
		(min_thickness 0.25)
		(keepout
			(tracks not_allowed)
			(vias allowed)
			(pads allowed)
			(copperpour not_allowed)
			(footprints allowed)
		)
		(placement
			(enabled no)
			(sheetname "")
		)
		(fill yes
			(thermal_gap 0.5)
			(thermal_bridge_width 0.5)
			(island_removal_mode 0)
		)
		(polygon
			(pts
				(xy -244.915202 21.764559) (xy -245.273873 21.941749) (xy -245.927954 21.70733) (xy -246.238004 21.079714)
				(xy -246.162693 20.819831) (xy -245.266131 20.376919) (xy -245.01397 20.475024) (xy -244.703923 21.10264)
			)
		)
	)
	(zone
		(layers "F.Cu" "B.Cu" "In1.Cu" "In2.Cu" "In3.Cu" "In4.Cu" "In6.Cu")
		(hatch none 0.5)
		(connect_pads
			(clearance 0)
		)
		(min_thickness 0.25)
		(keepout
			(tracks not_allowed)
			(vias allowed)
			(pads allowed)
			(copperpour not_allowed)
			(footprints allowed)
		)
		(placement
			(enabled no)
			(sheetname "")
		)
		(fill yes
			(thermal_gap 0.5)
			(thermal_bridge_width 0.5)
			(island_removal_mode 0)
		)
		(polygon
			(pts
				(xy -180.031936 29.283998) (xy -178.888936 29.283998) (xy -178.888936 26.235998) (xy -180.031936 26.235998)
			)
		)
	)
	(zone
		(layers "F.Cu" "B.Cu" "In1.Cu" "In2.Cu" "In3.Cu" "In4.Cu" "In6.Cu")
		(hatch none 0.5)
		(connect_pads
			(clearance 0)
		)
		(min_thickness 0.25)
		(keepout
			(tracks not_allowed)
			(vias allowed)
			(pads allowed)
			(copperpour not_allowed)
			(footprints allowed)
		)
		(placement
			(enabled no)
			(sheetname "")
		)
		(fill yes
			(thermal_gap 0.5)
			(thermal_bridge_width 0.5)
			(island_removal_mode 0)
		)
		(polygon
			(pts
				(xy -407.031937 27.983998) (xy -405.888937 27.983998) (xy -405.888937 24.935998) (xy -407.031937 24.935998)
			)
		)
	)
	(zone
		(layers "F.Cu" "B.Cu" "In1.Cu" "In2.Cu" "In3.Cu" "In4.Cu" "In6.Cu")
		(hatch none 0.5)
		(connect_pads
			(clearance 0)
		)
		(min_thickness 0.25)
		(keepout
			(tracks not_allowed)
			(vias allowed)
			(pads allowed)
			(copperpour not_allowed)
			(footprints allowed)
		)
		(placement
			(enabled no)
			(sheetname "")
		)
		(fill yes
			(thermal_gap 0.5)
			(thermal_bridge_width 0.5)
			(island_removal_mode 0)
		)
		(polygon
			(pts
				(xy -36.516346 23.073383) (xy -36.153776 22.904313) (xy -35.505136 23.153395) (xy -35.209295 23.787832)
				(xy -35.290435 24.045954) (xy -36.196742 24.468572) (xy -36.44663 24.364813) (xy -36.742474 23.730374)
			)
		)
	)
	(zone
		(layers "F.Cu" "B.Cu" "In1.Cu" "In2.Cu" "In3.Cu" "In4.Cu" "In6.Cu")
		(hatch none 0.5)
		(connect_pads
			(clearance 0)
		)
		(min_thickness 0.25)
		(keepout
			(tracks not_allowed)
			(vias allowed)
			(pads allowed)
			(copperpour not_allowed)
			(footprints allowed)
		)
		(placement
			(enabled no)
			(sheetname "")
		)
		(fill yes
			(thermal_gap 0.5)
			(thermal_bridge_width 0.5)
			(island_removal_mode 0)
		)
		(polygon
			(pts
				(xy -34.915203 17.964559) (xy -35.273874 18.141749) (xy -35.927955 17.90733) (xy -36.238005 17.279714)
				(xy -36.162694 17.019831) (xy -35.266132 16.576919) (xy -35.013971 16.675024) (xy -34.703923 17.30264)
			)
		)
	)
	(zone
		(layers "F.Cu" "B.Cu" "In1.Cu" "In2.Cu" "In3.Cu" "In4.Cu" "In6.Cu")
		(hatch none 0.5)
		(connect_pads
			(clearance 0)
		)
		(min_thickness 0.25)
		(keepout
			(tracks not_allowed)
			(vias allowed)
			(pads allowed)
			(copperpour not_allowed)
			(footprints allowed)
		)
		(placement
			(enabled no)
			(sheetname "")
		)
		(fill yes
			(thermal_gap 0.5)
			(thermal_bridge_width 0.5)
			(island_removal_mode 0)
		)
		(polygon
			(pts
				(xy -255.266345 23.073383) (xy -254.903775 22.904313) (xy -254.255135 23.153395) (xy -253.959294 23.787832)
				(xy -254.040434 24.045954) (xy -254.946742 24.468572) (xy -255.19663 24.364813) (xy -255.492474 23.730374)
			)
		)
	)
	(zone
		(layers "F.Cu" "B.Cu" "In1.Cu" "In2.Cu" "In3.Cu" "In4.Cu" "In6.Cu")
		(hatch none 0.5)
		(connect_pads
			(clearance 0)
		)
		(min_thickness 0.25)
		(keepout
			(tracks not_allowed)
			(vias allowed)
			(pads allowed)
			(copperpour not_allowed)
			(footprints allowed)
		)
		(placement
			(enabled no)
			(sheetname "")
		)
		(fill yes
			(thermal_gap 0.5)
			(thermal_bridge_width 0.5)
			(island_removal_mode 0)
		)
		(polygon
			(pts
				(xy -184.031936 29.283998) (xy -182.888936 29.283998) (xy -182.888936 26.235998) (xy -184.031936 26.235998)
			)
		)
	)
	(zone
		(layers "F.Cu" "B.Cu" "In1.Cu" "In2.Cu" "In3.Cu" "In4.Cu" "In6.Cu")
		(hatch none 0.5)
		(connect_pads
			(clearance 0)
		)
		(min_thickness 0.25)
		(keepout
			(tracks not_allowed)
			(vias allowed)
			(pads allowed)
			(copperpour not_allowed)
			(footprints allowed)
		)
		(placement
			(enabled no)
			(sheetname "")
		)
		(fill yes
			(thermal_gap 0.5)
			(thermal_bridge_width 0.5)
			(island_removal_mode 0)
		)
		(polygon
			(pts
				(xy -172.031937 29.283998) (xy -170.888937 29.283998) (xy -170.888937 26.235998) (xy -172.031937 26.235998)
			)
		)
	)
	(zone
		(layers "F.Cu" "B.Cu" "In1.Cu" "In2.Cu" "In3.Cu" "In4.Cu" "In6.Cu")
		(hatch none 0.5)
		(connect_pads
			(clearance 0)
		)
		(min_thickness 0.25)
		(keepout
			(tracks not_allowed)
			(vias allowed)
			(pads allowed)
			(copperpour not_allowed)
			(footprints allowed)
		)
		(placement
			(enabled no)
			(sheetname "")
		)
		(fill yes
			(thermal_gap 0.5)
			(thermal_bridge_width 0.5)
			(island_removal_mode 0)
		)
		(polygon
			(pts
				(xy -255.915203 17.964559) (xy -256.273874 18.141749) (xy -256.927955 17.90733) (xy -257.238005 17.279714)
				(xy -257.162694 17.019831) (xy -256.266132 16.576919) (xy -256.013971 16.675024) (xy -255.703923 17.30264)
			)
		)
	)
	(zone
		(layers "F.Cu" "B.Cu" "In1.Cu" "In2.Cu" "In3.Cu" "In4.Cu" "In6.Cu")
		(hatch none 0.5)
		(connect_pads
			(clearance 0)
		)
		(min_thickness 0.25)
		(keepout
			(tracks not_allowed)
			(vias allowed)
			(pads allowed)
			(copperpour not_allowed)
			(footprints allowed)
		)
		(placement
			(enabled no)
			(sheetname "")
		)
		(fill yes
			(thermal_gap 0.5)
			(thermal_bridge_width 0.5)
			(island_removal_mode 0)
		)
		(polygon
			(pts
				(xy -34.915203 25.564559) (xy -35.273874 25.741749) (xy -35.927955 25.50733) (xy -36.238005 24.879714)
				(xy -36.162694 24.619831) (xy -35.266132 24.176919) (xy -35.013971 24.275024) (xy -34.703923 24.90264)
			)
		)
	)
	(zone
		(layers "F.Cu" "B.Cu" "In1.Cu" "In2.Cu" "In3.Cu" "In4.Cu" "In6.Cu")
		(hatch none 0.5)
		(connect_pads
			(clearance 0)
		)
		(min_thickness 0.25)
		(keepout
			(tracks not_allowed)
			(vias allowed)
			(pads allowed)
			(copperpour not_allowed)
			(footprints allowed)
		)
		(placement
			(enabled no)
			(sheetname "")
		)
		(fill yes
			(thermal_gap 0.5)
			(thermal_bridge_width 0.5)
			(island_removal_mode 0)
		)
		(polygon
			(pts
				(xy -246.516345 15.473383) (xy -246.153775 15.304313) (xy -245.505135 15.553395) (xy -245.209294 16.187831)
				(xy -245.290434 16.445954) (xy -246.196742 16.868572) (xy -246.446629 16.764813) (xy -246.742473 16.130374)
			)
		)
	)
	(zone
		(layers "F.Cu" "B.Cu" "In1.Cu" "In2.Cu" "In3.Cu" "In4.Cu" "In6.Cu")
		(hatch none 0.5)
		(connect_pads
			(clearance 0)
		)
		(min_thickness 0.25)
		(keepout
			(tracks not_allowed)
			(vias allowed)
			(pads allowed)
			(copperpour not_allowed)
			(footprints allowed)
		)
		(placement
			(enabled no)
			(sheetname "")
		)
		(fill yes
			(thermal_gap 0.5)
			(thermal_bridge_width 0.5)
			(island_removal_mode 0)
		)
		(polygon
			(pts
				(xy -29.251501 40.684003) (xy -28.108501 40.684003) (xy -28.108501 37.636003) (xy -29.251501 37.636003)
			)
		)
	)
	(zone
		(layers "F.Cu" "B.Cu" "In1.Cu" "In2.Cu" "In3.Cu" "In4.Cu" "In6.Cu")
		(hatch none 0.5)
		(connect_pads
			(clearance 0)
		)
		(min_thickness 0.25)
		(keepout
			(tracks not_allowed)
			(vias allowed)
			(pads allowed)
			(copperpour not_allowed)
			(footprints allowed)
		)
		(placement
			(enabled no)
			(sheetname "")
		)
		(fill yes
			(thermal_gap 0.5)
			(thermal_bridge_width 0.5)
			(island_removal_mode 0)
		)
		(polygon
			(pts
				(xy -33.251501 40.684003) (xy -32.108501 40.684003) (xy -32.108501 37.636003) (xy -33.251501 37.636003)
			)
		)
	)
	(zone
		(layers "F.Cu" "B.Cu" "In1.Cu" "In2.Cu" "In3.Cu" "In4.Cu" "In6.Cu")
		(hatch none 0.5)
		(connect_pads
			(clearance 0)
		)
		(min_thickness 0.25)
		(keepout
			(tracks not_allowed)
			(vias allowed)
			(pads allowed)
			(copperpour not_allowed)
			(footprints allowed)
		)
		(placement
			(enabled no)
			(sheetname "")
		)
		(fill yes
			(thermal_gap 0.5)
			(thermal_bridge_width 0.5)
			(island_removal_mode 0)
		)
		(polygon
			(pts
				(xy -244.915202 17.964559) (xy -245.273873 18.141749) (xy -245.927954 17.90733) (xy -246.238004 17.279714)
				(xy -246.162693 17.019831) (xy -245.266131 16.576919) (xy -245.01397 16.675024) (xy -244.703923 17.30264)
			)
		)
	)
	(zone
		(layers "F.Cu" "B.Cu" "In1.Cu" "In2.Cu" "In3.Cu" "In4.Cu" "In6.Cu")
		(hatch none 0.5)
		(connect_pads
			(clearance 0)
		)
		(min_thickness 0.25)
		(keepout
			(tracks not_allowed)
			(vias allowed)
			(pads allowed)
			(copperpour not_allowed)
			(footprints allowed)
		)
		(placement
			(enabled no)
			(sheetname "")
		)
		(fill yes
			(thermal_gap 0.5)
			(thermal_bridge_width 0.5)
			(island_removal_mode 0)
		)
		(polygon
			(pts
				(xy -253.665203 25.564559) (xy -254.023873 25.741749) (xy -254.677954 25.50733) (xy -254.988004 24.879714)
				(xy -254.912693 24.619831) (xy -254.016132 24.176919) (xy -253.763971 24.275024) (xy -253.453923 24.90264)
			)
		)
	)
	(zone
		(layers "F.Cu" "B.Cu" "In1.Cu" "In2.Cu" "In3.Cu" "In4.Cu" "In6.Cu")
		(hatch none 0.5)
		(connect_pads
			(clearance 0)
		)
		(min_thickness 0.25)
		(keepout
			(tracks not_allowed)
			(vias allowed)
			(pads allowed)
			(copperpour not_allowed)
			(footprints allowed)
		)
		(placement
			(enabled no)
			(sheetname "")
		)
		(fill yes
			(thermal_gap 0.5)
			(thermal_bridge_width 0.5)
			(island_removal_mode 0)
		)
		(polygon
			(pts
				(xy -399.031938 27.983998) (xy -397.888938 27.983998) (xy -397.888938 24.935998) (xy -399.031938 24.935998)
			)
		)
	)
	(zone
		(layers "F.Cu" "B.Cu" "In1.Cu" "In2.Cu" "In3.Cu" "In4.Cu" "In6.Cu")
		(hatch none 0.5)
		(connect_pads
			(clearance 0)
		)
		(min_thickness 0.25)
		(keepout
			(tracks not_allowed)
			(vias allowed)
			(pads allowed)
			(copperpour not_allowed)
			(footprints allowed)
		)
		(placement
			(enabled no)
			(sheetname "")
		)
		(fill yes
			(thermal_gap 0.5)
			(thermal_bridge_width 0.5)
			(island_removal_mode 0)
		)
		(polygon
			(pts
				(xy -182.031937 27.983998) (xy -180.888937 27.983998) (xy -180.888937 24.935998) (xy -182.031937 24.935998)
			)
		)
	)
	(zone
		(layers "F.Cu" "B.Cu" "In1.Cu" "In2.Cu" "In3.Cu" "In4.Cu" "In6.Cu")
		(hatch none 0.5)
		(connect_pads
			(clearance 0)
		)
		(min_thickness 0.25)
		(keepout
			(tracks not_allowed)
			(vias allowed)
			(pads allowed)
			(copperpour not_allowed)
			(footprints allowed)
		)
		(placement
			(enabled no)
			(sheetname "")
		)
		(fill yes
			(thermal_gap 0.5)
			(thermal_bridge_width 0.5)
			(island_removal_mode 0)
		)
		(polygon
			(pts
				(xy -83.611938 36.483996) (xy -82.468938 36.483996) (xy -82.468938 33.435996) (xy -83.611938 33.435996)
			)
		)
	)
	(zone
		(layers "F.Cu" "B.Cu" "In1.Cu" "In2.Cu" "In3.Cu" "In4.Cu" "In6.Cu")
		(hatch none 0.5)
		(connect_pads
			(clearance 0)
		)
		(min_thickness 0.25)
		(keepout
			(tracks not_allowed)
			(vias allowed)
			(pads allowed)
			(copperpour not_allowed)
			(footprints allowed)
		)
		(placement
			(enabled no)
			(sheetname "")
		)
		(fill yes
			(thermal_gap 0.5)
			(thermal_bridge_width 0.5)
			(island_removal_mode 0)
		)
		(polygon
			(pts
				(xy -257.516346 11.673383) (xy -257.153776 11.504313) (xy -256.505136 11.753395) (xy -256.209295 12.387831)
				(xy -256.290435 12.645954) (xy -257.196742 13.068572) (xy -257.44663 12.964813) (xy -257.742474 12.330374)
			)
		)
	)
	(zone
		(layers "F.Cu" "B.Cu" "In1.Cu" "In2.Cu" "In3.Cu" "In4.Cu" "In6.Cu")
		(hatch none 0.5)
		(connect_pads
			(clearance 0)
		)
		(min_thickness 0.25)
		(keepout
			(tracks not_allowed)
			(vias allowed)
			(pads allowed)
			(copperpour not_allowed)
			(footprints allowed)
		)
		(placement
			(enabled no)
			(sheetname "")
		)
		(fill yes
			(thermal_gap 0.5)
			(thermal_bridge_width 0.5)
			(island_removal_mode 0)
		)
		(polygon
			(pts
				(xy -255.915203 14.164559) (xy -256.273874 14.341749) (xy -256.927955 14.10733) (xy -257.238005 13.479714)
				(xy -257.162694 13.219831) (xy -256.266132 12.776919) (xy -256.013971 12.875024) (xy -255.703923 13.50264)
			)
		)
	)
	(zone
		(layers "F.Cu" "B.Cu" "In1.Cu" "In2.Cu" "In3.Cu" "In4.Cu" "In6.Cu")
		(hatch none 0.5)
		(connect_pads
			(clearance 0)
		)
		(min_thickness 0.25)
		(keepout
			(tracks not_allowed)
			(vias allowed)
			(pads allowed)
			(copperpour not_allowed)
			(footprints allowed)
		)
		(placement
			(enabled no)
			(sheetname "")
		)
		(fill yes
			(thermal_gap 0.5)
			(thermal_bridge_width 0.5)
			(island_removal_mode 0)
		)
		(polygon
			(pts
				(xy -21.665202 25.564559) (xy -22.023873 25.741749) (xy -22.677953 25.50733) (xy -22.988003 24.879714)
				(xy -22.912692 24.619831) (xy -22.016131 24.176919) (xy -21.76397 24.275024) (xy -21.453922 24.90264)
			)
		)
	)
	(zone
		(layers "F.Cu" "B.Cu" "In1.Cu" "In2.Cu" "In3.Cu" "In4.Cu" "In6.Cu")
		(hatch none 0.5)
		(connect_pads
			(clearance 0)
		)
		(min_thickness 0.25)
		(keepout
			(tracks not_allowed)
			(vias allowed)
			(pads allowed)
			(copperpour not_allowed)
			(footprints allowed)
		)
		(placement
			(enabled no)
			(sheetname "")
		)
		(fill yes
			(thermal_gap 0.5)
			(thermal_bridge_width 0.5)
			(island_removal_mode 0)
		)
		(polygon
			(pts
				(xy -34.915203 14.164559) (xy -35.273874 14.341749) (xy -35.927955 14.10733) (xy -36.238005 13.479714)
				(xy -36.162694 13.219831) (xy -35.266132 12.776919) (xy -35.013971 12.875024) (xy -34.703923 13.50264)
			)
		)
	)
	(zone
		(layers "F.Cu" "B.Cu" "In1.Cu" "In2.Cu" "In3.Cu" "In4.Cu" "In6.Cu")
		(hatch none 0.5)
		(connect_pads
			(clearance 0)
		)
		(min_thickness 0.25)
		(keepout
			(tracks not_allowed)
			(vias allowed)
			(pads allowed)
			(copperpour not_allowed)
			(footprints allowed)
		)
		(placement
			(enabled no)
			(sheetname "")
		)
		(fill yes
			(thermal_gap 0.5)
			(thermal_bridge_width 0.5)
			(island_removal_mode 0)
		)
		(polygon
			(pts
				(xy -176.031936 29.283998) (xy -174.888936 29.283998) (xy -174.888936 26.235998) (xy -176.031936 26.235998)
			)
		)
	)
	(zone
		(layers "F.Cu" "B.Cu" "In1.Cu" "In2.Cu" "In3.Cu" "In4.Cu" "In6.Cu")
		(hatch none 0.5)
		(connect_pads
			(clearance 0)
		)
		(min_thickness 0.25)
		(keepout
			(tracks not_allowed)
			(vias allowed)
			(pads allowed)
			(copperpour not_allowed)
			(footprints allowed)
		)
		(placement
			(enabled no)
			(sheetname "")
		)
		(fill yes
			(thermal_gap 0.5)
			(thermal_bridge_width 0.5)
			(island_removal_mode 0)
		)
		(polygon
			(pts
				(xy -304.611938 36.483996) (xy -303.468938 36.483996) (xy -303.468938 33.435996) (xy -304.611938 33.435996)
			)
		)
	)
	(zone
		(layers "F.Cu" "B.Cu" "In1.Cu" "In2.Cu" "In3.Cu" "In4.Cu" "In6.Cu")
		(hatch none 0.5)
		(connect_pads
			(clearance 0)
		)
		(min_thickness 0.25)
		(keepout
			(tracks not_allowed)
			(vias allowed)
			(pads allowed)
			(copperpour not_allowed)
			(footprints allowed)
		)
		(placement
			(enabled no)
			(sheetname "")
		)
		(fill yes
			(thermal_gap 0.5)
			(thermal_bridge_width 0.5)
			(island_removal_mode 0)
		)
		(polygon
			(pts
				(xy -36.516346 11.673383) (xy -36.153776 11.504313) (xy -35.505136 11.753395) (xy -35.209295 12.387831)
				(xy -35.290435 12.645954) (xy -36.196742 13.068572) (xy -36.44663 12.964813) (xy -36.742474 12.330374)
			)
		)
	)
	(zone
		(layers "F.Cu" "B.Cu" "In1.Cu" "In2.Cu" "In3.Cu" "In4.Cu" "In6.Cu")
		(hatch none 0.5)
		(connect_pads
			(clearance 0)
		)
		(min_thickness 0.25)
		(keepout
			(tracks not_allowed)
			(vias allowed)
			(pads allowed)
			(copperpour not_allowed)
			(footprints allowed)
		)
		(placement
			(enabled no)
			(sheetname "")
		)
		(fill yes
			(thermal_gap 0.5)
			(thermal_bridge_width 0.5)
			(island_removal_mode 0)
		)
		(polygon
			(pts
				(xy -257.516346 23.073383) (xy -257.153776 22.904313) (xy -256.505136 23.153395) (xy -256.209295 23.787832)
				(xy -256.290435 24.045954) (xy -257.196742 24.468572) (xy -257.44663 24.364813) (xy -257.742474 23.730374)
			)
		)
	)
	(zone
		(layers "F.Cu" "B.Cu" "In1.Cu" "In2.Cu" "In3.Cu" "In4.Cu" "In6.Cu")
		(hatch none 0.5)
		(connect_pads
			(clearance 0)
		)
		(min_thickness 0.25)
		(keepout
			(tracks not_allowed)
			(vias allowed)
			(pads allowed)
			(copperpour not_allowed)
			(footprints allowed)
		)
		(placement
			(enabled no)
			(sheetname "")
		)
		(fill yes
			(thermal_gap 0.5)
			(thermal_bridge_width 0.5)
			(island_removal_mode 0)
		)
		(polygon
			(pts
				(xy -246.516345 23.073383) (xy -246.153775 22.904313) (xy -245.505135 23.153395) (xy -245.209294 23.787832)
				(xy -245.290434 24.045954) (xy -246.196742 24.468572) (xy -246.446629 24.364813) (xy -246.742473 23.730374)
			)
		)
	)
	(zone
		(layers "F.Cu" "B.Cu" "In1.Cu" "In2.Cu" "In3.Cu" "In4.Cu" "In6.Cu")
		(hatch none 0.5)
		(connect_pads
			(clearance 0)
		)
		(min_thickness 0.25)
		(keepout
			(tracks not_allowed)
			(vias allowed)
			(pads allowed)
			(copperpour not_allowed)
			(footprints allowed)
		)
		(placement
			(enabled no)
			(sheetname "")
		)
		(fill yes
			(thermal_gap 0.5)
			(thermal_bridge_width 0.5)
			(island_removal_mode 0)
		)
		(polygon
			(pts
				(xy -397.031936 29.283998) (xy -395.888936 29.283998) (xy -395.888936 26.235998) (xy -397.031936 26.235998)
			)
		)
	)
	(zone
		(layers "F.Cu" "B.Cu" "In1.Cu" "In2.Cu" "In3.Cu" "In4.Cu" "In6.Cu")
		(hatch none 0.5)
		(connect_pads
			(clearance 0)
		)
		(min_thickness 0.25)
		(keepout
			(tracks not_allowed)
			(vias allowed)
			(pads allowed)
			(copperpour not_allowed)
			(footprints allowed)
		)
		(placement
			(enabled no)
			(sheetname "")
		)
		(fill yes
			(thermal_gap 0.5)
			(thermal_bridge_width 0.5)
			(island_removal_mode 0)
		)
		(polygon
			(pts
				(xy -405.031936 29.283998) (xy -403.888936 29.283998) (xy -403.888936 26.235998) (xy -405.031936 26.235998)
			)
		)
	)
	(zone
		(layers "F.Cu" "B.Cu" "In1.Cu" "In2.Cu" "In3.Cu" "In4.Cu" "In6.Cu")
		(hatch none 0.5)
		(connect_pads
			(clearance 0)
		)
		(min_thickness 0.25)
		(keepout
			(tracks not_allowed)
			(vias allowed)
			(pads allowed)
			(copperpour not_allowed)
			(footprints allowed)
		)
		(placement
			(enabled no)
			(sheetname "")
		)
		(fill yes
			(thermal_gap 0.5)
			(thermal_bridge_width 0.5)
			(island_removal_mode 0)
		)
		(polygon
			(pts
				(xy -25.516345 23.073383) (xy -25.153775 22.904313) (xy -24.505135 23.153395) (xy -24.209294 23.787832)
				(xy -24.290434 24.045954) (xy -25.196742 24.468572) (xy -25.446629 24.364813) (xy -25.742473 23.730374)
			)
		)
	)
	(zone
		(layers "F.Cu" "B.Cu" "In1.Cu" "In2.Cu" "In3.Cu" "In4.Cu" "In6.Cu")
		(hatch none 0.5)
		(connect_pads
			(clearance 0)
		)
		(min_thickness 0.25)
		(keepout
			(tracks not_allowed)
			(vias allowed)
			(pads allowed)
			(copperpour not_allowed)
			(footprints allowed)
		)
		(placement
			(enabled no)
			(sheetname "")
		)
		(fill yes
			(thermal_gap 0.5)
			(thermal_bridge_width 0.5)
			(island_removal_mode 0)
		)
		(polygon
			(pts
				(xy -186.031937 27.983998) (xy -184.888937 27.983998) (xy -184.888937 24.935998) (xy -186.031937 24.935998)
			)
		)
	)
	(zone
		(layers "F.Cu" "B.Cu" "In1.Cu" "In2.Cu" "In3.Cu" "In4.Cu" "In6.Cu")
		(hatch none 0.5)
		(connect_pads
			(clearance 0)
		)
		(min_thickness 0.25)
		(keepout
			(tracks not_allowed)
			(vias allowed)
			(pads allowed)
			(copperpour not_allowed)
			(footprints allowed)
		)
		(placement
			(enabled no)
			(sheetname "")
		)
		(fill yes
			(thermal_gap 0.5)
			(thermal_bridge_width 0.5)
			(island_removal_mode 0)
		)
		(polygon
			(pts
				(xy -257.516346 19.273383) (xy -257.153776 19.104313) (xy -256.505136 19.353395) (xy -256.209295 19.987832)
				(xy -256.290435 20.245954) (xy -257.196742 20.668572) (xy -257.44663 20.564813) (xy -257.742474 19.930374)
			)
		)
	)
	(zone
		(layers "F.Cu" "B.Cu" "In1.Cu" "In2.Cu" "In3.Cu" "In4.Cu" "In6.Cu")
		(hatch none 0.5)
		(connect_pads
			(clearance 0)
		)
		(min_thickness 0.25)
		(keepout
			(tracks not_allowed)
			(vias allowed)
			(pads allowed)
			(copperpour not_allowed)
			(footprints allowed)
		)
		(placement
			(enabled no)
			(sheetname "")
		)
		(fill yes
			(thermal_gap 0.5)
			(thermal_bridge_width 0.5)
			(island_removal_mode 0)
		)
		(polygon
			(pts
				(xy -23.915202 21.764559) (xy -24.273873 21.941749) (xy -24.927954 21.70733) (xy -25.238004 21.079714)
				(xy -25.162693 20.819831) (xy -24.266131 20.376919) (xy -24.01397 20.475024) (xy -23.703923 21.10264)
			)
		)
	)
	(zone
		(layers "F.Cu" "B.Cu" "In1.Cu" "In2.Cu" "In3.Cu" "In4.Cu" "In6.Cu")
		(hatch none 0.5)
		(connect_pads
			(clearance 0)
		)
		(min_thickness 0.25)
		(keepout
			(tracks not_allowed)
			(vias allowed)
			(pads allowed)
			(copperpour not_allowed)
			(footprints allowed)
		)
		(placement
			(enabled no)
			(sheetname "")
		)
		(fill yes
			(thermal_gap 0.5)
			(thermal_bridge_width 0.5)
			(island_removal_mode 0)
		)
		(polygon
			(pts
				(xy -258.2515 36.484001) (xy -257.1085 36.484001) (xy -257.1085 33.436001) (xy -258.2515 33.436001)
			)
		)
	)
	(zone
		(layers "F.Cu" "B.Cu" "In1.Cu" "In2.Cu" "In3.Cu" "In4.Cu" "In6.Cu")
		(hatch none 0.5)
		(connect_pads
			(clearance 0)
		)
		(min_thickness 0.25)
		(keepout
			(tracks not_allowed)
			(vias allowed)
			(pads allowed)
			(copperpour not_allowed)
			(footprints allowed)
		)
		(placement
			(enabled no)
			(sheetname "")
		)
		(fill yes
			(thermal_gap 0.5)
			(thermal_bridge_width 0.5)
			(island_removal_mode 0)
		)
		(polygon
			(pts
				(xy -250.251501 40.684003) (xy -249.108501 40.684003) (xy -249.108501 37.636003) (xy -250.251501 37.636003)
			)
		)
	)
	(zone
		(layers "F.Cu" "B.Cu" "In1.Cu" "In2.Cu" "In3.Cu" "In4.Cu" "In6.Cu")
		(hatch none 0.5)
		(connect_pads
			(clearance 0)
		)
		(min_thickness 0.25)
		(keepout
			(tracks not_allowed)
			(vias allowed)
			(pads allowed)
			(copperpour not_allowed)
			(footprints allowed)
		)
		(placement
			(enabled no)
			(sheetname "")
		)
		(fill yes
			(thermal_gap 0.5)
			(thermal_bridge_width 0.5)
			(island_removal_mode 0)
		)
		(polygon
			(pts
				(xy -34.266345 23.073383) (xy -33.903775 22.904313) (xy -33.255135 23.153395) (xy -32.959294 23.787832)
				(xy -33.040434 24.045954) (xy -33.946742 24.468572) (xy -34.19663 24.364813) (xy -34.492474 23.730374)
			)
		)
	)
	(zone
		(layers "F.Cu" "B.Cu" "In1.Cu" "In2.Cu" "In3.Cu" "In4.Cu" "In6.Cu")
		(hatch none 0.5)
		(connect_pads
			(clearance 0)
		)
		(min_thickness 0.25)
		(keepout
			(tracks not_allowed)
			(vias allowed)
			(pads allowed)
			(copperpour not_allowed)
			(footprints allowed)
		)
		(placement
			(enabled no)
			(sheetname "")
		)
		(fill yes
			(thermal_gap 0.5)
			(thermal_bridge_width 0.5)
			(island_removal_mode 0)
		)
		(polygon
			(pts
				(xy -257.516346 15.473383) (xy -257.153776 15.304313) (xy -256.505136 15.553395) (xy -256.209295 16.187831)
				(xy -256.290435 16.445954) (xy -257.196742 16.868572) (xy -257.44663 16.764813) (xy -257.742474 16.130374)
			)
		)
	)
	(zone
		(layers "F.Cu" "B.Cu" "In1.Cu" "In2.Cu" "In3.Cu" "In4.Cu" "In6.Cu")
		(hatch none 0.5)
		(connect_pads
			(clearance 0)
		)
		(min_thickness 0.25)
		(keepout
			(tracks not_allowed)
			(vias allowed)
			(pads allowed)
			(copperpour not_allowed)
			(footprints allowed)
		)
		(placement
			(enabled no)
			(sheetname "")
		)
		(fill yes
			(thermal_gap 0.5)
			(thermal_bridge_width 0.5)
			(island_removal_mode 0)
		)
		(polygon
			(pts
				(xy -25.516345 15.473383) (xy -25.153775 15.304313) (xy -24.505135 15.553395) (xy -24.209294 16.187831)
				(xy -24.290434 16.445954) (xy -25.196742 16.868572) (xy -25.446629 16.764813) (xy -25.742473 16.130374)
			)
		)
	)
	(zone
		(layers "F.Cu" "B.Cu" "In1.Cu" "In2.Cu" "In3.Cu" "In4.Cu" "In6.Cu")
		(hatch none 0.5)
		(connect_pads
			(clearance 0)
		)
		(min_thickness 0.25)
		(keepout
			(tracks not_allowed)
			(vias allowed)
			(pads allowed)
			(copperpour not_allowed)
			(footprints allowed)
		)
		(placement
			(enabled no)
			(sheetname "")
		)
		(fill yes
			(thermal_gap 0.5)
			(thermal_bridge_width 0.5)
			(island_removal_mode 0)
		)
		(polygon
			(pts
				(xy -174.031938 27.983998) (xy -172.888938 27.983998) (xy -172.888938 24.935998) (xy -174.031938 24.935998)
			)
		)
	)
	(zone
		(layers "F.Cu" "B.Cu" "In1.Cu" "In2.Cu" "In3.Cu" "In4.Cu" "In6.Cu")
		(hatch none 0.5)
		(connect_pads
			(clearance 0)
		)
		(min_thickness 0.25)
		(keepout
			(tracks not_allowed)
			(vias allowed)
			(pads allowed)
			(copperpour not_allowed)
			(footprints allowed)
		)
		(placement
			(enabled no)
			(sheetname "")
		)
		(fill yes
			(thermal_gap 0.5)
			(thermal_bridge_width 0.5)
			(island_removal_mode 0)
		)
		(polygon
			(pts
				(xy -35.251499 37.784001) (xy -34.108499 37.784001) (xy -34.108499 34.736001) (xy -35.251499 34.736001)
			)
		)
	)
	(zone
		(layers "F.Cu" "B.Cu" "In1.Cu" "In2.Cu" "In3.Cu" "In4.Cu" "In6.Cu")
		(hatch none 0.5)
		(connect_pads
			(clearance 0)
		)
		(min_thickness 0.25)
		(keepout
			(tracks not_allowed)
			(vias allowed)
			(pads allowed)
			(copperpour not_allowed)
			(footprints allowed)
		)
		(placement
			(enabled no)
			(sheetname "")
		)
		(fill yes
			(thermal_gap 0.5)
			(thermal_bridge_width 0.5)
			(island_removal_mode 0)
		)
		(polygon
			(pts
				(xy -29.251501 44.884005) (xy -28.108501 44.884005) (xy -28.108501 41.836005) (xy -29.251501 41.836005)
			)
		)
	)
	(zone
		(layers "F.Cu" "B.Cu" "In1.Cu" "In2.Cu" "In3.Cu" "In4.Cu" "In6.Cu")
		(hatch none 0.5)
		(connect_pads
			(clearance 0)
		)
		(min_thickness 0.25)
		(keepout
			(tracks not_allowed)
			(vias allowed)
			(pads allowed)
			(copperpour not_allowed)
			(footprints allowed)
		)
		(placement
			(enabled no)
			(sheetname "")
		)
		(fill yes
			(thermal_gap 0.5)
			(thermal_bridge_width 0.5)
			(island_removal_mode 0)
		)
		(polygon
			(pts
				(xy -254.251501 40.684003) (xy -253.108501 40.684003) (xy -253.108501 37.636003) (xy -254.251501 37.636003)
			)
		)
	)
	(zone
		(layers "F.Cu" "B.Cu" "In1.Cu" "In2.Cu" "In3.Cu" "In4.Cu" "In6.Cu")
		(hatch none 0.5)
		(connect_pads
			(clearance 0)
		)
		(min_thickness 0.25)
		(keepout
			(tracks not_allowed)
			(vias allowed)
			(pads allowed)
			(copperpour not_allowed)
			(footprints allowed)
		)
		(placement
			(enabled no)
			(sheetname "")
		)
		(fill yes
			(thermal_gap 0.5)
			(thermal_bridge_width 0.5)
			(island_removal_mode 0)
		)
		(polygon
			(pts
				(xy -401.031936 29.283998) (xy -399.888936 29.283998) (xy -399.888936 26.235998) (xy -401.031936 26.235998)
			)
		)
	)
	(zone
		(layers "F.Cu" "B.Cu" "In1.Cu" "In2.Cu" "In3.Cu" "In4.Cu" "In6.Cu")
		(hatch none 0.5)
		(connect_pads
			(clearance 0)
		)
		(min_thickness 0.25)
		(keepout
			(tracks not_allowed)
			(vias allowed)
			(pads allowed)
			(copperpour not_allowed)
			(footprints allowed)
		)
		(placement
			(enabled no)
			(sheetname "")
		)
		(fill yes
			(thermal_gap 0.5)
			(thermal_bridge_width 0.5)
			(island_removal_mode 0)
		)
		(polygon
			(pts
				(xy -244.266344 23.073383) (xy -243.903774 22.904313) (xy -243.255135 23.153395) (xy -242.959293 23.787832)
				(xy -243.040433 24.045954) (xy -243.946741 24.468572) (xy -244.196629 24.364813) (xy -244.492473 23.730374)
			)
		)
	)
	(zone
		(layers "F.Cu" "B.Cu" "In1.Cu" "In2.Cu" "In3.Cu" "In4.Cu" "In6.Cu")
		(hatch none 0.5)
		(connect_pads
			(clearance 0)
		)
		(min_thickness 0.25)
		(keepout
			(tracks not_allowed)
			(vias allowed)
			(pads allowed)
			(copperpour not_allowed)
			(footprints allowed)
		)
		(placement
			(enabled no)
			(sheetname "")
		)
		(fill yes
			(thermal_gap 0.5)
			(thermal_bridge_width 0.5)
			(island_removal_mode 0)
		)
		(polygon
			(pts
				(xy -244.915202 25.564559) (xy -245.273873 25.741749) (xy -245.927954 25.50733) (xy -246.238004 24.879714)
				(xy -246.162693 24.619831) (xy -245.266131 24.176919) (xy -245.01397 24.275024) (xy -244.703923 24.90264)
			)
		)
	)
	(zone
		(layers "F.Cu" "B.Cu" "In1.Cu" "In2.Cu" "In3.Cu" "In4.Cu" "In6.Cu")
		(hatch none 0.5)
		(connect_pads
			(clearance 0)
		)
		(min_thickness 0.25)
		(keepout
			(tracks not_allowed)
			(vias allowed)
			(pads allowed)
			(copperpour not_allowed)
			(footprints allowed)
		)
		(placement
			(enabled no)
			(sheetname "")
		)
		(fill yes
			(thermal_gap 0.5)
			(thermal_bridge_width 0.5)
			(island_removal_mode 0)
		)
		(polygon
			(pts
				(xy -32.665203 25.564559) (xy -33.023874 25.741749) (xy -33.677954 25.50733) (xy -33.988004 24.879714)
				(xy -33.912693 24.619831) (xy -33.016132 24.176919) (xy -32.763971 24.275024) (xy -32.453923 24.90264)
			)
		)
	)
	(zone
		(layers "F.Cu" "B.Cu" "In1.Cu" "In2.Cu" "In3.Cu" "In4.Cu" "In6.Cu")
		(hatch none 0.5)
		(connect_pads
			(clearance 0)
		)
		(min_thickness 0.25)
		(keepout
			(tracks not_allowed)
			(vias allowed)
			(pads allowed)
			(copperpour not_allowed)
			(footprints allowed)
		)
		(placement
			(enabled no)
			(sheetname "")
		)
		(fill yes
			(thermal_gap 0.5)
			(thermal_bridge_width 0.5)
			(island_removal_mode 0)
		)
		(polygon
			(pts
				(xy -246.516345 19.273383) (xy -246.153775 19.104313) (xy -245.505135 19.353395) (xy -245.209294 19.987832)
				(xy -245.290434 20.245954) (xy -246.196742 20.668572) (xy -246.446629 20.564813) (xy -246.742473 19.930374)
			)
		)
	)
	(zone
		(layers "F.Cu" "B.Cu" "In1.Cu" "In2.Cu" "In3.Cu" "In4.Cu" "In6.Cu")
		(hatch none 0.5)
		(connect_pads
			(clearance 0)
		)
		(min_thickness 0.25)
		(keepout
			(tracks not_allowed)
			(vias allowed)
			(pads allowed)
			(copperpour not_allowed)
			(footprints allowed)
		)
		(placement
			(enabled no)
			(sheetname "")
		)
		(fill yes
			(thermal_gap 0.5)
			(thermal_bridge_width 0.5)
			(island_removal_mode 0)
		)
		(polygon
			(pts
				(xy -23.266344 23.073383) (xy -22.903774 22.904313) (xy -22.255135 23.153395) (xy -21.959293 23.787832)
				(xy -22.040433 24.045954) (xy -22.946741 24.468572) (xy -23.196629 24.364813) (xy -23.492473 23.730374)
			)
		)
	)
	(zone
		(layers "F.Cu" "B.Cu" "In1.Cu" "In2.Cu" "In3.Cu" "In4.Cu" "In6.Cu")
		(hatch none 0.5)
		(connect_pads
			(clearance 0)
		)
		(min_thickness 0.25)
		(keepout
			(tracks not_allowed)
			(vias allowed)
			(pads allowed)
			(copperpour not_allowed)
			(footprints allowed)
		)
		(placement
			(enabled no)
			(sheetname "")
		)
		(fill yes
			(thermal_gap 0.5)
			(thermal_bridge_width 0.5)
			(island_removal_mode 0)
		)
		(polygon
			(pts
				(xy -37.2515 44.884005) (xy -36.1085 44.884005) (xy -36.1085 41.836005) (xy -37.2515 41.836005)
			)
		)
	)
	(zone
		(layers "F.Cu" "B.Cu" "In1.Cu" "In2.Cu" "In4.Cu" "In5.Cu" "In6.Cu")
		(hatch none 0.5)
		(connect_pads
			(clearance 0)
		)
		(min_thickness 0.25)
		(keepout
			(tracks not_allowed)
			(vias allowed)
			(pads allowed)
			(copperpour not_allowed)
			(footprints allowed)
		)
		(placement
			(enabled no)
			(sheetname "")
		)
		(fill yes
			(thermal_gap 0.5)
			(thermal_bridge_width 0.5)
			(island_removal_mode 0)
		)
		(polygon
			(pts
				(xy -393.031937 37.684001) (xy -391.888937 37.684001) (xy -391.888937 34.636001) (xy -393.031937 34.636001)
			)
		)
	)
	(zone
		(layers "F.Cu" "B.Cu" "In1.Cu" "In2.Cu" "In4.Cu" "In5.Cu" "In6.Cu")
		(hatch none 0.5)
		(connect_pads
			(clearance 0)
		)
		(min_thickness 0.25)
		(keepout
			(tracks not_allowed)
			(vias allowed)
			(pads allowed)
			(copperpour not_allowed)
			(footprints allowed)
		)
		(placement
			(enabled no)
			(sheetname "")
		)
		(fill yes
			(thermal_gap 0.5)
			(thermal_bridge_width 0.5)
			(island_removal_mode 0)
		)
		(polygon
			(pts
				(xy -395.031938 36.384001) (xy -393.888938 36.384001) (xy -393.888938 33.336001) (xy -395.031938 33.336001)
			)
		)
	)
	(zone
		(layers "F.Cu" "B.Cu" "In1.Cu" "In2.Cu" "In4.Cu" "In5.Cu" "In6.Cu")
		(hatch none 0.5)
		(connect_pads
			(clearance 0)
		)
		(min_thickness 0.25)
		(keepout
			(tracks not_allowed)
			(vias allowed)
			(pads allowed)
			(copperpour not_allowed)
			(footprints allowed)
		)
		(placement
			(enabled no)
			(sheetname "")
		)
		(fill yes
			(thermal_gap 0.5)
			(thermal_bridge_width 0.5)
			(island_removal_mode 0)
		)
		(polygon
			(pts
				(xy -176.031936 37.684001) (xy -174.888936 37.684001) (xy -174.888936 34.636001) (xy -176.031936 34.636001)
			)
		)
	)
	(zone
		(layers "F.Cu" "B.Cu" "In1.Cu" "In2.Cu" "In4.Cu" "In5.Cu" "In6.Cu")
		(hatch none 0.5)
		(connect_pads
			(clearance 0)
		)
		(min_thickness 0.25)
		(keepout
			(tracks not_allowed)
			(vias allowed)
			(pads allowed)
			(copperpour not_allowed)
			(footprints allowed)
		)
		(placement
			(enabled no)
			(sheetname "")
		)
		(fill yes
			(thermal_gap 0.5)
			(thermal_bridge_width 0.5)
			(island_removal_mode 0)
		)
		(polygon
			(pts
				(xy -172.031937 37.684001) (xy -170.888937 37.684001) (xy -170.888937 34.636001) (xy -172.031937 34.636001)
			)
		)
	)
	(zone
		(layers "F.Cu" "B.Cu" "In1.Cu" "In2.Cu" "In4.Cu" "In5.Cu" "In6.Cu")
		(hatch none 0.5)
		(connect_pads
			(clearance 0)
		)
		(min_thickness 0.25)
		(keepout
			(tracks not_allowed)
			(vias allowed)
			(pads allowed)
			(copperpour not_allowed)
			(footprints allowed)
		)
		(placement
			(enabled no)
			(sheetname "")
		)
		(fill yes
			(thermal_gap 0.5)
			(thermal_bridge_width 0.5)
			(island_removal_mode 0)
		)
		(polygon
			(pts
				(xy -184.031936 37.684001) (xy -182.888936 37.684001) (xy -182.888936 34.636001) (xy -184.031936 34.636001)
			)
		)
	)
	(zone
		(layers "F.Cu" "B.Cu" "In1.Cu" "In2.Cu" "In4.Cu" "In5.Cu" "In6.Cu")
		(hatch none 0.5)
		(connect_pads
			(clearance 0)
		)
		(min_thickness 0.25)
		(keepout
			(tracks not_allowed)
			(vias allowed)
			(pads allowed)
			(copperpour not_allowed)
			(footprints allowed)
		)
		(placement
			(enabled no)
			(sheetname "")
		)
		(fill yes
			(thermal_gap 0.5)
			(thermal_bridge_width 0.5)
			(island_removal_mode 0)
		)
		(polygon
			(pts
				(xy -403.031937 36.384001) (xy -401.888937 36.384001) (xy -401.888937 33.336001) (xy -403.031937 33.336001)
			)
		)
	)
	(zone
		(layers "F.Cu" "B.Cu" "In1.Cu" "In2.Cu" "In4.Cu" "In5.Cu" "In6.Cu")
		(hatch none 0.5)
		(connect_pads
			(clearance 0)
		)
		(min_thickness 0.25)
		(keepout
			(tracks not_allowed)
			(vias allowed)
			(pads allowed)
			(copperpour not_allowed)
			(footprints allowed)
		)
		(placement
			(enabled no)
			(sheetname "")
		)
		(fill yes
			(thermal_gap 0.5)
			(thermal_bridge_width 0.5)
			(island_removal_mode 0)
		)
		(polygon
			(pts
				(xy -405.031936 37.684001) (xy -403.888936 37.684001) (xy -403.888936 34.636001) (xy -405.031936 34.636001)
			)
		)
	)
	(zone
		(layers "F.Cu" "B.Cu" "In1.Cu" "In2.Cu" "In4.Cu" "In5.Cu" "In6.Cu")
		(hatch none 0.5)
		(connect_pads
			(clearance 0)
		)
		(min_thickness 0.25)
		(keepout
			(tracks not_allowed)
			(vias allowed)
			(pads allowed)
			(copperpour not_allowed)
			(footprints allowed)
		)
		(placement
			(enabled no)
			(sheetname "")
		)
		(fill yes
			(thermal_gap 0.5)
			(thermal_bridge_width 0.5)
			(island_removal_mode 0)
		)
		(polygon
			(pts
				(xy -399.031938 36.384001) (xy -397.888938 36.384001) (xy -397.888938 33.336001) (xy -399.031938 33.336001)
			)
		)
	)
	(zone
		(layers "F.Cu" "B.Cu" "In1.Cu" "In2.Cu" "In4.Cu" "In5.Cu" "In6.Cu")
		(hatch none 0.5)
		(connect_pads
			(clearance 0)
		)
		(min_thickness 0.25)
		(keepout
			(tracks not_allowed)
			(vias allowed)
			(pads allowed)
			(copperpour not_allowed)
			(footprints allowed)
		)
		(placement
			(enabled no)
			(sheetname "")
		)
		(fill yes
			(thermal_gap 0.5)
			(thermal_bridge_width 0.5)
			(island_removal_mode 0)
		)
		(polygon
			(pts
				(xy -182.031937 36.384001) (xy -180.888937 36.384001) (xy -180.888937 33.336001) (xy -182.031937 33.336001)
			)
		)
	)
	(zone
		(layers "F.Cu" "B.Cu" "In1.Cu" "In2.Cu" "In4.Cu" "In5.Cu" "In6.Cu")
		(hatch none 0.5)
		(connect_pads
			(clearance 0)
		)
		(min_thickness 0.25)
		(keepout
			(tracks not_allowed)
			(vias allowed)
			(pads allowed)
			(copperpour not_allowed)
			(footprints allowed)
		)
		(placement
			(enabled no)
			(sheetname "")
		)
		(fill yes
			(thermal_gap 0.5)
			(thermal_bridge_width 0.5)
			(island_removal_mode 0)
		)
		(polygon
			(pts
				(xy -401.031936 37.684001) (xy -399.888936 37.684001) (xy -399.888936 34.636001) (xy -401.031936 34.636001)
			)
		)
	)
	(zone
		(layers "F.Cu" "B.Cu" "In1.Cu" "In2.Cu" "In4.Cu" "In5.Cu" "In6.Cu")
		(hatch none 0.5)
		(connect_pads
			(clearance 0)
		)
		(min_thickness 0.25)
		(keepout
			(tracks not_allowed)
			(vias allowed)
			(pads allowed)
			(copperpour not_allowed)
			(footprints allowed)
		)
		(placement
			(enabled no)
			(sheetname "")
		)
		(fill yes
			(thermal_gap 0.5)
			(thermal_bridge_width 0.5)
			(island_removal_mode 0)
		)
		(polygon
			(pts
				(xy -174.031938 36.384001) (xy -172.888938 36.384001) (xy -172.888938 33.336001) (xy -174.031938 33.336001)
			)
		)
	)
	(zone
		(layers "F.Cu" "B.Cu" "In1.Cu" "In2.Cu" "In4.Cu" "In5.Cu" "In6.Cu")
		(hatch none 0.5)
		(connect_pads
			(clearance 0)
		)
		(min_thickness 0.25)
		(keepout
			(tracks not_allowed)
			(vias allowed)
			(pads allowed)
			(copperpour not_allowed)
			(footprints allowed)
		)
		(placement
			(enabled no)
			(sheetname "")
		)
		(fill yes
			(thermal_gap 0.5)
			(thermal_bridge_width 0.5)
			(island_removal_mode 0)
		)
		(polygon
			(pts
				(xy -180.031936 37.684001) (xy -178.888936 37.684001) (xy -178.888936 34.636001) (xy -180.031936 34.636001)
			)
		)
	)
	(zone
		(layers "F.Cu" "B.Cu" "In1.Cu" "In2.Cu" "In4.Cu" "In5.Cu" "In6.Cu")
		(hatch none 0.5)
		(connect_pads
			(clearance 0)
		)
		(min_thickness 0.25)
		(keepout
			(tracks not_allowed)
			(vias allowed)
			(pads allowed)
			(copperpour not_allowed)
			(footprints allowed)
		)
		(placement
			(enabled no)
			(sheetname "")
		)
		(fill yes
			(thermal_gap 0.5)
			(thermal_bridge_width 0.5)
			(island_removal_mode 0)
		)
		(polygon
			(pts
				(xy -178.031938 36.384001) (xy -176.888938 36.384001) (xy -176.888938 33.336001) (xy -178.031938 33.336001)
			)
		)
	)
	(zone
		(layers "F.Cu" "B.Cu" "In1.Cu" "In2.Cu" "In4.Cu" "In5.Cu" "In6.Cu")
		(hatch none 0.5)
		(connect_pads
			(clearance 0)
		)
		(min_thickness 0.25)
		(keepout
			(tracks not_allowed)
			(vias allowed)
			(pads allowed)
			(copperpour not_allowed)
			(footprints allowed)
		)
		(placement
			(enabled no)
			(sheetname "")
		)
		(fill yes
			(thermal_gap 0.5)
			(thermal_bridge_width 0.5)
			(island_removal_mode 0)
		)
		(polygon
			(pts
				(xy -397.031936 37.684001) (xy -395.888936 37.684001) (xy -395.888936 34.636001) (xy -397.031936 34.636001)
			)
		)
	)
	(zone
		(layers "F.Cu" "B.Cu" "In1.Cu" "In3.Cu" "In4.Cu" "In5.Cu" "In6.Cu")
		(hatch none 0.5)
		(connect_pads
			(clearance 0)
		)
		(min_thickness 0.25)
		(keepout
			(tracks not_allowed)
			(vias allowed)
			(pads allowed)
			(copperpour not_allowed)
			(footprints allowed)
		)
		(placement
			(enabled no)
			(sheetname "")
		)
		(fill yes
			(thermal_gap 0.5)
			(thermal_bridge_width 0.5)
			(island_removal_mode 0)
		)
		(polygon
			(pts
				(xy -407.031937 40.584003) (xy -405.888937 40.584003) (xy -405.888937 37.536003) (xy -407.031937 37.536003)
			)
		)
	)
	(zone
		(layers "F.Cu" "B.Cu" "In1.Cu" "In3.Cu" "In4.Cu" "In5.Cu" "In6.Cu")
		(hatch none 0.5)
		(connect_pads
			(clearance 0)
		)
		(min_thickness 0.25)
		(keepout
			(tracks not_allowed)
			(vias allowed)
			(pads allowed)
			(copperpour not_allowed)
			(footprints allowed)
		)
		(placement
			(enabled no)
			(sheetname "")
		)
		(fill yes
			(thermal_gap 0.5)
			(thermal_bridge_width 0.5)
			(island_removal_mode 0)
		)
		(polygon
			(pts
				(xy -401.031936 41.884003) (xy -399.888936 41.884003) (xy -399.888936 38.836003) (xy -401.031936 38.836003)
			)
		)
	)
	(zone
		(layers "F.Cu" "B.Cu" "In1.Cu" "In3.Cu" "In4.Cu" "In5.Cu" "In6.Cu")
		(hatch none 0.5)
		(connect_pads
			(clearance 0)
		)
		(min_thickness 0.25)
		(keepout
			(tracks not_allowed)
			(vias allowed)
			(pads allowed)
			(copperpour not_allowed)
			(footprints allowed)
		)
		(placement
			(enabled no)
			(sheetname "")
		)
		(fill yes
			(thermal_gap 0.5)
			(thermal_bridge_width 0.5)
			(island_removal_mode 0)
		)
		(polygon
			(pts
				(xy -409.031935 41.884003) (xy -407.888935 41.884003) (xy -407.888935 38.836003) (xy -409.031935 38.836003)
			)
		)
	)
	(zone
		(layers "F.Cu" "B.Cu" "In1.Cu" "In3.Cu" "In4.Cu" "In5.Cu" "In6.Cu")
		(hatch none 0.5)
		(connect_pads
			(clearance 0)
		)
		(min_thickness 0.25)
		(keepout
			(tracks not_allowed)
			(vias allowed)
			(pads allowed)
			(copperpour not_allowed)
			(footprints allowed)
		)
		(placement
			(enabled no)
			(sheetname "")
		)
		(fill yes
			(thermal_gap 0.5)
			(thermal_bridge_width 0.5)
			(island_removal_mode 0)
		)
		(polygon
			(pts
				(xy -403.031937 40.584003) (xy -401.888937 40.584003) (xy -401.888937 37.536003) (xy -403.031937 37.536003)
			)
		)
	)
	(zone
		(layers "F.Cu" "B.Cu" "In1.Cu" "In3.Cu" "In4.Cu" "In5.Cu" "In6.Cu")
		(hatch none 0.5)
		(connect_pads
			(clearance 0)
		)
		(min_thickness 0.25)
		(keepout
			(tracks not_allowed)
			(vias allowed)
			(pads allowed)
			(copperpour not_allowed)
			(footprints allowed)
		)
		(placement
			(enabled no)
			(sheetname "")
		)
		(fill yes
			(thermal_gap 0.5)
			(thermal_bridge_width 0.5)
			(island_removal_mode 0)
		)
		(polygon
			(pts
				(xy -405.031936 41.884003) (xy -403.888936 41.884003) (xy -403.888936 38.836003) (xy -405.031936 38.836003)
			)
		)
	)
	(zone
		(layers "F.Cu" "B.Cu" "In1.Cu" "In3.Cu" "In4.Cu" "In5.Cu" "In6.Cu")
		(hatch none 0.5)
		(connect_pads
			(clearance 0)
		)
		(min_thickness 0.25)
		(keepout
			(tracks not_allowed)
			(vias allowed)
			(pads allowed)
			(copperpour not_allowed)
			(footprints allowed)
		)
		(placement
			(enabled no)
			(sheetname "")
		)
		(fill yes
			(thermal_gap 0.5)
			(thermal_bridge_width 0.5)
			(island_removal_mode 0)
		)
		(polygon
			(pts
				(xy -395.031938 40.584003) (xy -393.888938 40.584003) (xy -393.888938 37.536003) (xy -395.031938 37.536003)
			)
		)
	)
	(zone
		(layers "F.Cu" "B.Cu" "In1.Cu" "In3.Cu" "In4.Cu" "In5.Cu" "In6.Cu")
		(hatch none 0.5)
		(connect_pads
			(clearance 0)
		)
		(min_thickness 0.25)
		(keepout
			(tracks not_allowed)
			(vias allowed)
			(pads allowed)
			(copperpour not_allowed)
			(footprints allowed)
		)
		(placement
			(enabled no)
			(sheetname "")
		)
		(fill yes
			(thermal_gap 0.5)
			(thermal_bridge_width 0.5)
			(island_removal_mode 0)
		)
		(polygon
			(pts
				(xy -172.031937 41.884003) (xy -170.888937 41.884003) (xy -170.888937 38.836003) (xy -172.031937 38.836003)
			)
		)
	)
	(zone
		(layers "F.Cu" "B.Cu" "In1.Cu" "In3.Cu" "In4.Cu" "In5.Cu" "In6.Cu")
		(hatch none 0.5)
		(connect_pads
			(clearance 0)
		)
		(min_thickness 0.25)
		(keepout
			(tracks not_allowed)
			(vias allowed)
			(pads allowed)
			(copperpour not_allowed)
			(footprints allowed)
		)
		(placement
			(enabled no)
			(sheetname "")
		)
		(fill yes
			(thermal_gap 0.5)
			(thermal_bridge_width 0.5)
			(island_removal_mode 0)
		)
		(polygon
			(pts
				(xy -178.031938 40.584003) (xy -176.888938 40.584003) (xy -176.888938 37.536003) (xy -178.031938 37.536003)
			)
		)
	)
	(zone
		(layers "F.Cu" "B.Cu" "In1.Cu" "In3.Cu" "In4.Cu" "In5.Cu" "In6.Cu")
		(hatch none 0.5)
		(connect_pads
			(clearance 0)
		)
		(min_thickness 0.25)
		(keepout
			(tracks not_allowed)
			(vias allowed)
			(pads allowed)
			(copperpour not_allowed)
			(footprints allowed)
		)
		(placement
			(enabled no)
			(sheetname "")
		)
		(fill yes
			(thermal_gap 0.5)
			(thermal_bridge_width 0.5)
			(island_removal_mode 0)
		)
		(polygon
			(pts
				(xy -188.031935 41.884003) (xy -186.888935 41.884003) (xy -186.888935 38.836003) (xy -188.031935 38.836003)
			)
		)
	)
	(zone
		(layers "F.Cu" "B.Cu" "In1.Cu" "In3.Cu" "In4.Cu" "In5.Cu" "In6.Cu")
		(hatch none 0.5)
		(connect_pads
			(clearance 0)
		)
		(min_thickness 0.25)
		(keepout
			(tracks not_allowed)
			(vias allowed)
			(pads allowed)
			(copperpour not_allowed)
			(footprints allowed)
		)
		(placement
			(enabled no)
			(sheetname "")
		)
		(fill yes
			(thermal_gap 0.5)
			(thermal_bridge_width 0.5)
			(island_removal_mode 0)
		)
		(polygon
			(pts
				(xy -180.031936 41.884003) (xy -178.888936 41.884003) (xy -178.888936 38.836003) (xy -180.031936 38.836003)
			)
		)
	)
	(zone
		(layers "F.Cu" "B.Cu" "In1.Cu" "In3.Cu" "In4.Cu" "In5.Cu" "In6.Cu")
		(hatch none 0.5)
		(connect_pads
			(clearance 0)
		)
		(min_thickness 0.25)
		(keepout
			(tracks not_allowed)
			(vias allowed)
			(pads allowed)
			(copperpour not_allowed)
			(footprints allowed)
		)
		(placement
			(enabled no)
			(sheetname "")
		)
		(fill yes
			(thermal_gap 0.5)
			(thermal_bridge_width 0.5)
			(island_removal_mode 0)
		)
		(polygon
			(pts
				(xy -393.031937 41.884003) (xy -391.888937 41.884003) (xy -391.888937 38.836003) (xy -393.031937 38.836003)
			)
		)
	)
	(zone
		(layers "F.Cu" "B.Cu" "In1.Cu" "In3.Cu" "In4.Cu" "In5.Cu" "In6.Cu")
		(hatch none 0.5)
		(connect_pads
			(clearance 0)
		)
		(min_thickness 0.25)
		(keepout
			(tracks not_allowed)
			(vias allowed)
			(pads allowed)
			(copperpour not_allowed)
			(footprints allowed)
		)
		(placement
			(enabled no)
			(sheetname "")
		)
		(fill yes
			(thermal_gap 0.5)
			(thermal_bridge_width 0.5)
			(island_removal_mode 0)
		)
		(polygon
			(pts
				(xy -397.031936 41.884003) (xy -395.888936 41.884003) (xy -395.888936 38.836003) (xy -397.031936 38.836003)
			)
		)
	)
	(zone
		(layers "F.Cu" "B.Cu" "In1.Cu" "In3.Cu" "In4.Cu" "In5.Cu" "In6.Cu")
		(hatch none 0.5)
		(connect_pads
			(clearance 0)
		)
		(min_thickness 0.25)
		(keepout
			(tracks not_allowed)
			(vias allowed)
			(pads allowed)
			(copperpour not_allowed)
			(footprints allowed)
		)
		(placement
			(enabled no)
			(sheetname "")
		)
		(fill yes
			(thermal_gap 0.5)
			(thermal_bridge_width 0.5)
			(island_removal_mode 0)
		)
		(polygon
			(pts
				(xy -399.031938 40.584003) (xy -397.888938 40.584003) (xy -397.888938 37.536003) (xy -399.031938 37.536003)
			)
		)
	)
	(zone
		(layers "F.Cu" "B.Cu" "In1.Cu" "In3.Cu" "In4.Cu" "In5.Cu" "In6.Cu")
		(hatch none 0.5)
		(connect_pads
			(clearance 0)
		)
		(min_thickness 0.25)
		(keepout
			(tracks not_allowed)
			(vias allowed)
			(pads allowed)
			(copperpour not_allowed)
			(footprints allowed)
		)
		(placement
			(enabled no)
			(sheetname "")
		)
		(fill yes
			(thermal_gap 0.5)
			(thermal_bridge_width 0.5)
			(island_removal_mode 0)
		)
		(polygon
			(pts
				(xy -176.031936 41.884003) (xy -174.888936 41.884003) (xy -174.888936 38.836003) (xy -176.031936 38.836003)
			)
		)
	)
	(zone
		(layers "F.Cu" "B.Cu" "In1.Cu" "In3.Cu" "In4.Cu" "In5.Cu" "In6.Cu")
		(hatch none 0.5)
		(connect_pads
			(clearance 0)
		)
		(min_thickness 0.25)
		(keepout
			(tracks not_allowed)
			(vias allowed)
			(pads allowed)
			(copperpour not_allowed)
			(footprints allowed)
		)
		(placement
			(enabled no)
			(sheetname "")
		)
		(fill yes
			(thermal_gap 0.5)
			(thermal_bridge_width 0.5)
			(island_removal_mode 0)
		)
		(polygon
			(pts
				(xy -182.031937 40.584003) (xy -180.888937 40.584003) (xy -180.888937 37.536003) (xy -182.031937 37.536003)
			)
		)
	)
	(zone
		(layers "F.Cu" "B.Cu" "In1.Cu" "In3.Cu" "In4.Cu" "In5.Cu" "In6.Cu")
		(hatch none 0.5)
		(connect_pads
			(clearance 0)
		)
		(min_thickness 0.25)
		(keepout
			(tracks not_allowed)
			(vias allowed)
			(pads allowed)
			(copperpour not_allowed)
			(footprints allowed)
		)
		(placement
			(enabled no)
			(sheetname "")
		)
		(fill yes
			(thermal_gap 0.5)
			(thermal_bridge_width 0.5)
			(island_removal_mode 0)
		)
		(polygon
			(pts
				(xy -186.031937 40.584003) (xy -184.888937 40.584003) (xy -184.888937 37.536003) (xy -186.031937 37.536003)
			)
		)
	)
	(zone
		(layers "F.Cu" "B.Cu" "In1.Cu" "In3.Cu" "In4.Cu" "In5.Cu" "In6.Cu")
		(hatch none 0.5)
		(connect_pads
			(clearance 0)
		)
		(min_thickness 0.25)
		(keepout
			(tracks not_allowed)
			(vias allowed)
			(pads allowed)
			(copperpour not_allowed)
			(footprints allowed)
		)
		(placement
			(enabled no)
			(sheetname "")
		)
		(fill yes
			(thermal_gap 0.5)
			(thermal_bridge_width 0.5)
			(island_removal_mode 0)
		)
		(polygon
			(pts
				(xy -184.031936 41.884003) (xy -182.888936 41.884003) (xy -182.888936 38.836003) (xy -184.031936 38.836003)
			)
		)
	)
	(zone
		(layers "F.Cu" "B.Cu" "In1.Cu" "In3.Cu" "In4.Cu" "In5.Cu" "In6.Cu")
		(hatch none 0.5)
		(connect_pads
			(clearance 0)
		)
		(min_thickness 0.25)
		(keepout
			(tracks not_allowed)
			(vias allowed)
			(pads allowed)
			(copperpour not_allowed)
			(footprints allowed)
		)
		(placement
			(enabled no)
			(sheetname "")
		)
		(fill yes
			(thermal_gap 0.5)
			(thermal_bridge_width 0.5)
			(island_removal_mode 0)
		)
		(polygon
			(pts
				(xy -174.031938 40.584003) (xy -172.888938 40.584003) (xy -172.888938 37.536003) (xy -174.031938 37.536003)
			)
		)
	)
	(zone
		(layers "F.Cu" "In1.Cu" "In2.Cu" "In3.Cu" "In4.Cu" "In5.Cu" "In6.Cu")
		(hatch none 0.5)
		(connect_pads
			(clearance 0)
		)
		(min_thickness 0.25)
		(keepout
			(tracks not_allowed)
			(vias allowed)
			(pads allowed)
			(copperpour not_allowed)
			(footprints allowed)
		)
		(placement
			(enabled no)
			(sheetname "")
		)
		(fill yes
			(thermal_gap 0.5)
			(thermal_bridge_width 0.5)
			(island_removal_mode 0)
		)
		(polygon
			(pts
				(xy -34.266345 11.673383) (xy -33.903775 11.504313) (xy -33.255135 11.753395) (xy -32.959294 12.387831)
				(xy -33.040434 12.645954) (xy -33.946742 13.068572) (xy -34.19663 12.964813) (xy -34.492474 12.330374)
			)
		)
	)
	(zone
		(layers "F.Cu" "In1.Cu" "In2.Cu" "In3.Cu" "In4.Cu" "In5.Cu" "In6.Cu")
		(hatch none 0.5)
		(connect_pads
			(clearance 0)
		)
		(min_thickness 0.25)
		(keepout
			(tracks not_allowed)
			(vias allowed)
			(pads allowed)
			(copperpour not_allowed)
			(footprints allowed)
		)
		(placement
			(enabled no)
			(sheetname "")
		)
		(fill yes
			(thermal_gap 0.5)
			(thermal_bridge_width 0.5)
			(island_removal_mode 0)
		)
		(polygon
			(pts
				(xy -253.665203 17.964559) (xy -254.023873 18.141749) (xy -254.677954 17.90733) (xy -254.988004 17.279714)
				(xy -254.912693 17.019831) (xy -254.016132 16.576919) (xy -253.763971 16.675024) (xy -253.453923 17.30264)
			)
		)
	)
	(zone
		(layers "F.Cu" "In1.Cu" "In2.Cu" "In3.Cu" "In4.Cu" "In5.Cu" "In6.Cu")
		(hatch none 0.5)
		(connect_pads
			(clearance 0)
		)
		(min_thickness 0.25)
		(keepout
			(tracks not_allowed)
			(vias allowed)
			(pads allowed)
			(copperpour not_allowed)
			(footprints allowed)
		)
		(placement
			(enabled no)
			(sheetname "")
		)
		(fill yes
			(thermal_gap 0.5)
			(thermal_bridge_width 0.5)
			(island_removal_mode 0)
		)
		(polygon
			(pts
				(xy -35.251499 41.984003) (xy -34.108499 41.984003) (xy -34.108499 38.936003) (xy -35.251499 38.936003)
			)
		)
	)
	(zone
		(layers "F.Cu" "In1.Cu" "In2.Cu" "In3.Cu" "In4.Cu" "In5.Cu" "In6.Cu")
		(hatch none 0.5)
		(connect_pads
			(clearance 0)
		)
		(min_thickness 0.25)
		(keepout
			(tracks not_allowed)
			(vias allowed)
			(pads allowed)
			(copperpour not_allowed)
			(footprints allowed)
		)
		(placement
			(enabled no)
			(sheetname "")
		)
		(fill yes
			(thermal_gap 0.5)
			(thermal_bridge_width 0.5)
			(island_removal_mode 0)
		)
		(polygon
			(pts
				(xy -34.266345 15.473383) (xy -33.903775 15.304313) (xy -33.255135 15.553395) (xy -32.959294 16.187831)
				(xy -33.040434 16.445954) (xy -33.946742 16.868572) (xy -34.19663 16.764813) (xy -34.492474 16.130374)
			)
		)
	)
	(zone
		(layers "F.Cu" "In1.Cu" "In2.Cu" "In3.Cu" "In4.Cu" "In5.Cu" "In6.Cu")
		(hatch none 0.5)
		(connect_pads
			(clearance 0)
		)
		(min_thickness 0.25)
		(keepout
			(tracks not_allowed)
			(vias allowed)
			(pads allowed)
			(copperpour not_allowed)
			(footprints allowed)
		)
		(placement
			(enabled no)
			(sheetname "")
		)
		(fill yes
			(thermal_gap 0.5)
			(thermal_bridge_width 0.5)
			(island_removal_mode 0)
		)
		(polygon
			(pts
				(xy -302.611937 46.184012) (xy -301.468937 46.184012) (xy -301.468937 43.136012) (xy -302.611937 43.136012)
			)
		)
	)
	(zone
		(layers "F.Cu" "In1.Cu" "In2.Cu" "In3.Cu" "In4.Cu" "In5.Cu" "In6.Cu")
		(hatch none 0.5)
		(connect_pads
			(clearance 0)
		)
		(min_thickness 0.25)
		(keepout
			(tracks not_allowed)
			(vias allowed)
			(pads allowed)
			(copperpour not_allowed)
			(footprints allowed)
		)
		(placement
			(enabled no)
			(sheetname "")
		)
		(fill yes
			(thermal_gap 0.5)
			(thermal_bridge_width 0.5)
			(island_removal_mode 0)
		)
		(polygon
			(pts
				(xy -81.611937 46.184012) (xy -80.468937 46.184012) (xy -80.468937 43.136012) (xy -81.611937 43.136012)
			)
		)
	)
	(zone
		(layers "F.Cu" "In1.Cu" "In2.Cu" "In3.Cu" "In4.Cu" "In5.Cu" "In6.Cu")
		(hatch none 0.5)
		(connect_pads
			(clearance 0)
		)
		(min_thickness 0.25)
		(keepout
			(tracks not_allowed)
			(vias allowed)
			(pads allowed)
			(copperpour not_allowed)
			(footprints allowed)
		)
		(placement
			(enabled no)
			(sheetname "")
		)
		(fill yes
			(thermal_gap 0.5)
			(thermal_bridge_width 0.5)
			(island_removal_mode 0)
		)
		(polygon
			(pts
				(xy -34.266345 19.273383) (xy -33.903775 19.104313) (xy -33.255135 19.353395) (xy -32.959294 19.987832)
				(xy -33.040434 20.245954) (xy -33.946742 20.668572) (xy -34.19663 20.564813) (xy -34.492474 19.930374)
			)
		)
	)
	(zone
		(layers "F.Cu" "In1.Cu" "In2.Cu" "In3.Cu" "In4.Cu" "In5.Cu" "In6.Cu")
		(hatch none 0.5)
		(connect_pads
			(clearance 0)
		)
		(min_thickness 0.25)
		(keepout
			(tracks not_allowed)
			(vias allowed)
			(pads allowed)
			(copperpour not_allowed)
			(footprints allowed)
		)
		(placement
			(enabled no)
			(sheetname "")
		)
		(fill yes
			(thermal_gap 0.5)
			(thermal_bridge_width 0.5)
			(island_removal_mode 0)
		)
		(polygon
			(pts
				(xy -31.2515 41.984003) (xy -30.1085 41.984003) (xy -30.1085 38.936003) (xy -31.2515 38.936003)
			)
		)
	)
	(zone
		(layers "F.Cu" "In1.Cu" "In2.Cu" "In3.Cu" "In4.Cu" "In5.Cu" "In6.Cu")
		(hatch none 0.5)
		(connect_pads
			(clearance 0)
		)
		(min_thickness 0.25)
		(keepout
			(tracks not_allowed)
			(vias allowed)
			(pads allowed)
			(copperpour not_allowed)
			(footprints allowed)
		)
		(placement
			(enabled no)
			(sheetname "")
		)
		(fill yes
			(thermal_gap 0.5)
			(thermal_bridge_width 0.5)
			(island_removal_mode 0)
		)
		(polygon
			(pts
				(xy -172.031937 33.484) (xy -170.888937 33.484) (xy -170.888937 30.436) (xy -172.031937 30.436)
			)
		)
	)
	(zone
		(layers "F.Cu" "In1.Cu" "In2.Cu" "In3.Cu" "In4.Cu" "In5.Cu" "In6.Cu")
		(hatch none 0.5)
		(connect_pads
			(clearance 0)
		)
		(min_thickness 0.25)
		(keepout
			(tracks not_allowed)
			(vias allowed)
			(pads allowed)
			(copperpour not_allowed)
			(footprints allowed)
		)
		(placement
			(enabled no)
			(sheetname "")
		)
		(fill yes
			(thermal_gap 0.5)
			(thermal_bridge_width 0.5)
			(island_removal_mode 0)
		)
		(polygon
			(pts
				(xy -294.611938 41.984011) (xy -293.468938 41.984011) (xy -293.468938 38.936011) (xy -294.611938 38.936011)
			)
		)
	)
	(zone
		(layers "F.Cu" "In1.Cu" "In2.Cu" "In3.Cu" "In4.Cu" "In5.Cu" "In6.Cu")
		(hatch none 0.5)
		(connect_pads
			(clearance 0)
		)
		(min_thickness 0.25)
		(keepout
			(tracks not_allowed)
			(vias allowed)
			(pads allowed)
			(copperpour not_allowed)
			(footprints allowed)
		)
		(placement
			(enabled no)
			(sheetname "")
		)
		(fill yes
			(thermal_gap 0.5)
			(thermal_bridge_width 0.5)
			(island_removal_mode 0)
		)
		(polygon
			(pts
				(xy -255.266345 15.473383) (xy -254.903775 15.304313) (xy -254.255135 15.553395) (xy -253.959294 16.187831)
				(xy -254.040434 16.445954) (xy -254.946742 16.868572) (xy -255.19663 16.764813) (xy -255.492474 16.130374)
			)
		)
	)
	(zone
		(layers "F.Cu" "In1.Cu" "In2.Cu" "In3.Cu" "In4.Cu" "In5.Cu" "In6.Cu")
		(hatch none 0.5)
		(connect_pads
			(clearance 0)
		)
		(min_thickness 0.25)
		(keepout
			(tracks not_allowed)
			(vias allowed)
			(pads allowed)
			(copperpour not_allowed)
			(footprints allowed)
		)
		(placement
			(enabled no)
			(sheetname "")
		)
		(fill yes
			(thermal_gap 0.5)
			(thermal_bridge_width 0.5)
			(island_removal_mode 0)
		)
		(polygon
			(pts
				(xy -23.266344 19.273383) (xy -22.903774 19.104313) (xy -22.255135 19.353395) (xy -21.959293 19.987832)
				(xy -22.040433 20.245954) (xy -22.946741 20.668572) (xy -23.196629 20.564813) (xy -23.492473 19.930374)
			)
		)
	)
	(zone
		(layers "F.Cu" "In1.Cu" "In2.Cu" "In3.Cu" "In4.Cu" "In5.Cu" "In6.Cu")
		(hatch none 0.5)
		(connect_pads
			(clearance 0)
		)
		(min_thickness 0.25)
		(keepout
			(tracks not_allowed)
			(vias allowed)
			(pads allowed)
			(copperpour not_allowed)
			(footprints allowed)
		)
		(placement
			(enabled no)
			(sheetname "")
		)
		(fill yes
			(thermal_gap 0.5)
			(thermal_bridge_width 0.5)
			(island_removal_mode 0)
		)
		(polygon
			(pts
				(xy -21.665202 21.764559) (xy -22.023873 21.941749) (xy -22.677953 21.70733) (xy -22.988003 21.079714)
				(xy -22.912692 20.819831) (xy -22.016131 20.376919) (xy -21.76397 20.475024) (xy -21.453922 21.10264)
			)
		)
	)
	(zone
		(layers "F.Cu" "In1.Cu" "In2.Cu" "In3.Cu" "In4.Cu" "In5.Cu" "In6.Cu")
		(hatch none 0.5)
		(connect_pads
			(clearance 0)
		)
		(min_thickness 0.25)
		(keepout
			(tracks not_allowed)
			(vias allowed)
			(pads allowed)
			(copperpour not_allowed)
			(footprints allowed)
		)
		(placement
			(enabled no)
			(sheetname "")
		)
		(fill yes
			(thermal_gap 0.5)
			(thermal_bridge_width 0.5)
			(island_removal_mode 0)
		)
		(polygon
			(pts
				(xy -255.266345 19.273383) (xy -254.903775 19.104313) (xy -254.255135 19.353395) (xy -253.959294 19.987832)
				(xy -254.040434 20.245954) (xy -254.946742 20.668572) (xy -255.19663 20.564813) (xy -255.492474 19.930374)
			)
		)
	)
	(zone
		(layers "F.Cu" "In1.Cu" "In2.Cu" "In3.Cu" "In4.Cu" "In5.Cu" "In6.Cu")
		(hatch none 0.5)
		(connect_pads
			(clearance 0)
		)
		(min_thickness 0.25)
		(keepout
			(tracks not_allowed)
			(vias allowed)
			(pads allowed)
			(copperpour not_allowed)
			(footprints allowed)
		)
		(placement
			(enabled no)
			(sheetname "")
		)
		(fill yes
			(thermal_gap 0.5)
			(thermal_bridge_width 0.5)
			(island_removal_mode 0)
		)
		(polygon
			(pts
				(xy -73.611938 41.984011) (xy -72.468938 41.984011) (xy -72.468938 38.936011) (xy -73.611938 38.936011)
			)
		)
	)
	(zone
		(layers "F.Cu" "In1.Cu" "In2.Cu" "In3.Cu" "In4.Cu" "In5.Cu" "In6.Cu")
		(hatch none 0.5)
		(connect_pads
			(clearance 0)
		)
		(min_thickness 0.25)
		(keepout
			(tracks not_allowed)
			(vias allowed)
			(pads allowed)
			(copperpour not_allowed)
			(footprints allowed)
		)
		(placement
			(enabled no)
			(sheetname "")
		)
		(fill yes
			(thermal_gap 0.5)
			(thermal_bridge_width 0.5)
			(island_removal_mode 0)
		)
		(polygon
			(pts
				(xy -411.031936 44.784005) (xy -409.888936 44.784005) (xy -409.888936 41.736005) (xy -411.031936 41.736005)
			)
		)
	)
	(zone
		(layers "F.Cu" "In1.Cu" "In2.Cu" "In3.Cu" "In4.Cu" "In5.Cu" "In6.Cu")
		(hatch none 0.5)
		(connect_pads
			(clearance 0)
		)
		(min_thickness 0.25)
		(keepout
			(tracks not_allowed)
			(vias allowed)
			(pads allowed)
			(copperpour not_allowed)
			(footprints allowed)
		)
		(placement
			(enabled no)
			(sheetname "")
		)
		(fill yes
			(thermal_gap 0.5)
			(thermal_bridge_width 0.5)
			(island_removal_mode 0)
		)
		(polygon
			(pts
				(xy -246.516345 11.673383) (xy -246.153775 11.504313) (xy -245.505135 11.753395) (xy -245.209294 12.387831)
				(xy -245.290434 12.645954) (xy -246.196742 13.068572) (xy -246.446629 12.964813) (xy -246.742473 12.330374)
			)
		)
	)
	(zone
		(layers "F.Cu" "In1.Cu" "In2.Cu" "In3.Cu" "In4.Cu" "In5.Cu" "In6.Cu")
		(hatch none 0.5)
		(connect_pads
			(clearance 0)
		)
		(min_thickness 0.25)
		(keepout
			(tracks not_allowed)
			(vias allowed)
			(pads allowed)
			(copperpour not_allowed)
			(footprints allowed)
		)
		(placement
			(enabled no)
			(sheetname "")
		)
		(fill yes
			(thermal_gap 0.5)
			(thermal_bridge_width 0.5)
			(island_removal_mode 0)
		)
		(polygon
			(pts
				(xy -401.031936 33.484) (xy -399.888936 33.484) (xy -399.888936 30.436) (xy -401.031936 30.436)
			)
		)
	)
	(zone
		(layers "F.Cu" "In1.Cu" "In2.Cu" "In3.Cu" "In4.Cu" "In5.Cu" "In6.Cu")
		(hatch none 0.5)
		(connect_pads
			(clearance 0)
		)
		(min_thickness 0.25)
		(keepout
			(tracks not_allowed)
			(vias allowed)
			(pads allowed)
			(copperpour not_allowed)
			(footprints allowed)
		)
		(placement
			(enabled no)
			(sheetname "")
		)
		(fill yes
			(thermal_gap 0.5)
			(thermal_bridge_width 0.5)
			(island_removal_mode 0)
		)
		(polygon
			(pts
				(xy -256.251499 46.184005) (xy -255.108499 46.184005) (xy -255.108499 43.136005) (xy -256.251499 43.136005)
			)
		)
	)
	(zone
		(layers "F.Cu" "In1.Cu" "In2.Cu" "In3.Cu" "In4.Cu" "In5.Cu" "In6.Cu")
		(hatch none 0.5)
		(connect_pads
			(clearance 0)
		)
		(min_thickness 0.25)
		(keepout
			(tracks not_allowed)
			(vias allowed)
			(pads allowed)
			(copperpour not_allowed)
			(footprints allowed)
		)
		(placement
			(enabled no)
			(sheetname "")
		)
		(fill yes
			(thermal_gap 0.5)
			(thermal_bridge_width 0.5)
			(island_removal_mode 0)
		)
		(polygon
			(pts
				(xy -252.2515 41.984003) (xy -251.1085 41.984003) (xy -251.1085 38.936003) (xy -252.2515 38.936003)
			)
		)
	)
	(zone
		(layers "F.Cu" "In1.Cu" "In2.Cu" "In3.Cu" "In4.Cu" "In5.Cu" "In6.Cu")
		(hatch none 0.5)
		(connect_pads
			(clearance 0)
		)
		(min_thickness 0.25)
		(keepout
			(tracks not_allowed)
			(vias allowed)
			(pads allowed)
			(copperpour not_allowed)
			(footprints allowed)
		)
		(placement
			(enabled no)
			(sheetname "")
		)
		(fill yes
			(thermal_gap 0.5)
			(thermal_bridge_width 0.5)
			(island_removal_mode 0)
		)
		(polygon
			(pts
				(xy -294.611938 37.784009) (xy -293.468938 37.784009) (xy -293.468938 34.736009) (xy -294.611938 34.736009)
			)
		)
	)
	(zone
		(layers "F.Cu" "In1.Cu" "In2.Cu" "In3.Cu" "In4.Cu" "In5.Cu" "In6.Cu")
		(hatch none 0.5)
		(connect_pads
			(clearance 0)
		)
		(min_thickness 0.25)
		(keepout
			(tracks not_allowed)
			(vias allowed)
			(pads allowed)
			(copperpour not_allowed)
			(footprints allowed)
		)
		(placement
			(enabled no)
			(sheetname "")
		)
		(fill yes
			(thermal_gap 0.5)
			(thermal_bridge_width 0.5)
			(island_removal_mode 0)
		)
		(polygon
			(pts
				(xy -407.031937 32.184) (xy -405.888937 32.184) (xy -405.888937 29.136) (xy -407.031937 29.136)
			)
		)
	)
	(zone
		(layers "F.Cu" "In1.Cu" "In2.Cu" "In3.Cu" "In4.Cu" "In5.Cu" "In6.Cu")
		(hatch none 0.5)
		(connect_pads
			(clearance 0)
		)
		(min_thickness 0.25)
		(keepout
			(tracks not_allowed)
			(vias allowed)
			(pads allowed)
			(copperpour not_allowed)
			(footprints allowed)
		)
		(placement
			(enabled no)
			(sheetname "")
		)
		(fill yes
			(thermal_gap 0.5)
			(thermal_bridge_width 0.5)
			(island_removal_mode 0)
		)
		(polygon
			(pts
				(xy -244.266344 19.273383) (xy -243.903774 19.104313) (xy -243.255135 19.353395) (xy -242.959293 19.987832)
				(xy -243.040433 20.245954) (xy -243.946741 20.668572) (xy -244.196629 20.564813) (xy -244.492473 19.930374)
			)
		)
	)
	(zone
		(layers "F.Cu" "In1.Cu" "In2.Cu" "In3.Cu" "In4.Cu" "In5.Cu" "In6.Cu")
		(hatch none 0.5)
		(connect_pads
			(clearance 0)
		)
		(min_thickness 0.25)
		(keepout
			(tracks not_allowed)
			(vias allowed)
			(pads allowed)
			(copperpour not_allowed)
			(footprints allowed)
		)
		(placement
			(enabled no)
			(sheetname "")
		)
		(fill yes
			(thermal_gap 0.5)
			(thermal_bridge_width 0.5)
			(island_removal_mode 0)
		)
		(polygon
			(pts
				(xy -180.031936 33.484) (xy -178.888936 33.484) (xy -178.888936 30.436) (xy -180.031936 30.436)
			)
		)
	)
	(zone
		(layers "F.Cu" "In1.Cu" "In2.Cu" "In3.Cu" "In4.Cu" "In5.Cu" "In6.Cu")
		(hatch none 0.5)
		(connect_pads
			(clearance 0)
		)
		(min_thickness 0.25)
		(keepout
			(tracks not_allowed)
			(vias allowed)
			(pads allowed)
			(copperpour not_allowed)
			(footprints allowed)
		)
		(placement
			(enabled no)
			(sheetname "")
		)
		(fill yes
			(thermal_gap 0.5)
			(thermal_bridge_width 0.5)
			(island_removal_mode 0)
		)
		(polygon
			(pts
				(xy -184.031936 33.484) (xy -182.888936 33.484) (xy -182.888936 30.436) (xy -184.031936 30.436)
			)
		)
	)
	(zone
		(layers "F.Cu" "In1.Cu" "In2.Cu" "In3.Cu" "In4.Cu" "In5.Cu" "In6.Cu")
		(hatch none 0.5)
		(connect_pads
			(clearance 0)
		)
		(min_thickness 0.25)
		(keepout
			(tracks not_allowed)
			(vias allowed)
			(pads allowed)
			(copperpour not_allowed)
			(footprints allowed)
		)
		(placement
			(enabled no)
			(sheetname "")
		)
		(fill yes
			(thermal_gap 0.5)
			(thermal_bridge_width 0.5)
			(island_removal_mode 0)
		)
		(polygon
			(pts
				(xy -27.2515 37.784001) (xy -26.1085 37.784001) (xy -26.1085 34.736001) (xy -27.2515 34.736001)
			)
		)
	)
	(zone
		(layers "F.Cu" "In1.Cu" "In2.Cu" "In3.Cu" "In4.Cu" "In5.Cu" "In6.Cu")
		(hatch none 0.5)
		(connect_pads
			(clearance 0)
		)
		(min_thickness 0.25)
		(keepout
			(tracks not_allowed)
			(vias allowed)
			(pads allowed)
			(copperpour not_allowed)
			(footprints allowed)
		)
		(placement
			(enabled no)
			(sheetname "")
		)
		(fill yes
			(thermal_gap 0.5)
			(thermal_bridge_width 0.5)
			(island_removal_mode 0)
		)
		(polygon
			(pts
				(xy -393.031937 33.484) (xy -391.888937 33.484) (xy -391.888937 30.436) (xy -393.031937 30.436)
			)
		)
	)
	(zone
		(layers "F.Cu" "In1.Cu" "In2.Cu" "In3.Cu" "In4.Cu" "In5.Cu" "In6.Cu")
		(hatch none 0.5)
		(connect_pads
			(clearance 0)
		)
		(min_thickness 0.25)
		(keepout
			(tracks not_allowed)
			(vias allowed)
			(pads allowed)
			(copperpour not_allowed)
			(footprints allowed)
		)
		(placement
			(enabled no)
			(sheetname "")
		)
		(fill yes
			(thermal_gap 0.5)
			(thermal_bridge_width 0.5)
			(island_removal_mode 0)
		)
		(polygon
			(pts
				(xy -35.251499 46.184005) (xy -34.108499 46.184005) (xy -34.108499 43.136005) (xy -35.251499 43.136005)
			)
		)
	)
	(zone
		(layers "F.Cu" "In1.Cu" "In2.Cu" "In3.Cu" "In4.Cu" "In5.Cu" "In6.Cu")
		(hatch none 0.5)
		(connect_pads
			(clearance 0)
		)
		(min_thickness 0.25)
		(keepout
			(tracks not_allowed)
			(vias allowed)
			(pads allowed)
			(copperpour not_allowed)
			(footprints allowed)
		)
		(placement
			(enabled no)
			(sheetname "")
		)
		(fill yes
			(thermal_gap 0.5)
			(thermal_bridge_width 0.5)
			(island_removal_mode 0)
		)
		(polygon
			(pts
				(xy -244.266344 11.673383) (xy -243.903774 11.504313) (xy -243.255135 11.753395) (xy -242.959293 12.387831)
				(xy -243.040433 12.645954) (xy -243.946741 13.068572) (xy -244.196629 12.964813) (xy -244.492473 12.330374)
			)
		)
	)
	(zone
		(layers "F.Cu" "In1.Cu" "In2.Cu" "In3.Cu" "In4.Cu" "In5.Cu" "In6.Cu")
		(hatch none 0.5)
		(connect_pads
			(clearance 0)
		)
		(min_thickness 0.25)
		(keepout
			(tracks not_allowed)
			(vias allowed)
			(pads allowed)
			(copperpour not_allowed)
			(footprints allowed)
		)
		(placement
			(enabled no)
			(sheetname "")
		)
		(fill yes
			(thermal_gap 0.5)
			(thermal_bridge_width 0.5)
			(island_removal_mode 0)
		)
		(polygon
			(pts
				(xy -255.266345 11.673383) (xy -254.903775 11.504313) (xy -254.255135 11.753395) (xy -253.959294 12.387831)
				(xy -254.040434 12.645954) (xy -254.946742 13.068572) (xy -255.19663 12.964813) (xy -255.492474 12.330374)
			)
		)
	)
	(zone
		(layers "F.Cu" "In1.Cu" "In2.Cu" "In3.Cu" "In4.Cu" "In5.Cu" "In6.Cu")
		(hatch none 0.5)
		(connect_pads
			(clearance 0)
		)
		(min_thickness 0.25)
		(keepout
			(tracks not_allowed)
			(vias allowed)
			(pads allowed)
			(copperpour not_allowed)
			(footprints allowed)
		)
		(placement
			(enabled no)
			(sheetname "")
		)
		(fill yes
			(thermal_gap 0.5)
			(thermal_bridge_width 0.5)
			(island_removal_mode 0)
		)
		(polygon
			(pts
				(xy -298.611938 46.184012) (xy -297.468938 46.184012) (xy -297.468938 43.136012) (xy -298.611938 43.136012)
			)
		)
	)
	(zone
		(layers "F.Cu" "In1.Cu" "In2.Cu" "In3.Cu" "In4.Cu" "In5.Cu" "In6.Cu")
		(hatch none 0.5)
		(connect_pads
			(clearance 0)
		)
		(min_thickness 0.25)
		(keepout
			(tracks not_allowed)
			(vias allowed)
			(pads allowed)
			(copperpour not_allowed)
			(footprints allowed)
		)
		(placement
			(enabled no)
			(sheetname "")
		)
		(fill yes
			(thermal_gap 0.5)
			(thermal_bridge_width 0.5)
			(island_removal_mode 0)
		)
		(polygon
			(pts
				(xy -399.031938 32.184) (xy -397.888938 32.184) (xy -397.888938 29.136) (xy -399.031938 29.136)
			)
		)
	)
	(zone
		(layers "F.Cu" "In1.Cu" "In2.Cu" "In3.Cu" "In4.Cu" "In5.Cu" "In6.Cu")
		(hatch none 0.5)
		(connect_pads
			(clearance 0)
		)
		(min_thickness 0.25)
		(keepout
			(tracks not_allowed)
			(vias allowed)
			(pads allowed)
			(copperpour not_allowed)
			(footprints allowed)
		)
		(placement
			(enabled no)
			(sheetname "")
		)
		(fill yes
			(thermal_gap 0.5)
			(thermal_bridge_width 0.5)
			(island_removal_mode 0)
		)
		(polygon
			(pts
				(xy -176.031936 33.484) (xy -174.888936 33.484) (xy -174.888936 30.436) (xy -176.031936 30.436)
			)
		)
	)
	(zone
		(layers "F.Cu" "In1.Cu" "In2.Cu" "In3.Cu" "In4.Cu" "In5.Cu" "In6.Cu")
		(hatch none 0.5)
		(connect_pads
			(clearance 0)
		)
		(min_thickness 0.25)
		(keepout
			(tracks not_allowed)
			(vias allowed)
			(pads allowed)
			(copperpour not_allowed)
			(footprints allowed)
		)
		(placement
			(enabled no)
			(sheetname "")
		)
		(fill yes
			(thermal_gap 0.5)
			(thermal_bridge_width 0.5)
			(island_removal_mode 0)
		)
		(polygon
			(pts
				(xy -409.031935 37.684001) (xy -407.888935 37.684001) (xy -407.888935 34.636001) (xy -409.031935 34.636001)
			)
		)
	)
	(zone
		(layers "F.Cu" "In1.Cu" "In2.Cu" "In3.Cu" "In4.Cu" "In5.Cu" "In6.Cu")
		(hatch none 0.5)
		(connect_pads
			(clearance 0)
		)
		(min_thickness 0.25)
		(keepout
			(tracks not_allowed)
			(vias allowed)
			(pads allowed)
			(copperpour not_allowed)
			(footprints allowed)
		)
		(placement
			(enabled no)
			(sheetname "")
		)
		(fill yes
			(thermal_gap 0.5)
			(thermal_bridge_width 0.5)
			(island_removal_mode 0)
		)
		(polygon
			(pts
				(xy -83.611938 44.884012) (xy -82.468938 44.884012) (xy -82.468938 41.836012) (xy -83.611938 41.836012)
			)
		)
	)
	(zone
		(layers "F.Cu" "In1.Cu" "In2.Cu" "In3.Cu" "In4.Cu" "In5.Cu" "In6.Cu")
		(hatch none 0.5)
		(connect_pads
			(clearance 0)
		)
		(min_thickness 0.25)
		(keepout
			(tracks not_allowed)
			(vias allowed)
			(pads allowed)
			(copperpour not_allowed)
			(footprints allowed)
		)
		(placement
			(enabled no)
			(sheetname "")
		)
		(fill yes
			(thermal_gap 0.5)
			(thermal_bridge_width 0.5)
			(island_removal_mode 0)
		)
		(polygon
			(pts
				(xy -190.031936 44.784005) (xy -188.888936 44.784005) (xy -188.888936 41.736005) (xy -190.031936 41.736005)
			)
		)
	)
	(zone
		(layers "F.Cu" "In1.Cu" "In2.Cu" "In3.Cu" "In4.Cu" "In5.Cu" "In6.Cu")
		(hatch none 0.5)
		(connect_pads
			(clearance 0)
		)
		(min_thickness 0.25)
		(keepout
			(tracks not_allowed)
			(vias allowed)
			(pads allowed)
			(copperpour not_allowed)
			(footprints allowed)
		)
		(placement
			(enabled no)
			(sheetname "")
		)
		(fill yes
			(thermal_gap 0.5)
			(thermal_bridge_width 0.5)
			(island_removal_mode 0)
		)
		(polygon
			(pts
				(xy -186.031937 32.184) (xy -184.888937 32.184) (xy -184.888937 29.136) (xy -186.031937 29.136)
			)
		)
	)
	(zone
		(layers "F.Cu" "In1.Cu" "In2.Cu" "In3.Cu" "In4.Cu" "In5.Cu" "In6.Cu")
		(hatch none 0.5)
		(connect_pads
			(clearance 0)
		)
		(min_thickness 0.25)
		(keepout
			(tracks not_allowed)
			(vias allowed)
			(pads allowed)
			(copperpour not_allowed)
			(footprints allowed)
		)
		(placement
			(enabled no)
			(sheetname "")
		)
		(fill yes
			(thermal_gap 0.5)
			(thermal_bridge_width 0.5)
			(island_removal_mode 0)
		)
		(polygon
			(pts
				(xy -242.665202 21.764559) (xy -243.023873 21.941749) (xy -243.677953 21.70733) (xy -243.988003 21.079714)
				(xy -243.912692 20.819831) (xy -243.016131 20.376919) (xy -242.76397 20.475024) (xy -242.453922 21.10264)
			)
		)
	)
	(zone
		(layers "F.Cu" "In1.Cu" "In2.Cu" "In3.Cu" "In4.Cu" "In5.Cu" "In6.Cu")
		(hatch none 0.5)
		(connect_pads
			(clearance 0)
		)
		(min_thickness 0.25)
		(keepout
			(tracks not_allowed)
			(vias allowed)
			(pads allowed)
			(copperpour not_allowed)
			(footprints allowed)
		)
		(placement
			(enabled no)
			(sheetname "")
		)
		(fill yes
			(thermal_gap 0.5)
			(thermal_bridge_width 0.5)
			(island_removal_mode 0)
		)
		(polygon
			(pts
				(xy -21.665202 14.164559) (xy -22.023873 14.341749) (xy -22.677953 14.10733) (xy -22.988003 13.479714)
				(xy -22.912692 13.219831) (xy -22.016131 12.776919) (xy -21.76397 12.875024) (xy -21.453922 13.50264)
			)
		)
	)
	(zone
		(layers "F.Cu" "In1.Cu" "In2.Cu" "In3.Cu" "In4.Cu" "In5.Cu" "In6.Cu")
		(hatch none 0.5)
		(connect_pads
			(clearance 0)
		)
		(min_thickness 0.25)
		(keepout
			(tracks not_allowed)
			(vias allowed)
			(pads allowed)
			(copperpour not_allowed)
			(footprints allowed)
		)
		(placement
			(enabled no)
			(sheetname "")
		)
		(fill yes
			(thermal_gap 0.5)
			(thermal_bridge_width 0.5)
			(island_removal_mode 0)
		)
		(polygon
			(pts
				(xy -83.611938 40.683998) (xy -82.468938 40.683998) (xy -82.468938 37.635998) (xy -83.611938 37.635998)
			)
		)
	)
	(zone
		(layers "F.Cu" "In1.Cu" "In2.Cu" "In3.Cu" "In4.Cu" "In5.Cu" "In6.Cu")
		(hatch none 0.5)
		(connect_pads
			(clearance 0)
		)
		(min_thickness 0.25)
		(keepout
			(tracks not_allowed)
			(vias allowed)
			(pads allowed)
			(copperpour not_allowed)
			(footprints allowed)
		)
		(placement
			(enabled no)
			(sheetname "")
		)
		(fill yes
			(thermal_gap 0.5)
			(thermal_bridge_width 0.5)
			(island_removal_mode 0)
		)
		(polygon
			(pts
				(xy -23.266344 11.673383) (xy -22.903774 11.504313) (xy -22.255135 11.753395) (xy -21.959293 12.387831)
				(xy -22.040433 12.645954) (xy -22.946741 13.068572) (xy -23.196629 12.964813) (xy -23.492473 12.330374)
			)
		)
	)
	(zone
		(layers "F.Cu" "In1.Cu" "In2.Cu" "In3.Cu" "In4.Cu" "In5.Cu" "In6.Cu")
		(hatch none 0.5)
		(connect_pads
			(clearance 0)
		)
		(min_thickness 0.25)
		(keepout
			(tracks not_allowed)
			(vias allowed)
			(pads allowed)
			(copperpour not_allowed)
			(footprints allowed)
		)
		(placement
			(enabled no)
			(sheetname "")
		)
		(fill yes
			(thermal_gap 0.5)
			(thermal_bridge_width 0.5)
			(island_removal_mode 0)
		)
		(polygon
			(pts
				(xy -304.611938 44.884012) (xy -303.468938 44.884012) (xy -303.468938 41.836012) (xy -304.611938 41.836012)
			)
		)
	)
	(zone
		(layers "F.Cu" "In1.Cu" "In2.Cu" "In3.Cu" "In4.Cu" "In5.Cu" "In6.Cu")
		(hatch none 0.5)
		(connect_pads
			(clearance 0)
		)
		(min_thickness 0.25)
		(keepout
			(tracks not_allowed)
			(vias allowed)
			(pads allowed)
			(copperpour not_allowed)
			(footprints allowed)
		)
		(placement
			(enabled no)
			(sheetname "")
		)
		(fill yes
			(thermal_gap 0.5)
			(thermal_bridge_width 0.5)
			(island_removal_mode 0)
		)
		(polygon
			(pts
				(xy -25.516345 11.673383) (xy -25.153775 11.504313) (xy -24.505135 11.753395) (xy -24.209294 12.387831)
				(xy -24.290434 12.645954) (xy -25.196742 13.068572) (xy -25.446629 12.964813) (xy -25.742473 12.330374)
			)
		)
	)
	(zone
		(layers "F.Cu" "In1.Cu" "In2.Cu" "In3.Cu" "In4.Cu" "In5.Cu" "In6.Cu")
		(hatch none 0.5)
		(connect_pads
			(clearance 0)
		)
		(min_thickness 0.25)
		(keepout
			(tracks not_allowed)
			(vias allowed)
			(pads allowed)
			(copperpour not_allowed)
			(footprints allowed)
		)
		(placement
			(enabled no)
			(sheetname "")
		)
		(fill yes
			(thermal_gap 0.5)
			(thermal_bridge_width 0.5)
			(island_removal_mode 0)
		)
		(polygon
			(pts
				(xy -188.031935 37.684001) (xy -186.888935 37.684001) (xy -186.888935 34.636001) (xy -188.031935 34.636001)
			)
		)
	)
	(zone
		(layers "F.Cu" "In1.Cu" "In2.Cu" "In3.Cu" "In4.Cu" "In5.Cu" "In6.Cu")
		(hatch none 0.5)
		(connect_pads
			(clearance 0)
		)
		(min_thickness 0.25)
		(keepout
			(tracks not_allowed)
			(vias allowed)
			(pads allowed)
			(copperpour not_allowed)
			(footprints allowed)
		)
		(placement
			(enabled no)
			(sheetname "")
		)
		(fill yes
			(thermal_gap 0.5)
			(thermal_bridge_width 0.5)
			(island_removal_mode 0)
		)
		(polygon
			(pts
				(xy -242.665202 17.964559) (xy -243.023873 18.141749) (xy -243.677953 17.90733) (xy -243.988003 17.279714)
				(xy -243.912692 17.019831) (xy -243.016131 16.576919) (xy -242.76397 16.675024) (xy -242.453922 17.30264)
			)
		)
	)
	(zone
		(layers "F.Cu" "In1.Cu" "In2.Cu" "In3.Cu" "In4.Cu" "In5.Cu" "In6.Cu")
		(hatch none 0.5)
		(connect_pads
			(clearance 0)
		)
		(min_thickness 0.25)
		(keepout
			(tracks not_allowed)
			(vias allowed)
			(pads allowed)
			(copperpour not_allowed)
			(footprints allowed)
		)
		(placement
			(enabled no)
			(sheetname "")
		)
		(fill yes
			(thermal_gap 0.5)
			(thermal_bridge_width 0.5)
			(island_removal_mode 0)
		)
		(polygon
			(pts
				(xy -397.031936 33.484) (xy -395.888936 33.484) (xy -395.888936 30.436) (xy -397.031936 30.436)
			)
		)
	)
	(zone
		(layers "F.Cu" "In1.Cu" "In2.Cu" "In3.Cu" "In4.Cu" "In5.Cu" "In6.Cu")
		(hatch none 0.5)
		(connect_pads
			(clearance 0)
		)
		(min_thickness 0.25)
		(keepout
			(tracks not_allowed)
			(vias allowed)
			(pads allowed)
			(copperpour not_allowed)
			(footprints allowed)
		)
		(placement
			(enabled no)
			(sheetname "")
		)
		(fill yes
			(thermal_gap 0.5)
			(thermal_bridge_width 0.5)
			(island_removal_mode 0)
		)
		(polygon
			(pts
				(xy -23.266344 15.473383) (xy -22.903774 15.304313) (xy -22.255135 15.553395) (xy -21.959293 16.187831)
				(xy -22.040433 16.445954) (xy -22.946741 16.868572) (xy -23.196629 16.764813) (xy -23.492473 16.130374)
			)
		)
	)
	(zone
		(layers "F.Cu" "In1.Cu" "In2.Cu" "In3.Cu" "In4.Cu" "In5.Cu" "In6.Cu")
		(hatch none 0.5)
		(connect_pads
			(clearance 0)
		)
		(min_thickness 0.25)
		(keepout
			(tracks not_allowed)
			(vias allowed)
			(pads allowed)
			(copperpour not_allowed)
			(footprints allowed)
		)
		(placement
			(enabled no)
			(sheetname "")
		)
		(fill yes
			(thermal_gap 0.5)
			(thermal_bridge_width 0.5)
			(island_removal_mode 0)
		)
		(polygon
			(pts
				(xy -29.251501 36.484001) (xy -28.108501 36.484001) (xy -28.108501 33.436001) (xy -29.251501 33.436001)
			)
		)
	)
	(zone
		(layers "F.Cu" "In1.Cu" "In2.Cu" "In3.Cu" "In4.Cu" "In5.Cu" "In6.Cu")
		(hatch none 0.5)
		(connect_pads
			(clearance 0)
		)
		(min_thickness 0.25)
		(keepout
			(tracks not_allowed)
			(vias allowed)
			(pads allowed)
			(copperpour not_allowed)
			(footprints allowed)
		)
		(placement
			(enabled no)
			(sheetname "")
		)
		(fill yes
			(thermal_gap 0.5)
			(thermal_bridge_width 0.5)
			(island_removal_mode 0)
		)
		(polygon
			(pts
				(xy -256.251499 41.984003) (xy -255.108499 41.984003) (xy -255.108499 38.936003) (xy -256.251499 38.936003)
			)
		)
	)
	(zone
		(layers "F.Cu" "In1.Cu" "In2.Cu" "In3.Cu" "In4.Cu" "In5.Cu" "In6.Cu")
		(hatch none 0.5)
		(connect_pads
			(clearance 0)
		)
		(min_thickness 0.25)
		(keepout
			(tracks not_allowed)
			(vias allowed)
			(pads allowed)
			(copperpour not_allowed)
			(footprints allowed)
		)
		(placement
			(enabled no)
			(sheetname "")
		)
		(fill yes
			(thermal_gap 0.5)
			(thermal_bridge_width 0.5)
			(island_removal_mode 0)
		)
		(polygon
			(pts
				(xy -254.251501 36.484001) (xy -253.108501 36.484001) (xy -253.108501 33.436001) (xy -254.251501 33.436001)
			)
		)
	)
	(zone
		(layers "F.Cu" "In1.Cu" "In2.Cu" "In3.Cu" "In4.Cu" "In5.Cu" "In6.Cu")
		(hatch none 0.5)
		(connect_pads
			(clearance 0)
		)
		(min_thickness 0.25)
		(keepout
			(tracks not_allowed)
			(vias allowed)
			(pads allowed)
			(copperpour not_allowed)
			(footprints allowed)
		)
		(placement
			(enabled no)
			(sheetname "")
		)
		(fill yes
			(thermal_gap 0.5)
			(thermal_bridge_width 0.5)
			(island_removal_mode 0)
		)
		(polygon
			(pts
				(xy -403.031937 32.184) (xy -401.888937 32.184) (xy -401.888937 29.136) (xy -403.031937 29.136)
			)
		)
	)
	(zone
		(layers "F.Cu" "In1.Cu" "In2.Cu" "In3.Cu" "In4.Cu" "In5.Cu" "In6.Cu")
		(hatch none 0.5)
		(connect_pads
			(clearance 0)
		)
		(min_thickness 0.25)
		(keepout
			(tracks not_allowed)
			(vias allowed)
			(pads allowed)
			(copperpour not_allowed)
			(footprints allowed)
		)
		(placement
			(enabled no)
			(sheetname "")
		)
		(fill yes
			(thermal_gap 0.5)
			(thermal_bridge_width 0.5)
			(island_removal_mode 0)
		)
		(polygon
			(pts
				(xy -395.031938 32.184) (xy -393.888938 32.184) (xy -393.888938 29.136) (xy -395.031938 29.136)
			)
		)
	)
	(zone
		(layers "F.Cu" "In1.Cu" "In2.Cu" "In3.Cu" "In4.Cu" "In5.Cu" "In6.Cu")
		(hatch none 0.5)
		(connect_pads
			(clearance 0)
		)
		(min_thickness 0.25)
		(keepout
			(tracks not_allowed)
			(vias allowed)
			(pads allowed)
			(copperpour not_allowed)
			(footprints allowed)
		)
		(placement
			(enabled no)
			(sheetname "")
		)
		(fill yes
			(thermal_gap 0.5)
			(thermal_bridge_width 0.5)
			(island_removal_mode 0)
		)
		(polygon
			(pts
				(xy -304.611938 40.683998) (xy -303.468938 40.683998) (xy -303.468938 37.635998) (xy -304.611938 37.635998)
			)
		)
	)
	(zone
		(layers "F.Cu" "In1.Cu" "In2.Cu" "In3.Cu" "In4.Cu" "In5.Cu" "In6.Cu")
		(hatch none 0.5)
		(connect_pads
			(clearance 0)
		)
		(min_thickness 0.25)
		(keepout
			(tracks not_allowed)
			(vias allowed)
			(pads allowed)
			(copperpour not_allowed)
			(footprints allowed)
		)
		(placement
			(enabled no)
			(sheetname "")
		)
		(fill yes
			(thermal_gap 0.5)
			(thermal_bridge_width 0.5)
			(island_removal_mode 0)
		)
		(polygon
			(pts
				(xy -242.665202 14.164559) (xy -243.023873 14.341749) (xy -243.677953 14.10733) (xy -243.988003 13.479714)
				(xy -243.912692 13.219831) (xy -243.016131 12.776919) (xy -242.76397 12.875024) (xy -242.453922 13.50264)
			)
		)
	)
	(zone
		(layers "F.Cu" "In1.Cu" "In2.Cu" "In3.Cu" "In4.Cu" "In5.Cu" "In6.Cu")
		(hatch none 0.5)
		(connect_pads
			(clearance 0)
		)
		(min_thickness 0.25)
		(keepout
			(tracks not_allowed)
			(vias allowed)
			(pads allowed)
			(copperpour not_allowed)
			(footprints allowed)
		)
		(placement
			(enabled no)
			(sheetname "")
		)
		(fill yes
			(thermal_gap 0.5)
			(thermal_bridge_width 0.5)
			(island_removal_mode 0)
		)
		(polygon
			(pts
				(xy -23.915202 14.164559) (xy -24.273873 14.341749) (xy -24.927954 14.10733) (xy -25.238004 13.479714)
				(xy -25.162693 13.219831) (xy -24.266131 12.776919) (xy -24.01397 12.875024) (xy -23.703923 13.50264)
			)
		)
	)
	(zone
		(layers "F.Cu" "In1.Cu" "In2.Cu" "In3.Cu" "In4.Cu" "In5.Cu" "In6.Cu")
		(hatch none 0.5)
		(connect_pads
			(clearance 0)
		)
		(min_thickness 0.25)
		(keepout
			(tracks not_allowed)
			(vias allowed)
			(pads allowed)
			(copperpour not_allowed)
			(footprints allowed)
		)
		(placement
			(enabled no)
			(sheetname "")
		)
		(fill yes
			(thermal_gap 0.5)
			(thermal_bridge_width 0.5)
			(island_removal_mode 0)
		)
		(polygon
			(pts
				(xy -405.031936 33.484) (xy -403.888936 33.484) (xy -403.888936 30.436) (xy -405.031936 30.436)
			)
		)
	)
	(zone
		(layers "F.Cu" "In1.Cu" "In2.Cu" "In3.Cu" "In4.Cu" "In5.Cu" "In6.Cu")
		(hatch none 0.5)
		(connect_pads
			(clearance 0)
		)
		(min_thickness 0.25)
		(keepout
			(tracks not_allowed)
			(vias allowed)
			(pads allowed)
			(copperpour not_allowed)
			(footprints allowed)
		)
		(placement
			(enabled no)
			(sheetname "")
		)
		(fill yes
			(thermal_gap 0.5)
			(thermal_bridge_width 0.5)
			(island_removal_mode 0)
		)
		(polygon
			(pts
				(xy -174.031938 32.184) (xy -172.888938 32.184) (xy -172.888938 29.136) (xy -174.031938 29.136)
			)
		)
	)
	(zone
		(layers "F.Cu" "In1.Cu" "In2.Cu" "In3.Cu" "In4.Cu" "In5.Cu" "In6.Cu")
		(hatch none 0.5)
		(connect_pads
			(clearance 0)
		)
		(min_thickness 0.25)
		(keepout
			(tracks not_allowed)
			(vias allowed)
			(pads allowed)
			(copperpour not_allowed)
			(footprints allowed)
		)
		(placement
			(enabled no)
			(sheetname "")
		)
		(fill yes
			(thermal_gap 0.5)
			(thermal_bridge_width 0.5)
			(island_removal_mode 0)
		)
		(polygon
			(pts
				(xy -21.665202 17.964559) (xy -22.023873 18.141749) (xy -22.677953 17.90733) (xy -22.988003 17.279714)
				(xy -22.912692 17.019831) (xy -22.016131 16.576919) (xy -21.76397 16.675024) (xy -21.453922 17.30264)
			)
		)
	)
	(zone
		(layers "F.Cu" "In1.Cu" "In2.Cu" "In3.Cu" "In4.Cu" "In5.Cu" "In6.Cu")
		(hatch none 0.5)
		(connect_pads
			(clearance 0)
		)
		(min_thickness 0.25)
		(keepout
			(tracks not_allowed)
			(vias allowed)
			(pads allowed)
			(copperpour not_allowed)
			(footprints allowed)
		)
		(placement
			(enabled no)
			(sheetname "")
		)
		(fill yes
			(thermal_gap 0.5)
			(thermal_bridge_width 0.5)
			(island_removal_mode 0)
		)
		(polygon
			(pts
				(xy -248.2515 41.984003) (xy -247.1085 41.984003) (xy -247.1085 38.936003) (xy -248.2515 38.936003)
			)
		)
	)
	(zone
		(layers "F.Cu" "In1.Cu" "In2.Cu" "In3.Cu" "In4.Cu" "In5.Cu" "In6.Cu")
		(hatch none 0.5)
		(connect_pads
			(clearance 0)
		)
		(min_thickness 0.25)
		(keepout
			(tracks not_allowed)
			(vias allowed)
			(pads allowed)
			(copperpour not_allowed)
			(footprints allowed)
		)
		(placement
			(enabled no)
			(sheetname "")
		)
		(fill yes
			(thermal_gap 0.5)
			(thermal_bridge_width 0.5)
			(island_removal_mode 0)
		)
		(polygon
			(pts
				(xy -253.665203 21.764559) (xy -254.023873 21.941749) (xy -254.677954 21.70733) (xy -254.988004 21.079714)
				(xy -254.912693 20.819831) (xy -254.016132 20.376919) (xy -253.763971 20.475024) (xy -253.453923 21.10264)
			)
		)
	)
	(zone
		(layers "F.Cu" "In1.Cu" "In2.Cu" "In3.Cu" "In4.Cu" "In5.Cu" "In6.Cu")
		(hatch none 0.5)
		(connect_pads
			(clearance 0)
		)
		(min_thickness 0.25)
		(keepout
			(tracks not_allowed)
			(vias allowed)
			(pads allowed)
			(copperpour not_allowed)
			(footprints allowed)
		)
		(placement
			(enabled no)
			(sheetname "")
		)
		(fill yes
			(thermal_gap 0.5)
			(thermal_bridge_width 0.5)
			(island_removal_mode 0)
		)
		(polygon
			(pts
				(xy -244.266344 15.473383) (xy -243.903774 15.304313) (xy -243.255135 15.553395) (xy -242.959293 16.187831)
				(xy -243.040433 16.445954) (xy -243.946741 16.868572) (xy -244.196629 16.764813) (xy -244.492473 16.130374)
			)
		)
	)
	(zone
		(layers "F.Cu" "In1.Cu" "In2.Cu" "In3.Cu" "In4.Cu" "In5.Cu" "In6.Cu")
		(hatch none 0.5)
		(connect_pads
			(clearance 0)
		)
		(min_thickness 0.25)
		(keepout
			(tracks not_allowed)
			(vias allowed)
			(pads allowed)
			(copperpour not_allowed)
			(footprints allowed)
		)
		(placement
			(enabled no)
			(sheetname "")
		)
		(fill yes
			(thermal_gap 0.5)
			(thermal_bridge_width 0.5)
			(island_removal_mode 0)
		)
		(polygon
			(pts
				(xy -73.611938 37.784009) (xy -72.468938 37.784009) (xy -72.468938 34.736009) (xy -73.611938 34.736009)
			)
		)
	)
	(zone
		(layers "F.Cu" "In1.Cu" "In2.Cu" "In3.Cu" "In4.Cu" "In5.Cu" "In6.Cu")
		(hatch none 0.5)
		(connect_pads
			(clearance 0)
		)
		(min_thickness 0.25)
		(keepout
			(tracks not_allowed)
			(vias allowed)
			(pads allowed)
			(copperpour not_allowed)
			(footprints allowed)
		)
		(placement
			(enabled no)
			(sheetname "")
		)
		(fill yes
			(thermal_gap 0.5)
			(thermal_bridge_width 0.5)
			(island_removal_mode 0)
		)
		(polygon
			(pts
				(xy -27.2515 41.984003) (xy -26.1085 41.984003) (xy -26.1085 38.936003) (xy -27.2515 38.936003)
			)
		)
	)
	(zone
		(layers "F.Cu" "In1.Cu" "In2.Cu" "In3.Cu" "In4.Cu" "In5.Cu" "In6.Cu")
		(hatch none 0.5)
		(connect_pads
			(clearance 0)
		)
		(min_thickness 0.25)
		(keepout
			(tracks not_allowed)
			(vias allowed)
			(pads allowed)
			(copperpour not_allowed)
			(footprints allowed)
		)
		(placement
			(enabled no)
			(sheetname "")
		)
		(fill yes
			(thermal_gap 0.5)
			(thermal_bridge_width 0.5)
			(island_removal_mode 0)
		)
		(polygon
			(pts
				(xy -250.251501 36.484001) (xy -249.108501 36.484001) (xy -249.108501 33.436001) (xy -250.251501 33.436001)
			)
		)
	)
	(zone
		(layers "F.Cu" "In1.Cu" "In2.Cu" "In3.Cu" "In4.Cu" "In5.Cu" "In6.Cu")
		(hatch none 0.5)
		(connect_pads
			(clearance 0)
		)
		(min_thickness 0.25)
		(keepout
			(tracks not_allowed)
			(vias allowed)
			(pads allowed)
			(copperpour not_allowed)
			(footprints allowed)
		)
		(placement
			(enabled no)
			(sheetname "")
		)
		(fill yes
			(thermal_gap 0.5)
			(thermal_bridge_width 0.5)
			(island_removal_mode 0)
		)
		(polygon
			(pts
				(xy -178.031938 32.184) (xy -176.888938 32.184) (xy -176.888938 29.136) (xy -178.031938 29.136)
			)
		)
	)
	(zone
		(layers "F.Cu" "In1.Cu" "In2.Cu" "In3.Cu" "In4.Cu" "In5.Cu" "In6.Cu")
		(hatch none 0.5)
		(connect_pads
			(clearance 0)
		)
		(min_thickness 0.25)
		(keepout
			(tracks not_allowed)
			(vias allowed)
			(pads allowed)
			(copperpour not_allowed)
			(footprints allowed)
		)
		(placement
			(enabled no)
			(sheetname "")
		)
		(fill yes
			(thermal_gap 0.5)
			(thermal_bridge_width 0.5)
			(island_removal_mode 0)
		)
		(polygon
			(pts
				(xy -253.665203 14.164559) (xy -254.023873 14.341749) (xy -254.677954 14.10733) (xy -254.988004 13.479714)
				(xy -254.912693 13.219831) (xy -254.016132 12.776919) (xy -253.763971 12.875024) (xy -253.453923 13.50264)
			)
		)
	)
	(zone
		(layers "F.Cu" "In1.Cu" "In2.Cu" "In3.Cu" "In4.Cu" "In5.Cu" "In6.Cu")
		(hatch none 0.5)
		(connect_pads
			(clearance 0)
		)
		(min_thickness 0.25)
		(keepout
			(tracks not_allowed)
			(vias allowed)
			(pads allowed)
			(copperpour not_allowed)
			(footprints allowed)
		)
		(placement
			(enabled no)
			(sheetname "")
		)
		(fill yes
			(thermal_gap 0.5)
			(thermal_bridge_width 0.5)
			(island_removal_mode 0)
		)
		(polygon
			(pts
				(xy -77.611938 46.184012) (xy -76.468938 46.184012) (xy -76.468938 43.136012) (xy -77.611938 43.136012)
			)
		)
	)
	(zone
		(layers "F.Cu" "In1.Cu" "In2.Cu" "In3.Cu" "In4.Cu" "In5.Cu" "In6.Cu")
		(hatch none 0.5)
		(connect_pads
			(clearance 0)
		)
		(min_thickness 0.25)
		(keepout
			(tracks not_allowed)
			(vias allowed)
			(pads allowed)
			(copperpour not_allowed)
			(footprints allowed)
		)
		(placement
			(enabled no)
			(sheetname "")
		)
		(fill yes
			(thermal_gap 0.5)
			(thermal_bridge_width 0.5)
			(island_removal_mode 0)
		)
		(polygon
			(pts
				(xy -32.665203 14.164559) (xy -33.023874 14.341749) (xy -33.677954 14.10733) (xy -33.988004 13.479714)
				(xy -33.912693 13.219831) (xy -33.016132 12.776919) (xy -32.763971 12.875024) (xy -32.453923 13.50264)
			)
		)
	)
	(zone
		(layers "F.Cu" "In1.Cu" "In2.Cu" "In3.Cu" "In4.Cu" "In5.Cu" "In6.Cu")
		(hatch none 0.5)
		(connect_pads
			(clearance 0)
		)
		(min_thickness 0.25)
		(keepout
			(tracks not_allowed)
			(vias allowed)
			(pads allowed)
			(copperpour not_allowed)
			(footprints allowed)
		)
		(placement
			(enabled no)
			(sheetname "")
		)
		(fill yes
			(thermal_gap 0.5)
			(thermal_bridge_width 0.5)
			(island_removal_mode 0)
		)
		(polygon
			(pts
				(xy -33.251501 36.484001) (xy -32.108501 36.484001) (xy -32.108501 33.436001) (xy -33.251501 33.436001)
			)
		)
	)
	(zone
		(layers "F.Cu" "In1.Cu" "In2.Cu" "In3.Cu" "In4.Cu" "In5.Cu" "In6.Cu")
		(hatch none 0.5)
		(connect_pads
			(clearance 0)
		)
		(min_thickness 0.25)
		(keepout
			(tracks not_allowed)
			(vias allowed)
			(pads allowed)
			(copperpour not_allowed)
			(footprints allowed)
		)
		(placement
			(enabled no)
			(sheetname "")
		)
		(fill yes
			(thermal_gap 0.5)
			(thermal_bridge_width 0.5)
			(island_removal_mode 0)
		)
		(polygon
			(pts
				(xy -32.665203 17.964559) (xy -33.023874 18.141749) (xy -33.677954 17.90733) (xy -33.988004 17.279714)
				(xy -33.912693 17.019831) (xy -33.016132 16.576919) (xy -32.763971 16.675024) (xy -32.453923 17.30264)
			)
		)
	)
	(zone
		(layers "F.Cu" "In1.Cu" "In2.Cu" "In3.Cu" "In4.Cu" "In5.Cu" "In6.Cu")
		(hatch none 0.5)
		(connect_pads
			(clearance 0)
		)
		(min_thickness 0.25)
		(keepout
			(tracks not_allowed)
			(vias allowed)
			(pads allowed)
			(copperpour not_allowed)
			(footprints allowed)
		)
		(placement
			(enabled no)
			(sheetname "")
		)
		(fill yes
			(thermal_gap 0.5)
			(thermal_bridge_width 0.5)
			(island_removal_mode 0)
		)
		(polygon
			(pts
				(xy -32.665203 21.764559) (xy -33.023874 21.941749) (xy -33.677954 21.70733) (xy -33.988004 21.079714)
				(xy -33.912693 20.819831) (xy -33.016132 20.376919) (xy -32.763971 20.475024) (xy -32.453923 21.10264)
			)
		)
	)
	(zone
		(layers "F.Cu" "In1.Cu" "In2.Cu" "In3.Cu" "In4.Cu" "In5.Cu" "In6.Cu")
		(hatch none 0.5)
		(connect_pads
			(clearance 0)
		)
		(min_thickness 0.25)
		(keepout
			(tracks not_allowed)
			(vias allowed)
			(pads allowed)
			(copperpour not_allowed)
			(footprints allowed)
		)
		(placement
			(enabled no)
			(sheetname "")
		)
		(fill yes
			(thermal_gap 0.5)
			(thermal_bridge_width 0.5)
			(island_removal_mode 0)
		)
		(polygon
			(pts
				(xy -182.031937 32.184) (xy -180.888937 32.184) (xy -180.888937 29.136) (xy -182.031937 29.136)
			)
		)
	)
	(zone
		(layers "F.Cu" "In1.Cu" "In2.Cu" "In3.Cu" "In4.Cu" "In5.Cu" "In6.Cu")
		(hatch none 0.5)
		(connect_pads
			(clearance 0)
		)
		(min_thickness 0.25)
		(keepout
			(tracks not_allowed)
			(vias allowed)
			(pads allowed)
			(copperpour not_allowed)
			(footprints allowed)
		)
		(placement
			(enabled no)
			(sheetname "")
		)
		(fill yes
			(thermal_gap 0.5)
			(thermal_bridge_width 0.5)
			(island_removal_mode 0)
		)
		(polygon
			(pts
				(xy -244.915202 14.164559) (xy -245.273873 14.341749) (xy -245.927954 14.10733) (xy -246.238004 13.479714)
				(xy -246.162693 13.219831) (xy -245.266131 12.776919) (xy -245.01397 12.875024) (xy -244.703923 13.50264)
			)
		)
	)
	(zone
		(layers "F.Cu" "In1.Cu" "In2.Cu" "In3.Cu" "In4.Cu" "In5.Cu" "In6.Cu")
		(hatch none 0.5)
		(connect_pads
			(clearance 0)
		)
		(min_thickness 0.25)
		(keepout
			(tracks not_allowed)
			(vias allowed)
			(pads allowed)
			(copperpour not_allowed)
			(footprints allowed)
		)
		(placement
			(enabled no)
			(sheetname "")
		)
		(fill yes
			(thermal_gap 0.5)
			(thermal_bridge_width 0.5)
			(island_removal_mode 0)
		)
		(polygon
			(pts
				(xy -248.2515 37.784001) (xy -247.1085 37.784001) (xy -247.1085 34.736001) (xy -248.2515 34.736001)
			)
		)
	)
	(zone
		(layers "F.Cu" "In1.Cu" "In2.Cu" "In3.Cu" "In4.Cu" "In6.Cu")
		(hatch none 0.5)
		(connect_pads
			(clearance 0)
		)
		(min_thickness 0.25)
		(keepout
			(tracks not_allowed)
			(vias allowed)
			(pads allowed)
			(copperpour not_allowed)
			(footprints allowed)
		)
		(placement
			(enabled no)
			(sheetname "")
		)
		(fill yes
			(thermal_gap 0.5)
			(thermal_bridge_width 0.5)
			(island_removal_mode 0)
		)
		(polygon
			(pts
				(xy -75.611939 44.884012) (xy -74.468939 44.884012) (xy -74.468939 41.836012) (xy -75.611939 41.836012)
			)
		)
	)
	(zone
		(layers "F.Cu" "In1.Cu" "In2.Cu" "In3.Cu" "In4.Cu" "In6.Cu")
		(hatch none 0.5)
		(connect_pads
			(clearance 0)
		)
		(min_thickness 0.25)
		(keepout
			(tracks not_allowed)
			(vias allowed)
			(pads allowed)
			(copperpour not_allowed)
			(footprints allowed)
		)
		(placement
			(enabled no)
			(sheetname "")
		)
		(fill yes
			(thermal_gap 0.5)
			(thermal_bridge_width 0.5)
			(island_removal_mode 0)
		)
		(polygon
			(pts
				(xy -409.031935 33.484) (xy -407.888935 33.484) (xy -407.888935 30.436) (xy -409.031935 30.436)
			)
		)
	)
	(zone
		(layers "F.Cu" "In1.Cu" "In2.Cu" "In3.Cu" "In4.Cu" "In6.Cu")
		(hatch none 0.5)
		(connect_pads
			(clearance 0)
		)
		(min_thickness 0.25)
		(keepout
			(tracks not_allowed)
			(vias allowed)
			(pads allowed)
			(copperpour not_allowed)
			(footprints allowed)
		)
		(placement
			(enabled no)
			(sheetname "")
		)
		(fill yes
			(thermal_gap 0.5)
			(thermal_bridge_width 0.5)
			(island_removal_mode 0)
		)
		(polygon
			(pts
				(xy -300.611939 44.884012) (xy -299.468939 44.884012) (xy -299.468939 41.836012) (xy -300.611939 41.836012)
			)
		)
	)
	(zone
		(layers "F.Cu" "In1.Cu" "In2.Cu" "In3.Cu" "In4.Cu" "In6.Cu")
		(hatch none 0.5)
		(connect_pads
			(clearance 0)
		)
		(min_thickness 0.25)
		(keepout
			(tracks not_allowed)
			(vias allowed)
			(pads allowed)
			(copperpour not_allowed)
			(footprints allowed)
		)
		(placement
			(enabled no)
			(sheetname "")
		)
		(fill yes
			(thermal_gap 0.5)
			(thermal_bridge_width 0.5)
			(island_removal_mode 0)
		)
		(polygon
			(pts
				(xy -188.031935 33.484) (xy -186.888935 33.484) (xy -186.888935 30.436) (xy -188.031935 30.436)
			)
		)
	)
	(zone
		(layers "F.Cu" "In1.Cu" "In2.Cu" "In3.Cu" "In4.Cu" "In6.Cu")
		(hatch none 0.5)
		(connect_pads
			(clearance 0)
		)
		(min_thickness 0.25)
		(keepout
			(tracks not_allowed)
			(vias allowed)
			(pads allowed)
			(copperpour not_allowed)
			(footprints allowed)
		)
		(placement
			(enabled no)
			(sheetname "")
		)
		(fill yes
			(thermal_gap 0.5)
			(thermal_bridge_width 0.5)
			(island_removal_mode 0)
		)
		(polygon
			(pts
				(xy -73.611938 46.184012) (xy -72.468938 46.184012) (xy -72.468938 43.136012) (xy -73.611938 43.136012)
			)
		)
	)
	(zone
		(layers "F.Cu" "In1.Cu" "In2.Cu" "In3.Cu" "In4.Cu" "In6.Cu")
		(hatch none 0.5)
		(connect_pads
			(clearance 0)
		)
		(min_thickness 0.25)
		(keepout
			(tracks not_allowed)
			(vias allowed)
			(pads allowed)
			(copperpour not_allowed)
			(footprints allowed)
		)
		(placement
			(enabled no)
			(sheetname "")
		)
		(fill yes
			(thermal_gap 0.5)
			(thermal_bridge_width 0.5)
			(island_removal_mode 0)
		)
		(polygon
			(pts
				(xy -79.611939 44.884012) (xy -78.468939 44.884012) (xy -78.468939 41.836012) (xy -79.611939 41.836012)
			)
		)
	)
	(zone
		(layers "F.Cu" "In1.Cu" "In2.Cu" "In3.Cu" "In4.Cu" "In6.Cu")
		(hatch none 0.5)
		(connect_pads
			(clearance 0)
		)
		(min_thickness 0.25)
		(keepout
			(tracks not_allowed)
			(vias allowed)
			(pads allowed)
			(copperpour not_allowed)
			(footprints allowed)
		)
		(placement
			(enabled no)
			(sheetname "")
		)
		(fill yes
			(thermal_gap 0.5)
			(thermal_bridge_width 0.5)
			(island_removal_mode 0)
		)
		(polygon
			(pts
				(xy -294.611938 46.184012) (xy -293.468938 46.184012) (xy -293.468938 43.136012) (xy -294.611938 43.136012)
			)
		)
	)
	(zone
		(layers "F.Cu" "In1.Cu" "In2.Cu" "In3.Cu" "In4.Cu" "In6.Cu")
		(hatch none 0.5)
		(connect_pads
			(clearance 0)
		)
		(min_thickness 0.25)
		(keepout
			(tracks not_allowed)
			(vias allowed)
			(pads allowed)
			(copperpour not_allowed)
			(footprints allowed)
		)
		(placement
			(enabled no)
			(sheetname "")
		)
		(fill yes
			(thermal_gap 0.5)
			(thermal_bridge_width 0.5)
			(island_removal_mode 0)
		)
		(polygon
			(pts
				(xy -296.611939 44.884012) (xy -295.468939 44.884012) (xy -295.468939 41.836012) (xy -296.611939 41.836012)
			)
		)
	)
	(zone
		(layers "F.Cu" "In1.Cu" "In2.Cu" "In3.Cu" "In4.Cu" "In6.Cu")
		(hatch none 0.5)
		(connect_pads
			(clearance 0)
		)
		(min_thickness 0.25)
		(keepout
			(tracks not_allowed)
			(vias allowed)
			(pads allowed)
			(copperpour not_allowed)
			(footprints allowed)
		)
		(placement
			(enabled no)
			(sheetname "")
		)
		(fill yes
			(thermal_gap 0.5)
			(thermal_bridge_width 0.5)
			(island_removal_mode 0)
		)
		(polygon
			(pts
				(xy -186.031937 36.384001) (xy -184.888937 36.384001) (xy -184.888937 33.336001) (xy -186.031937 33.336001)
			)
		)
	)
	(zone
		(layers "F.Cu" "In1.Cu" "In2.Cu" "In4.Cu" "In6.Cu")
		(hatch none 0.5)
		(connect_pads
			(clearance 0)
		)
		(min_thickness 0.25)
		(keepout
			(tracks not_allowed)
			(vias allowed)
			(pads allowed)
			(copperpour not_allowed)
			(footprints allowed)
		)
		(placement
			(enabled no)
			(sheetname "")
		)
		(fill yes
			(thermal_gap 0.5)
			(thermal_bridge_width 0.5)
			(island_removal_mode 0)
		)
		(polygon
			(pts
				(xy -407.031937 36.384001) (xy -405.888937 36.384001) (xy -405.888937 33.336001) (xy -407.031937 33.336001)
			)
		)
	)
	(zone
		(layer "B.Cu")
		(hatch none 0.5)
		(connect_pads
			(clearance 0)
		)
		(min_thickness 0.25)
		(keepout
			(tracks not_allowed)
			(vias allowed)
			(pads allowed)
			(copperpour not_allowed)
			(footprints allowed)
		)
		(placement
			(enabled no)
			(sheetname "")
		)
		(fill
			(thermal_gap 0.5)
			(thermal_bridge_width 0.5)
			(island_removal_mode 0)
		)
		(polygon
			(pts
				(arc
					(start -146.16 23.459999)
					(mid -142.46 19.759999)
					(end -138.759999 23.459999)
				)
				(arc
					(start -138.759999 29.46)
					(mid -142.46 33.160001)
					(end -146.16 29.46)
				)
			)
		)
	)
	(zone
		(layer "B.Cu")
		(hatch none 0.5)
		(connect_pads
			(clearance 0)
		)
		(min_thickness 0.25)
		(keepout
			(tracks allowed)
			(vias allowed)
			(pads allowed)
			(copperpour allowed)
			(footprints not_allowed)
		)
		(placement
			(enabled no)
			(sheetname "")
		)
		(fill
			(thermal_gap 0.5)
			(thermal_bridge_width 0.5)
			(island_removal_mode 0)
		)
		(polygon
			(pts
				(arc
					(start -42.1097 20.000001)
					(mid -45.109702 23.000003)
					(end -48.109701 20.000001)
				)
				(arc
					(start -48.109701 14)
					(mid -45.109702 11.000001)
					(end -42.1097 14)
				)
			)
		)
	)
	(zone
		(layer "B.Cu")
		(hatch none 0.5)
		(connect_pads
			(clearance 0)
		)
		(min_thickness 0.25)
		(keepout
			(tracks allowed)
			(vias allowed)
			(pads allowed)
			(copperpour allowed)
			(footprints not_allowed)
		)
		(placement
			(enabled no)
			(sheetname "")
		)
		(fill
			(thermal_gap 0.5)
			(thermal_bridge_width 0.5)
			(island_removal_mode 0)
		)
		(polygon
			(pts
				(arc
					(start -413.760001 19)
					(mid -417.460001 22.7)
					(end -421.160001 19)
				)
				(arc
					(start -421.160001 12.999999)
					(mid -417.460001 9.299999)
					(end -413.760001 12.999999)
				)
			)
		)
	)
	(zone
		(layer "B.Cu")
		(hatch none 0.5)
		(connect_pads
			(clearance 0)
		)
		(min_thickness 0.25)
		(keepout
			(tracks not_allowed)
			(vias allowed)
			(pads allowed)
			(copperpour not_allowed)
			(footprints allowed)
		)
		(placement
			(enabled no)
			(sheetname "")
		)
		(fill
			(thermal_gap 0.5)
			(thermal_bridge_width 0.5)
			(island_removal_mode 0)
		)
		(polygon
			(pts
				(xy -300.611939 41.836012) (xy -300.611939 44.884012) (xy -299.468939 44.884012) (xy -299.468939 41.836012)
			)
		)
	)
	(zone
		(layer "B.Cu")
		(hatch none 0.5)
		(connect_pads
			(clearance 0)
		)
		(min_thickness 0.25)
		(keepout
			(tracks allowed)
			(vias allowed)
			(pads allowed)
			(copperpour allowed)
			(footprints not_allowed)
		)
		(placement
			(enabled no)
			(sheetname "")
		)
		(fill
			(thermal_gap 0.5)
			(thermal_bridge_width 0.5)
			(island_removal_mode 0)
		)
		(polygon
			(pts
				(arc
					(start -420.43 29.067897)
					(mid -417.460002 21.73)
					(end -414.489999 29.067897)
				)
				(arc
					(start -414.489999 30.000001)
					(mid -417.460001 32.970003)
					(end -420.43 30.000001)
				)
			)
		)
	)
	(zone
		(layer "B.Cu")
		(hatch none 0.5)
		(connect_pads
			(clearance 0)
		)
		(min_thickness 0.25)
		(keepout
			(tracks not_allowed)
			(vias allowed)
			(pads allowed)
			(copperpour not_allowed)
			(footprints allowed)
		)
		(placement
			(enabled no)
			(sheetname "")
		)
		(fill
			(thermal_gap 0.5)
			(thermal_bridge_width 0.5)
			(island_removal_mode 0)
		)
		(polygon
			(pts
				(xy -79.611939 41.836012) (xy -79.611939 44.884012) (xy -78.468939 44.884012) (xy -78.468939 41.836012)
			)
		)
	)
	(zone
		(layer "B.Cu")
		(hatch none 0.5)
		(connect_pads
			(clearance 0)
		)
		(min_thickness 0.25)
		(keepout
			(tracks not_allowed)
			(vias allowed)
			(pads allowed)
			(copperpour not_allowed)
			(footprints allowed)
		)
		(placement
			(enabled no)
			(sheetname "")
		)
		(fill
			(thermal_gap 0.5)
			(thermal_bridge_width 0.5)
			(island_removal_mode 0)
		)
		(polygon
			(pts
				(arc
					(start -12.009999 26.86)
					(mid -8.310001 23.160002)
					(end -4.610001 26.86)
				)
				(arc
					(start -4.610001 32.86)
					(mid -8.310001 36.56)
					(end -12.009999 32.86)
				)
			)
		)
	)
	(zone
		(layer "B.Cu")
		(hatch none 0.5)
		(connect_pads
			(clearance 0)
		)
		(min_thickness 0.25)
		(keepout
			(tracks allowed)
			(vias allowed)
			(pads allowed)
			(copperpour allowed)
			(footprints not_allowed)
		)
		(placement
			(enabled no)
			(sheetname "")
		)
		(fill
			(thermal_gap 0.5)
			(thermal_bridge_width 0.5)
			(island_removal_mode 0)
		)
		(polygon
			(pts
				(arc
					(start -73.76 23.459999)
					(mid -77.46 27.159999)
					(end -81.16 23.459999)
				)
				(arc
					(start -81.16 17.460001)
					(mid -77.46 13.760001)
					(end -73.76 17.460001)
				)
			)
		)
	)
	(zone
		(layer "B.Cu")
		(hatch none 0.5)
		(connect_pads
			(clearance 0)
		)
		(min_thickness 0.25)
		(keepout
			(tracks allowed)
			(vias allowed)
			(pads allowed)
			(copperpour allowed)
			(footprints not_allowed)
		)
		(placement
			(enabled no)
			(sheetname "")
		)
		(fill
			(thermal_gap 0.5)
			(thermal_bridge_width 0.5)
			(island_removal_mode 0)
		)
		(polygon
			(pts
				(arc
					(start -302.43 21.527897)
					(mid -299.460002 14.19)
					(end -296.489999 21.527897)
				)
				(arc
					(start -296.489999 22.460001)
					(mid -299.460001 25.430003)
					(end -302.43 22.460001)
				)
			)
		)
	)
	(zone
		(net "GND")
		(layer "B.Cu")
		(hatch none 0.5)
		(connect_pads
			(clearance 0.5)
		)
		(min_thickness 0.25)
		(fill yes
			(thermal_gap 0.5)
			(thermal_bridge_width 0.5)
			(island_removal_mode 0)
		)
		(polygon
			(pts
				(xy -327.4822 27.559) (xy -327.4822 46.863) (xy -369.7732 46.863) (xy -369.7732 26.7462) (xy -369.7732 22.606)
				(xy -368.8842 21.717) (xy -366.395 21.717) (xy -363.7026 19.0246) (xy -362.2548 19.0246) (xy -343.0778 19.0246)
				(xy -335.3562 26.7462) (xy -328.295 26.7462)
			)
		)
	)
	(zone
		(layer "B.Cu")
		(hatch none 0.5)
		(connect_pads
			(clearance 0)
		)
		(min_thickness 0.25)
		(keepout
			(tracks not_allowed)
			(vias allowed)
			(pads allowed)
			(copperpour not_allowed)
			(footprints allowed)
		)
		(placement
			(enabled no)
			(sheetname "")
		)
		(fill
			(thermal_gap 0.5)
			(thermal_bridge_width 0.5)
			(island_removal_mode 0)
		)
		(polygon
			(pts
				(arc
					(start -421.160001 12.999999)
					(mid -417.460001 9.299999)
					(end -413.760001 12.999999)
				)
				(arc
					(start -413.760001 19)
					(mid -417.460001 22.7)
					(end -421.160001 19)
				)
			)
		)
	)
	(zone
		(layer "B.Cu")
		(hatch none 0.5)
		(connect_pads
			(clearance 0)
		)
		(min_thickness 0.25)
		(keepout
			(tracks allowed)
			(vias allowed)
			(pads allowed)
			(copperpour allowed)
			(footprints not_allowed)
		)
		(placement
			(enabled no)
			(sheetname "")
		)
		(fill
			(thermal_gap 0.5)
			(thermal_bridge_width 0.5)
			(island_removal_mode 0)
		)
		(polygon
			(pts
				(arc
					(start -162.77 39.36)
					(mid -165.770001 42.360001)
					(end -168.77 39.36)
				)
				(arc
					(start -168.77 33.359999)
					(mid -165.770001 30.36)
					(end -162.77 33.359999)
				)
			)
		)
	)
	(zone
		(net "P5V_USB_B1")
		(layer "B.Cu")
		(hatch none 0.5)
		(connect_pads
			(clearance 0.5)
		)
		(min_thickness 0.25)
		(fill yes
			(thermal_gap 0.5)
			(thermal_bridge_width 0.5)
			(island_removal_mode 0)
		)
		(polygon
			(pts
				(xy -416.1028 32.2326) (xy -413.8168 34.5186) (xy -413.8168 38.0492) (xy -411.4038 40.4622) (xy -409.9052 40.4622)
				(xy -409.3972 39.9542) (xy -409.3972 39.4208) (xy -409.9052 38.9128) (xy -411.0228 38.9128) (xy -411.7086 38.227)
				(xy -411.7086 32.0802) (xy -414.0454 29.7434) (xy -414.2486 29.5402) (xy -419.7858 29.5402) (xy -420.2176 29.972)
				(xy -420.2176 31.5976) (xy -419.5826 32.2326)
			)
		)
	)
	(zone
		(layer "B.Cu")
		(hatch none 0.5)
		(connect_pads
			(clearance 0)
		)
		(min_thickness 0.25)
		(keepout
			(tracks not_allowed)
			(vias allowed)
			(pads allowed)
			(copperpour not_allowed)
			(footprints allowed)
		)
		(placement
			(enabled no)
			(sheetname "")
		)
		(fill
			(thermal_gap 0.5)
			(thermal_bridge_width 0.5)
			(island_removal_mode 0)
		)
		(polygon
			(pts
				(xy -296.611939 41.836012) (xy -296.611939 44.884012) (xy -295.468939 44.884012) (xy -295.468939 41.836012)
			)
		)
	)
	(zone
		(layer "B.Cu")
		(hatch none 0.5)
		(connect_pads
			(clearance 0)
		)
		(min_thickness 0.25)
		(keepout
			(tracks not_allowed)
			(vias allowed)
			(pads allowed)
			(copperpour not_allowed)
			(footprints allowed)
		)
		(placement
			(enabled no)
			(sheetname "")
		)
		(fill
			(thermal_gap 0.5)
			(thermal_bridge_width 0.5)
			(island_removal_mode 0)
		)
		(polygon
			(pts
				(xy -75.611939 41.836012) (xy -75.611939 44.884012) (xy -74.468939 44.884012) (xy -74.468939 41.836012)
			)
		)
	)
	(zone
		(layer "B.Cu")
		(hatch none 0.5)
		(connect_pads
			(clearance 0)
		)
		(min_thickness 0.25)
		(keepout
			(tracks allowed)
			(vias allowed)
			(pads allowed)
			(copperpour allowed)
			(footprints not_allowed)
		)
		(placement
			(enabled no)
			(sheetname "")
		)
		(fill
			(thermal_gap 0.5)
			(thermal_bridge_width 0.5)
			(island_removal_mode 0)
		)
		(polygon
			(pts
				(arc
					(start -165.429999 6.527897)
					(mid -162.46 -0.810002)
					(end -159.490001 6.527897)
				)
				(arc
					(start -159.490001 7.46)
					(mid -162.46 10.429999)
					(end -165.429999 7.46)
				)
			)
		)
	)
	(zone
		(layer "B.Cu")
		(hatch none 0.5)
		(connect_pads
			(clearance 0)
		)
		(min_thickness 0.25)
		(keepout
			(tracks allowed)
			(vias allowed)
			(pads allowed)
			(copperpour allowed)
			(footprints not_allowed)
		)
		(placement
			(enabled no)
			(sheetname "")
		)
		(fill
			(thermal_gap 0.5)
			(thermal_bridge_width 0.5)
			(island_removal_mode 0)
		)
		(polygon
			(pts
				(arc
					(start -263.1097 20.000001)
					(mid -266.109701 23.000002)
					(end -269.109701 20.000001)
				)
				(arc
					(start -269.109701 14)
					(mid -266.109701 11)
					(end -263.1097 14)
				)
			)
		)
	)
	(zone
		(layer "B.Cu")
		(hatch none 0.5)
		(connect_pads
			(clearance 0)
		)
		(min_thickness 0.25)
		(keepout
			(tracks allowed)
			(vias allowed)
			(pads allowed)
			(copperpour allowed)
			(footprints not_allowed)
		)
		(placement
			(enabled no)
			(sheetname "")
		)
		(fill
			(thermal_gap 0.5)
			(thermal_bridge_width 0.5)
			(island_removal_mode 0)
		)
		(polygon
			(pts
				(arc
					(start -80.429999 21.527897)
					(mid -77.46 14.19)
					(end -74.490001 21.527897)
				)
				(arc
					(start -74.490001 22.460001)
					(mid -77.46 25.43)
					(end -80.429999 22.460001)
				)
			)
		)
	)
	(zone
		(layer "B.Cu")
		(hatch none 0.5)
		(connect_pads
			(clearance 0)
		)
		(min_thickness 0.25)
		(keepout
			(tracks allowed)
			(vias allowed)
			(pads allowed)
			(copperpour allowed)
			(footprints not_allowed)
		)
		(placement
			(enabled no)
			(sheetname "")
		)
		(fill
			(thermal_gap 0.5)
			(thermal_bridge_width 0.5)
			(island_removal_mode 0)
		)
		(polygon
			(pts
				(arc
					(start -383.772999 39.36)
					(mid -386.773001 42.360002)
					(end -389.773 39.36)
				)
				(arc
					(start -389.773 33.359999)
					(mid -386.773001 30.36)
					(end -383.772999 33.359999)
				)
			)
		)
	)
	(zone
		(layer "B.Cu")
		(hatch none 0.5)
		(connect_pads
			(clearance 0)
		)
		(min_thickness 0.25)
		(keepout
			(tracks allowed)
			(vias allowed)
			(pads allowed)
			(copperpour allowed)
			(footprints not_allowed)
		)
		(placement
			(enabled no)
			(sheetname "")
		)
		(fill
			(thermal_gap 0.5)
			(thermal_bridge_width 0.5)
			(island_removal_mode 0)
		)
		(polygon
			(pts
				(arc
					(start -347.430781 6.48717)
					(mid -344.460783 -0.850727)
					(end -341.49078 6.48717)
				)
				(arc
					(start -341.49078 7.419274)
					(mid -344.460782 10.389276)
					(end -347.430781 7.419274)
				)
			)
		)
	)
	(zone
		(layer "B.Cu")
		(hatch none 0.5)
		(connect_pads
			(clearance 0)
		)
		(min_thickness 0.25)
		(keepout
			(tracks not_allowed)
			(vias allowed)
			(pads allowed)
			(copperpour not_allowed)
			(footprints allowed)
		)
		(placement
			(enabled no)
			(sheetname "")
		)
		(fill
			(thermal_gap 0.5)
			(thermal_bridge_width 0.5)
			(island_removal_mode 0)
		)
		(polygon
			(pts
				(arc
					(start -81.16 17.460001)
					(mid -77.46 13.760001)
					(end -73.76 17.460001)
				)
				(arc
					(start -73.76 23.459999)
					(mid -77.46 27.159999)
					(end -81.16 23.459999)
				)
			)
		)
	)
	(zone
		(net "P5V_USB_B2")
		(layer "B.Cu")
		(hatch none 0.5)
		(connect_pads
			(clearance 0.5)
		)
		(min_thickness 0.25)
		(fill yes
			(thermal_gap 0.5)
			(thermal_bridge_width 0.5)
			(island_removal_mode 0)
		)
		(polygon
			(pts
				(xy -199.8472 39.1414) (xy -188.9506 39.1414) (xy -188.6204 39.4716) (xy -188.6204 40.132) (xy -189.0268 40.5384)
				(xy -191.2366 40.5384) (xy -193.3194 42.6212) (xy -202.5142 42.6212) (xy -202.819 42.6212) (xy -203.1238 42.3164)
				(xy -203.1238 40.132) (xy -202.742764 39.750964) (xy -200.456764 39.750964)
			)
		)
	)
	(zone
		(layer "B.Cu")
		(hatch none 0.5)
		(connect_pads
			(clearance 0)
		)
		(min_thickness 0.25)
		(keepout
			(tracks allowed)
			(vias allowed)
			(pads allowed)
			(copperpour allowed)
			(footprints not_allowed)
		)
		(placement
			(enabled no)
			(sheetname "")
		)
		(fill
			(thermal_gap 0.5)
			(thermal_bridge_width 0.5)
			(island_removal_mode 0)
		)
		(polygon
			(pts
				(arc
					(start -138.759999 29.46)
					(mid -142.46 33.160001)
					(end -146.16 29.46)
				)
				(arc
					(start -146.16 23.459999)
					(mid -142.46 19.759999)
					(end -138.759999 23.459999)
				)
			)
		)
	)
	(zone
		(net "P3V3_B1_QSFP")
		(layer "B.Cu")
		(hatch none 0.5)
		(connect_pads
			(clearance 0.5)
		)
		(min_thickness 0.25)
		(fill yes
			(thermal_gap 0.5)
			(thermal_bridge_width 0.5)
			(island_removal_mode 0)
		)
		(polygon
			(pts
				(xy -285.8516 23.749) (xy -287.9725 21.6281) (xy -291.5285 21.6281) (xy -292.38575 22.48535) (xy -295.3639 19.5072)
				(xy -295.3639 17.39646) (xy -303.59858 17.39646) (xy -303.59858 19.27098) (xy -307.8226 23.495)
				(xy -331.978 23.495) (xy -332.5622 22.9108) (xy -330.327 22.9108) (xy -330.327 21.082) (xy -334.391 21.082)
				(xy -336.169 19.304) (xy -336.169 10.033) (xy -324.6628 -1.4732) (xy -259.9182 -1.4732) (xy -259.08 -0.635)
				(xy -259.08 8.001) (xy -266.7 15.621) (xy -268.224 15.621) (xy -270.5862 17.9832) (xy -270.5862 23.2156)
				(xy -271.1196 23.749)
			)
		)
	)
	(zone
		(layer "B.Cu")
		(hatch none 0.5)
		(connect_pads
			(clearance 0)
		)
		(min_thickness 0.25)
		(keepout
			(tracks not_allowed)
			(vias allowed)
			(pads allowed)
			(copperpour not_allowed)
			(footprints allowed)
		)
		(placement
			(enabled no)
			(sheetname "")
		)
		(fill
			(thermal_gap 0.5)
			(thermal_bridge_width 0.5)
			(island_removal_mode 0)
		)
		(polygon
			(pts
				(arc
					(start -303.160001 17.460001)
					(mid -299.460001 13.760001)
					(end -295.76 17.460001)
				)
				(arc
					(start -295.76 23.459999)
					(mid -299.460001 27.16)
					(end -303.160001 23.459999)
				)
			)
		)
	)
	(zone
		(net "P12V")
		(layer "B.Cu")
		(hatch none 0.5)
		(connect_pads
			(clearance 0.5)
		)
		(min_thickness 0.25)
		(fill yes
			(thermal_gap 0.5)
			(thermal_bridge_width 0.5)
			(island_removal_mode 0)
		)
		(polygon
			(pts
				(xy -148.082 45.974) (xy -148.082 15.621) (xy -149.225 14.478) (xy -181.991 14.478) (xy -190.5381 23.0251)
				(xy -190.5381 35.7759) (xy -190.919654 36.157454) (xy -202.908296 36.157454) (xy -206.400243 39.6494)
				(xy -206.400243 46.050043) (xy -206.5274 46.1772) (xy -236.347 46.1772) (xy -236.347 45.339) (xy -236.347 12.3444)
				(xy -241.6556 7.0358) (xy -241.681 7.0612) (xy -255.2192 7.0612) (xy -255.2446 7.0358) (xy -255.2446 -1.397)
				(xy -236.347 -1.397) (xy -157.861 -1.397) (xy -154.686 1.778) (xy -131.191 1.778) (xy -118.364 14.605)
				(xy -118.237 14.732) (xy -118.237 15.621) (xy -118.237 21.958483) (xy -111.633 28.562483) (xy -106.895717 28.562483)
				(xy -106.299 29.1592) (xy -106.299 30.099) (xy -106.299 45.974) (xy -106.299 46.8376) (xy -106.3498 46.8884)
				(xy -148.082 46.8884)
			)
		)
		(polygon
			(pts
				(xy -210.185 35.814) (xy -210.185 40.005) (xy -235.966 40.005) (xy -235.966 35.814)
			)
		)
	)
	(zone
		(net "GND")
		(layer "B.Cu")
		(hatch none 0.5)
		(connect_pads
			(clearance 0.5)
		)
		(min_thickness 0.25)
		(fill yes
			(thermal_gap 0.5)
			(thermal_bridge_width 0.5)
			(island_removal_mode 0)
		)
		(polygon
			(pts
				(xy -390.9822 -4.2926) (xy -390.9822 5.1816) (xy -390.271 5.8928) (xy -371.729 5.8928) (xy -371.4242 5.588)
				(xy -371.4242 -4.2926)
			)
		)
	)
	(zone
		(net "P12V")
		(layer "B.Cu")
		(hatch none 0.5)
		(connect_pads
			(clearance 0.5)
		)
		(min_thickness 0.25)
		(fill yes
			(thermal_gap 0.5)
			(thermal_bridge_width 0.5)
			(island_removal_mode 0)
		)
		(polygon
			(pts
				(xy -410.6418 15.0114) (xy -411.2006 14.4526) (xy -411.2006 5.7912) (xy -410.7688 5.3594) (xy -410.7688 -4.1656)
				(xy -410.593256 -4.33832) (xy -391.69594 -4.33832) (xy -391.69594 5.33146) (xy -390.6774 6.35) (xy -390.398 6.35)
				(xy -371.348 6.35) (xy -370.84 5.842) (xy -366.964199 5.842) (xy -365.567199 4.445)
				(arc
					(start -365.567199 -2.34)
					(mid -365.07303 -3.53303)
					(end -363.880001 -4.0272)
				)
				(xy -326.6808 -4.0272) (xy -344.7161 14.0081) (xy -368.1095 14.0081) (xy -369.1128 15.0114)
			)
		)
	)
	(zone
		(layer "B.Cu")
		(hatch none 0.5)
		(connect_pads
			(clearance 0)
		)
		(min_thickness 0.25)
		(keepout
			(tracks allowed)
			(vias allowed)
			(pads allowed)
			(copperpour allowed)
			(footprints not_allowed)
		)
		(placement
			(enabled no)
			(sheetname "")
		)
		(fill
			(thermal_gap 0.5)
			(thermal_bridge_width 0.5)
			(island_removal_mode 0)
		)
		(polygon
			(pts
				(arc
					(start -295.76 23.459999)
					(mid -299.460001 27.16)
					(end -303.160001 23.459999)
				)
				(arc
					(start -303.160001 17.460001)
					(mid -299.460001 13.760001)
					(end -295.76 17.460001)
				)
			)
		)
	)
	(zone
		(layer "B.Cu")
		(hatch none 0.5)
		(connect_pads
			(clearance 0)
		)
		(min_thickness 0.25)
		(keepout
			(tracks not_allowed)
			(vias allowed)
			(pads allowed)
			(copperpour not_allowed)
			(footprints allowed)
		)
		(placement
			(enabled no)
			(sheetname "")
		)
		(fill
			(thermal_gap 0.5)
			(thermal_bridge_width 0.5)
			(island_removal_mode 0)
		)
		(polygon
			(pts
				(arc
					(start -365.160001 30.999999)
					(mid -361.460001 27.299999)
					(end -357.760001 30.999999)
				)
				(arc
					(start -357.760001 37)
					(mid -361.460001 40.7)
					(end -365.160001 37)
				)
			)
		)
	)
	(zone
		(layer "B.Cu")
		(hatch none 0.5)
		(connect_pads
			(clearance 0)
		)
		(min_thickness 0.25)
		(keepout
			(tracks allowed)
			(vias allowed)
			(pads allowed)
			(copperpour allowed)
			(footprints not_allowed)
		)
		(placement
			(enabled no)
			(sheetname "")
		)
		(fill
			(thermal_gap 0.5)
			(thermal_bridge_width 0.5)
			(island_removal_mode 0)
		)
		(polygon
			(pts
				(arc
					(start -357.760001 37)
					(mid -361.460001 40.7)
					(end -365.160001 37)
				)
				(arc
					(start -365.160001 30.999999)
					(mid -361.460001 27.299999)
					(end -357.760001 30.999999)
				)
			)
		)
	)
	(zone
		(layer "B.Cu")
		(hatch none 0.5)
		(connect_pads
			(clearance 0)
		)
		(min_thickness 0.25)
		(keepout
			(tracks not_allowed)
			(vias allowed)
			(pads allowed)
			(copperpour not_allowed)
			(footprints allowed)
		)
		(placement
			(enabled no)
			(sheetname "")
		)
		(fill
			(thermal_gap 0.5)
			(thermal_bridge_width 0.5)
			(island_removal_mode 0)
		)
		(polygon
			(pts
				(xy -73.611938 43.136012) (xy -73.611938 46.184012) (xy -72.468938 46.184012) (xy -72.468938 43.136012)
			)
		)
	)
	(zone
		(net "GND")
		(layer "B.Cu")
		(hatch none 0.5)
		(connect_pads
			(clearance 0.5)
		)
		(min_thickness 0.25)
		(fill yes
			(thermal_gap 0.5)
			(thermal_bridge_width 0.5)
			(island_removal_mode 0)
		)
		(polygon
			(pts
				(xy -105.5878 -3.8862) (xy -105.5878 19.177) (xy -105.5116 19.177) (xy -105.029 19.6596) (xy -103.8098 19.6596)
				(xy -99.2886 24.1808) (xy -72.1868 24.1808) (xy -72.0598 24.0538) (xy -72.0598 22.3266) (xy -70.155024 20.421824)
				(xy -68.1482 20.421824) (xy -65.710024 22.86) (xy -64.5668 22.86) (xy -53.2638 22.86) (xy -53.2638 22.733)
				(xy -53.2638 19.177) (xy -53.2638 -3.8862)
			)
		)
	)
	(zone
		(layer "B.Cu")
		(hatch none 0.5)
		(connect_pads
			(clearance 0)
		)
		(min_thickness 0.25)
		(keepout
			(tracks allowed)
			(vias allowed)
			(pads allowed)
			(copperpour allowed)
			(footprints not_allowed)
		)
		(placement
			(enabled no)
			(sheetname "")
		)
		(fill
			(thermal_gap 0.5)
			(thermal_bridge_width 0.5)
			(island_removal_mode 0)
		)
		(polygon
			(pts
				(arc
					(start -4.610001 32.86)
					(mid -8.310001 36.56)
					(end -12.009999 32.86)
				)
				(arc
					(start -12.009999 26.86)
					(mid -8.310001 23.160002)
					(end -4.610001 26.86)
				)
			)
		)
	)
	(zone
		(layer "B.Cu")
		(hatch none 0.5)
		(connect_pads
			(clearance 0)
		)
		(min_thickness 0.25)
		(keepout
			(tracks allowed)
			(vias allowed)
			(pads allowed)
			(copperpour allowed)
			(footprints not_allowed)
		)
		(placement
			(enabled no)
			(sheetname "")
		)
		(fill
			(thermal_gap 0.5)
			(thermal_bridge_width 0.5)
			(island_removal_mode 0)
		)
		(polygon
			(pts
				(arc
					(start -11.28 31.927897)
					(mid -8.310002 24.589998)
					(end -5.339999 31.927897)
				)
				(arc
					(start -5.339999 32.86)
					(mid -8.310001 35.830002)
					(end -11.28 32.86)
				)
			)
		)
	)
	(zone
		(layer "B.Cu")
		(hatch none 0.5)
		(connect_pads
			(clearance 0)
		)
		(min_thickness 0.25)
		(keepout
			(tracks not_allowed)
			(vias allowed)
			(pads allowed)
			(copperpour not_allowed)
			(footprints allowed)
		)
		(placement
			(enabled no)
			(sheetname "")
		)
		(fill
			(thermal_gap 0.5)
			(thermal_bridge_width 0.5)
			(island_removal_mode 0)
		)
		(polygon
			(pts
				(xy -294.611938 43.136012) (xy -294.611938 46.184012) (xy -293.468938 46.184012) (xy -293.468938 43.136012)
			)
		)
	)
	(zone
		(layers "B.Cu" "In1.Cu" "In2.Cu" "In3.Cu" "In4.Cu" "In5.Cu" "In6.Cu")
		(hatch none 0.5)
		(connect_pads
			(clearance 0)
		)
		(min_thickness 0.25)
		(keepout
			(tracks not_allowed)
			(vias allowed)
			(pads allowed)
			(copperpour not_allowed)
			(footprints allowed)
		)
		(placement
			(enabled no)
			(sheetname "")
		)
		(fill yes
			(thermal_gap 0.5)
			(thermal_bridge_width 0.5)
			(island_removal_mode 0)
		)
		(polygon
			(pts
				(xy -172.031937 46.084005) (xy -170.888937 46.084005) (xy -170.888937 43.036005) (xy -172.031937 43.036005)
			)
		)
	)
	(zone
		(layers "B.Cu" "In1.Cu" "In2.Cu" "In3.Cu" "In4.Cu" "In5.Cu" "In6.Cu")
		(hatch none 0.5)
		(connect_pads
			(clearance 0)
		)
		(min_thickness 0.25)
		(keepout
			(tracks not_allowed)
			(vias allowed)
			(pads allowed)
			(copperpour not_allowed)
			(footprints allowed)
		)
		(placement
			(enabled no)
			(sheetname "")
		)
		(fill yes
			(thermal_gap 0.5)
			(thermal_bridge_width 0.5)
			(island_removal_mode 0)
		)
		(polygon
			(pts
				(xy -401.031936 46.084005) (xy -399.888936 46.084005) (xy -399.888936 43.036005) (xy -401.031936 43.036005)
			)
		)
	)
	(zone
		(layers "B.Cu" "In1.Cu" "In2.Cu" "In3.Cu" "In4.Cu" "In5.Cu" "In6.Cu")
		(hatch none 0.5)
		(connect_pads
			(clearance 0)
		)
		(min_thickness 0.25)
		(keepout
			(tracks not_allowed)
			(vias allowed)
			(pads allowed)
			(copperpour not_allowed)
			(footprints allowed)
		)
		(placement
			(enabled no)
			(sheetname "")
		)
		(fill yes
			(thermal_gap 0.5)
			(thermal_bridge_width 0.5)
			(island_removal_mode 0)
		)
		(polygon
			(pts
				(xy -178.031938 44.784005) (xy -176.888938 44.784005) (xy -176.888938 41.736005) (xy -178.031938 41.736005)
			)
		)
	)
	(zone
		(layers "B.Cu" "In1.Cu" "In2.Cu" "In3.Cu" "In4.Cu" "In5.Cu" "In6.Cu")
		(hatch none 0.5)
		(connect_pads
			(clearance 0)
		)
		(min_thickness 0.25)
		(keepout
			(tracks not_allowed)
			(vias allowed)
			(pads allowed)
			(copperpour not_allowed)
			(footprints allowed)
		)
		(placement
			(enabled no)
			(sheetname "")
		)
		(fill yes
			(thermal_gap 0.5)
			(thermal_bridge_width 0.5)
			(island_removal_mode 0)
		)
		(polygon
			(pts
				(xy -184.031936 46.084005) (xy -182.888936 46.084005) (xy -182.888936 43.036005) (xy -184.031936 43.036005)
			)
		)
	)
	(zone
		(layers "B.Cu" "In1.Cu" "In2.Cu" "In3.Cu" "In4.Cu" "In5.Cu" "In6.Cu")
		(hatch none 0.5)
		(connect_pads
			(clearance 0)
		)
		(min_thickness 0.25)
		(keepout
			(tracks not_allowed)
			(vias allowed)
			(pads allowed)
			(copperpour not_allowed)
			(footprints allowed)
		)
		(placement
			(enabled no)
			(sheetname "")
		)
		(fill yes
			(thermal_gap 0.5)
			(thermal_bridge_width 0.5)
			(island_removal_mode 0)
		)
		(polygon
			(pts
				(xy -397.031936 46.084005) (xy -395.888936 46.084005) (xy -395.888936 43.036005) (xy -397.031936 43.036005)
			)
		)
	)
	(zone
		(layers "B.Cu" "In1.Cu" "In2.Cu" "In3.Cu" "In4.Cu" "In5.Cu" "In6.Cu")
		(hatch none 0.5)
		(connect_pads
			(clearance 0)
		)
		(min_thickness 0.25)
		(keepout
			(tracks not_allowed)
			(vias allowed)
			(pads allowed)
			(copperpour not_allowed)
			(footprints allowed)
		)
		(placement
			(enabled no)
			(sheetname "")
		)
		(fill yes
			(thermal_gap 0.5)
			(thermal_bridge_width 0.5)
			(island_removal_mode 0)
		)
		(polygon
			(pts
				(xy -174.031938 44.784005) (xy -172.888938 44.784005) (xy -172.888938 41.736005) (xy -174.031938 41.736005)
			)
		)
	)
	(zone
		(layers "B.Cu" "In1.Cu" "In2.Cu" "In3.Cu" "In4.Cu" "In5.Cu" "In6.Cu")
		(hatch none 0.5)
		(connect_pads
			(clearance 0)
		)
		(min_thickness 0.25)
		(keepout
			(tracks not_allowed)
			(vias allowed)
			(pads allowed)
			(copperpour not_allowed)
			(footprints allowed)
		)
		(placement
			(enabled no)
			(sheetname "")
		)
		(fill yes
			(thermal_gap 0.5)
			(thermal_bridge_width 0.5)
			(island_removal_mode 0)
		)
		(polygon
			(pts
				(xy -407.031937 44.784005) (xy -405.888937 44.784005) (xy -405.888937 41.736005) (xy -407.031937 41.736005)
			)
		)
	)
	(zone
		(layers "B.Cu" "In1.Cu" "In2.Cu" "In3.Cu" "In4.Cu" "In5.Cu" "In6.Cu")
		(hatch none 0.5)
		(connect_pads
			(clearance 0)
		)
		(min_thickness 0.25)
		(keepout
			(tracks not_allowed)
			(vias allowed)
			(pads allowed)
			(copperpour not_allowed)
			(footprints allowed)
		)
		(placement
			(enabled no)
			(sheetname "")
		)
		(fill yes
			(thermal_gap 0.5)
			(thermal_bridge_width 0.5)
			(island_removal_mode 0)
		)
		(polygon
			(pts
				(xy -281.0891 37.2999) (xy -281.0891 35.0139) (xy -280.8351 34.7599) (xy -279.4635 34.7599) (xy -279.2095 35.0139)
				(xy -279.2095 37.2999) (xy -279.4635 37.5539) (xy -280.8351 37.5539)
			)
		)
	)
	(zone
		(layers "B.Cu" "In1.Cu" "In2.Cu" "In3.Cu" "In4.Cu" "In5.Cu" "In6.Cu")
		(hatch none 0.5)
		(connect_pads
			(clearance 0)
		)
		(min_thickness 0.25)
		(keepout
			(tracks not_allowed)
			(vias allowed)
			(pads allowed)
			(copperpour not_allowed)
			(footprints allowed)
		)
		(placement
			(enabled no)
			(sheetname "")
		)
		(fill yes
			(thermal_gap 0.5)
			(thermal_bridge_width 0.5)
			(island_removal_mode 0)
		)
		(polygon
			(pts
				(xy -188.031935 46.084005) (xy -186.888935 46.084005) (xy -186.888935 43.036005) (xy -188.031935 43.036005)
			)
		)
	)
	(zone
		(layers "B.Cu" "In1.Cu" "In2.Cu" "In3.Cu" "In4.Cu" "In5.Cu" "In6.Cu")
		(hatch none 0.5)
		(connect_pads
			(clearance 0)
		)
		(min_thickness 0.25)
		(keepout
			(tracks not_allowed)
			(vias allowed)
			(pads allowed)
			(copperpour not_allowed)
			(footprints allowed)
		)
		(placement
			(enabled no)
			(sheetname "")
		)
		(fill yes
			(thermal_gap 0.5)
			(thermal_bridge_width 0.5)
			(island_removal_mode 0)
		)
		(polygon
			(pts
				(xy -176.031936 46.084005) (xy -174.888936 46.084005) (xy -174.888936 43.036005) (xy -176.031936 43.036005)
			)
		)
	)
	(zone
		(layers "B.Cu" "In1.Cu" "In2.Cu" "In3.Cu" "In4.Cu" "In5.Cu" "In6.Cu")
		(hatch none 0.5)
		(connect_pads
			(clearance 0)
		)
		(min_thickness 0.25)
		(keepout
			(tracks not_allowed)
			(vias allowed)
			(pads allowed)
			(copperpour not_allowed)
			(footprints allowed)
		)
		(placement
			(enabled no)
			(sheetname "")
		)
		(fill yes
			(thermal_gap 0.5)
			(thermal_bridge_width 0.5)
			(island_removal_mode 0)
		)
		(polygon
			(pts
				(xy -182.031937 44.784005) (xy -180.888937 44.784005) (xy -180.888937 41.736005) (xy -182.031937 41.736005)
			)
		)
	)
	(zone
		(layers "B.Cu" "In1.Cu" "In2.Cu" "In3.Cu" "In4.Cu" "In5.Cu" "In6.Cu")
		(hatch none 0.5)
		(connect_pads
			(clearance 0)
		)
		(min_thickness 0.25)
		(keepout
			(tracks not_allowed)
			(vias allowed)
			(pads allowed)
			(copperpour not_allowed)
			(footprints allowed)
		)
		(placement
			(enabled no)
			(sheetname "")
		)
		(fill yes
			(thermal_gap 0.5)
			(thermal_bridge_width 0.5)
			(island_removal_mode 0)
		)
		(polygon
			(pts
				(xy -180.031936 46.084005) (xy -178.888936 46.084005) (xy -178.888936 43.036005) (xy -180.031936 43.036005)
			)
		)
	)
	(zone
		(layers "B.Cu" "In1.Cu" "In2.Cu" "In3.Cu" "In4.Cu" "In5.Cu" "In6.Cu")
		(hatch none 0.5)
		(connect_pads
			(clearance 0)
		)
		(min_thickness 0.25)
		(keepout
			(tracks not_allowed)
			(vias allowed)
			(pads allowed)
			(copperpour not_allowed)
			(footprints allowed)
		)
		(placement
			(enabled no)
			(sheetname "")
		)
		(fill yes
			(thermal_gap 0.5)
			(thermal_bridge_width 0.5)
			(island_removal_mode 0)
		)
		(polygon
			(pts
				(xy -403.031937 44.784005) (xy -401.888937 44.784005) (xy -401.888937 41.736005) (xy -403.031937 41.736005)
			)
		)
	)
	(zone
		(layers "B.Cu" "In1.Cu" "In2.Cu" "In3.Cu" "In4.Cu" "In5.Cu" "In6.Cu")
		(hatch none 0.5)
		(connect_pads
			(clearance 0)
		)
		(min_thickness 0.25)
		(keepout
			(tracks not_allowed)
			(vias allowed)
			(pads allowed)
			(copperpour not_allowed)
			(footprints allowed)
		)
		(placement
			(enabled no)
			(sheetname "")
		)
		(fill yes
			(thermal_gap 0.5)
			(thermal_bridge_width 0.5)
			(island_removal_mode 0)
		)
		(polygon
			(pts
				(xy -395.031938 44.784005) (xy -393.888938 44.784005) (xy -393.888938 41.736005) (xy -395.031938 41.736005)
			)
		)
	)
	(zone
		(layers "B.Cu" "In1.Cu" "In2.Cu" "In3.Cu" "In4.Cu" "In5.Cu" "In6.Cu")
		(hatch none 0.5)
		(connect_pads
			(clearance 0)
		)
		(min_thickness 0.25)
		(keepout
			(tracks not_allowed)
			(vias allowed)
			(pads allowed)
			(copperpour not_allowed)
			(footprints allowed)
		)
		(placement
			(enabled no)
			(sheetname "")
		)
		(fill yes
			(thermal_gap 0.5)
			(thermal_bridge_width 0.5)
			(island_removal_mode 0)
		)
		(polygon
			(pts
				(xy -186.031937 44.784005) (xy -184.888937 44.784005) (xy -184.888937 41.736005) (xy -186.031937 41.736005)
			)
		)
	)
	(zone
		(layers "B.Cu" "In1.Cu" "In2.Cu" "In3.Cu" "In4.Cu" "In5.Cu" "In6.Cu")
		(hatch none 0.5)
		(connect_pads
			(clearance 0)
		)
		(min_thickness 0.25)
		(keepout
			(tracks not_allowed)
			(vias allowed)
			(pads allowed)
			(copperpour not_allowed)
			(footprints allowed)
		)
		(placement
			(enabled no)
			(sheetname "")
		)
		(fill yes
			(thermal_gap 0.5)
			(thermal_bridge_width 0.5)
			(island_removal_mode 0)
		)
		(polygon
			(pts
				(xy -64.889101 37.2999) (xy -64.889101 35.0139) (xy -64.635101 34.7599) (xy -63.263501 34.7599)
				(xy -63.009501 35.0139) (xy -63.009501 37.2999) (xy -63.263501 37.5539) (xy -64.635101 37.5539)
			)
		)
	)
	(zone
		(layers "B.Cu" "In1.Cu" "In2.Cu" "In3.Cu" "In4.Cu" "In5.Cu" "In6.Cu")
		(hatch none 0.5)
		(connect_pads
			(clearance 0)
		)
		(min_thickness 0.25)
		(keepout
			(tracks not_allowed)
			(vias allowed)
			(pads allowed)
			(copperpour not_allowed)
			(footprints allowed)
		)
		(placement
			(enabled no)
			(sheetname "")
		)
		(fill yes
			(thermal_gap 0.5)
			(thermal_bridge_width 0.5)
			(island_removal_mode 0)
		)
		(polygon
			(pts
				(xy -60.0891 37.2999) (xy -60.0891 35.0139) (xy -59.8351 34.7599) (xy -58.4635 34.7599) (xy -58.2095 35.0139)
				(xy -58.2095 37.2999) (xy -58.4635 37.5539) (xy -59.8351 37.5539)
			)
		)
	)
	(zone
		(layers "B.Cu" "In1.Cu" "In2.Cu" "In3.Cu" "In4.Cu" "In5.Cu" "In6.Cu")
		(hatch none 0.5)
		(connect_pads
			(clearance 0)
		)
		(min_thickness 0.25)
		(keepout
			(tracks not_allowed)
			(vias allowed)
			(pads allowed)
			(copperpour not_allowed)
			(footprints allowed)
		)
		(placement
			(enabled no)
			(sheetname "")
		)
		(fill yes
			(thermal_gap 0.5)
			(thermal_bridge_width 0.5)
			(island_removal_mode 0)
		)
		(polygon
			(pts
				(xy -285.889101 37.2999) (xy -285.889101 35.0139) (xy -285.635101 34.7599) (xy -284.263501 34.7599)
				(xy -284.009501 35.0139) (xy -284.009501 37.2999) (xy -284.263501 37.5539) (xy -285.635101 37.5539)
			)
		)
	)
	(zone
		(layers "B.Cu" "In1.Cu" "In2.Cu" "In3.Cu" "In4.Cu" "In5.Cu" "In6.Cu")
		(hatch none 0.5)
		(connect_pads
			(clearance 0)
		)
		(min_thickness 0.25)
		(keepout
			(tracks not_allowed)
			(vias allowed)
			(pads allowed)
			(copperpour not_allowed)
			(footprints allowed)
		)
		(placement
			(enabled no)
			(sheetname "")
		)
		(fill yes
			(thermal_gap 0.5)
			(thermal_bridge_width 0.5)
			(island_removal_mode 0)
		)
		(polygon
			(pts
				(xy -393.031937 46.084005) (xy -391.888937 46.084005) (xy -391.888937 43.036005) (xy -393.031937 43.036005)
			)
		)
	)
	(zone
		(layers "B.Cu" "In1.Cu" "In2.Cu" "In3.Cu" "In4.Cu" "In5.Cu" "In6.Cu")
		(hatch none 0.5)
		(connect_pads
			(clearance 0)
		)
		(min_thickness 0.25)
		(keepout
			(tracks not_allowed)
			(vias allowed)
			(pads allowed)
			(copperpour not_allowed)
			(footprints allowed)
		)
		(placement
			(enabled no)
			(sheetname "")
		)
		(fill yes
			(thermal_gap 0.5)
			(thermal_bridge_width 0.5)
			(island_removal_mode 0)
		)
		(polygon
			(pts
				(xy -409.031935 46.084005) (xy -407.888935 46.084005) (xy -407.888935 43.036005) (xy -409.031935 43.036005)
			)
		)
	)
	(zone
		(layers "B.Cu" "In1.Cu" "In2.Cu" "In3.Cu" "In4.Cu" "In5.Cu" "In6.Cu")
		(hatch none 0.5)
		(connect_pads
			(clearance 0)
		)
		(min_thickness 0.25)
		(keepout
			(tracks not_allowed)
			(vias allowed)
			(pads allowed)
			(copperpour not_allowed)
			(footprints allowed)
		)
		(placement
			(enabled no)
			(sheetname "")
		)
		(fill yes
			(thermal_gap 0.5)
			(thermal_bridge_width 0.5)
			(island_removal_mode 0)
		)
		(polygon
			(pts
				(xy -405.031936 46.084005) (xy -403.888936 46.084005) (xy -403.888936 43.036005) (xy -405.031936 43.036005)
			)
		)
	)
	(zone
		(layers "B.Cu" "In1.Cu" "In2.Cu" "In3.Cu" "In4.Cu" "In5.Cu" "In6.Cu")
		(hatch none 0.5)
		(connect_pads
			(clearance 0)
		)
		(min_thickness 0.25)
		(keepout
			(tracks not_allowed)
			(vias allowed)
			(pads allowed)
			(copperpour not_allowed)
			(footprints allowed)
		)
		(placement
			(enabled no)
			(sheetname "")
		)
		(fill yes
			(thermal_gap 0.5)
			(thermal_bridge_width 0.5)
			(island_removal_mode 0)
		)
		(polygon
			(pts
				(xy -399.031938 44.784005) (xy -397.888938 44.784005) (xy -397.888938 41.736005) (xy -399.031938 41.736005)
			)
		)
	)
	(zone
		(layers "B.Cu" "In1.Cu" "In2.Cu" "In3.Cu" "In4.Cu" "In6.Cu")
		(hatch none 0.5)
		(connect_pads
			(clearance 0)
		)
		(min_thickness 0.25)
		(keepout
			(tracks not_allowed)
			(vias allowed)
			(pads allowed)
			(copperpour not_allowed)
			(footprints allowed)
		)
		(placement
			(enabled no)
			(sheetname "")
		)
		(fill yes
			(thermal_gap 0.5)
			(thermal_bridge_width 0.5)
			(island_removal_mode 0)
		)
		(polygon
			(pts
				(xy -150.67566 32.23006) (xy -149.86286 32.23006) (xy -149.86286 30.96006) (xy -150.67566 30.96006)
			)
		)
	)
	(zone
		(layers "B.Cu" "In1.Cu" "In2.Cu" "In3.Cu" "In4.Cu" "In6.Cu")
		(hatch none 0.5)
		(connect_pads
			(clearance 0)
		)
		(min_thickness 0.25)
		(keepout
			(tracks not_allowed)
			(vias allowed)
			(pads allowed)
			(copperpour not_allowed)
			(footprints allowed)
		)
		(placement
			(enabled no)
			(sheetname "")
		)
		(fill yes
			(thermal_gap 0.5)
			(thermal_bridge_width 0.5)
			(island_removal_mode 0)
		)
		(polygon
			(pts
				(xy -150.67566 37.31006) (xy -149.86286 37.31006) (xy -149.86286 36.04006) (xy -150.67566 36.04006)
			)
		)
	)
	(zone
		(layers "B.Cu" "In1.Cu" "In2.Cu" "In3.Cu" "In4.Cu" "In6.Cu")
		(hatch none 0.5)
		(connect_pads
			(clearance 0)
		)
		(min_thickness 0.25)
		(keepout
			(tracks not_allowed)
			(vias allowed)
			(pads allowed)
			(copperpour not_allowed)
			(footprints allowed)
		)
		(placement
			(enabled no)
			(sheetname "")
		)
		(fill yes
			(thermal_gap 0.5)
			(thermal_bridge_width 0.5)
			(island_removal_mode 0)
		)
		(polygon
			(pts
				(xy -150.67566 27.15006) (xy -149.86286 27.15006) (xy -149.86286 25.88006) (xy -150.67566 25.88006)
			)
		)
	)
	(zone
		(layers "B.Cu" "In1.Cu" "In2.Cu" "In3.Cu" "In4.Cu" "In6.Cu")
		(hatch none 0.5)
		(connect_pads
			(clearance 0)
		)
		(min_thickness 0.25)
		(keepout
			(tracks not_allowed)
			(vias allowed)
			(pads allowed)
			(copperpour not_allowed)
			(footprints allowed)
		)
		(placement
			(enabled no)
			(sheetname "")
		)
		(fill yes
			(thermal_gap 0.5)
			(thermal_bridge_width 0.5)
			(island_removal_mode 0)
		)
		(polygon
			(pts
				(xy -371.67566 32.23006) (xy -370.86286 32.23006) (xy -370.86286 30.96006) (xy -371.67566 30.96006)
			)
		)
	)
	(zone
		(layers "B.Cu" "In1.Cu" "In2.Cu" "In3.Cu" "In4.Cu" "In6.Cu")
		(hatch none 0.5)
		(connect_pads
			(clearance 0)
		)
		(min_thickness 0.25)
		(keepout
			(tracks not_allowed)
			(vias allowed)
			(pads allowed)
			(copperpour not_allowed)
			(footprints allowed)
		)
		(placement
			(enabled no)
			(sheetname "")
		)
		(fill yes
			(thermal_gap 0.5)
			(thermal_bridge_width 0.5)
			(island_removal_mode 0)
		)
		(polygon
			(pts
				(xy -151.94566 29.69006) (xy -151.13286 29.69006) (xy -151.13286 28.42006) (xy -151.94566 28.42006)
			)
		)
	)
	(zone
		(layers "B.Cu" "In1.Cu" "In2.Cu" "In3.Cu" "In4.Cu" "In6.Cu")
		(hatch none 0.5)
		(connect_pads
			(clearance 0)
		)
		(min_thickness 0.25)
		(keepout
			(tracks not_allowed)
			(vias allowed)
			(pads allowed)
			(copperpour not_allowed)
			(footprints allowed)
		)
		(placement
			(enabled no)
			(sheetname "")
		)
		(fill yes
			(thermal_gap 0.5)
			(thermal_bridge_width 0.5)
			(island_removal_mode 0)
		)
		(polygon
			(pts
				(xy -371.67566 22.07006) (xy -370.86286 22.07006) (xy -370.86286 20.80006) (xy -371.67566 20.80006)
			)
		)
	)
	(zone
		(layers "B.Cu" "In1.Cu" "In2.Cu" "In3.Cu" "In4.Cu" "In6.Cu")
		(hatch none 0.5)
		(connect_pads
			(clearance 0)
		)
		(min_thickness 0.25)
		(keepout
			(tracks not_allowed)
			(vias allowed)
			(pads allowed)
			(copperpour not_allowed)
			(footprints allowed)
		)
		(placement
			(enabled no)
			(sheetname "")
		)
		(fill yes
			(thermal_gap 0.5)
			(thermal_bridge_width 0.5)
			(island_removal_mode 0)
		)
		(polygon
			(pts
				(xy -372.94566 24.61006) (xy -372.13286 24.61006) (xy -372.13286 23.34006) (xy -372.94566 23.34006)
			)
		)
	)
	(zone
		(layers "B.Cu" "In1.Cu" "In2.Cu" "In3.Cu" "In4.Cu" "In6.Cu")
		(hatch none 0.5)
		(connect_pads
			(clearance 0)
		)
		(min_thickness 0.25)
		(keepout
			(tracks not_allowed)
			(vias allowed)
			(pads allowed)
			(copperpour not_allowed)
			(footprints allowed)
		)
		(placement
			(enabled no)
			(sheetname "")
		)
		(fill yes
			(thermal_gap 0.5)
			(thermal_bridge_width 0.5)
			(island_removal_mode 0)
		)
		(polygon
			(pts
				(xy -151.94566 39.85006) (xy -151.13286 39.85006) (xy -151.13286 38.58006) (xy -151.94566 38.58006)
			)
		)
	)
	(zone
		(layers "B.Cu" "In1.Cu" "In2.Cu" "In3.Cu" "In4.Cu" "In6.Cu")
		(hatch none 0.5)
		(connect_pads
			(clearance 0)
		)
		(min_thickness 0.25)
		(keepout
			(tracks not_allowed)
			(vias allowed)
			(pads allowed)
			(copperpour not_allowed)
			(footprints allowed)
		)
		(placement
			(enabled no)
			(sheetname "")
		)
		(fill yes
			(thermal_gap 0.5)
			(thermal_bridge_width 0.5)
			(island_removal_mode 0)
		)
		(polygon
			(pts
				(xy -371.67566 42.39006) (xy -370.86286 42.39006) (xy -370.86286 41.12006) (xy -371.67566 41.12006)
			)
		)
	)
	(zone
		(layers "B.Cu" "In1.Cu" "In2.Cu" "In3.Cu" "In4.Cu" "In6.Cu")
		(hatch none 0.5)
		(connect_pads
			(clearance 0)
		)
		(min_thickness 0.25)
		(keepout
			(tracks not_allowed)
			(vias allowed)
			(pads allowed)
			(copperpour not_allowed)
			(footprints allowed)
		)
		(placement
			(enabled no)
			(sheetname "")
		)
		(fill yes
			(thermal_gap 0.5)
			(thermal_bridge_width 0.5)
			(island_removal_mode 0)
		)
		(polygon
			(pts
				(xy -151.94566 34.77006) (xy -151.13286 34.77006) (xy -151.13286 33.50006) (xy -151.94566 33.50006)
			)
		)
	)
	(zone
		(layers "B.Cu" "In1.Cu" "In2.Cu" "In3.Cu" "In4.Cu" "In6.Cu")
		(hatch none 0.5)
		(connect_pads
			(clearance 0)
		)
		(min_thickness 0.25)
		(keepout
			(tracks not_allowed)
			(vias allowed)
			(pads allowed)
			(copperpour not_allowed)
			(footprints allowed)
		)
		(placement
			(enabled no)
			(sheetname "")
		)
		(fill yes
			(thermal_gap 0.5)
			(thermal_bridge_width 0.5)
			(island_removal_mode 0)
		)
		(polygon
			(pts
				(xy -371.67566 27.15006) (xy -370.86286 27.15006) (xy -370.86286 25.88006) (xy -371.67566 25.88006)
			)
		)
	)
	(zone
		(layers "B.Cu" "In1.Cu" "In2.Cu" "In3.Cu" "In4.Cu" "In6.Cu")
		(hatch none 0.5)
		(connect_pads
			(clearance 0)
		)
		(min_thickness 0.25)
		(keepout
			(tracks not_allowed)
			(vias allowed)
			(pads allowed)
			(copperpour not_allowed)
			(footprints allowed)
		)
		(placement
			(enabled no)
			(sheetname "")
		)
		(fill yes
			(thermal_gap 0.5)
			(thermal_bridge_width 0.5)
			(island_removal_mode 0)
		)
		(polygon
			(pts
				(xy -372.94566 34.77006) (xy -372.13286 34.77006) (xy -372.13286 33.50006) (xy -372.94566 33.50006)
			)
		)
	)
	(zone
		(layers "B.Cu" "In1.Cu" "In2.Cu" "In3.Cu" "In4.Cu" "In6.Cu")
		(hatch none 0.5)
		(connect_pads
			(clearance 0)
		)
		(min_thickness 0.25)
		(keepout
			(tracks not_allowed)
			(vias allowed)
			(pads allowed)
			(copperpour not_allowed)
			(footprints allowed)
		)
		(placement
			(enabled no)
			(sheetname "")
		)
		(fill yes
			(thermal_gap 0.5)
			(thermal_bridge_width 0.5)
			(island_removal_mode 0)
		)
		(polygon
			(pts
				(xy -372.94566 29.69006) (xy -372.13286 29.69006) (xy -372.13286 28.42006) (xy -372.94566 28.42006)
			)
		)
	)
	(zone
		(layers "B.Cu" "In1.Cu" "In2.Cu" "In3.Cu" "In4.Cu" "In6.Cu")
		(hatch none 0.5)
		(connect_pads
			(clearance 0)
		)
		(min_thickness 0.25)
		(keepout
			(tracks not_allowed)
			(vias allowed)
			(pads allowed)
			(copperpour not_allowed)
			(footprints allowed)
		)
		(placement
			(enabled no)
			(sheetname "")
		)
		(fill yes
			(thermal_gap 0.5)
			(thermal_bridge_width 0.5)
			(island_removal_mode 0)
		)
		(polygon
			(pts
				(xy -151.94566 24.61006) (xy -151.13286 24.61006) (xy -151.13286 23.34006) (xy -151.94566 23.34006)
			)
		)
	)
	(zone
		(layers "B.Cu" "In1.Cu" "In2.Cu" "In3.Cu" "In4.Cu" "In6.Cu")
		(hatch none 0.5)
		(connect_pads
			(clearance 0)
		)
		(min_thickness 0.25)
		(keepout
			(tracks not_allowed)
			(vias allowed)
			(pads allowed)
			(copperpour not_allowed)
			(footprints allowed)
		)
		(placement
			(enabled no)
			(sheetname "")
		)
		(fill yes
			(thermal_gap 0.5)
			(thermal_bridge_width 0.5)
			(island_removal_mode 0)
		)
		(polygon
			(pts
				(xy -150.67566 42.39006) (xy -149.86286 42.39006) (xy -149.86286 41.12006) (xy -150.67566 41.12006)
			)
		)
	)
	(zone
		(layers "B.Cu" "In1.Cu" "In2.Cu" "In3.Cu" "In4.Cu" "In6.Cu")
		(hatch none 0.5)
		(connect_pads
			(clearance 0)
		)
		(min_thickness 0.25)
		(keepout
			(tracks not_allowed)
			(vias allowed)
			(pads allowed)
			(copperpour not_allowed)
			(footprints allowed)
		)
		(placement
			(enabled no)
			(sheetname "")
		)
		(fill yes
			(thermal_gap 0.5)
			(thermal_bridge_width 0.5)
			(island_removal_mode 0)
		)
		(polygon
			(pts
				(xy -150.67566 22.07006) (xy -149.86286 22.07006) (xy -149.86286 20.80006) (xy -150.67566 20.80006)
			)
		)
	)
	(zone
		(layers "B.Cu" "In1.Cu" "In2.Cu" "In3.Cu" "In4.Cu" "In6.Cu")
		(hatch none 0.5)
		(connect_pads
			(clearance 0)
		)
		(min_thickness 0.25)
		(keepout
			(tracks not_allowed)
			(vias allowed)
			(pads allowed)
			(copperpour not_allowed)
			(footprints allowed)
		)
		(placement
			(enabled no)
			(sheetname "")
		)
		(fill yes
			(thermal_gap 0.5)
			(thermal_bridge_width 0.5)
			(island_removal_mode 0)
		)
		(polygon
			(pts
				(xy -371.67566 37.31006) (xy -370.86286 37.31006) (xy -370.86286 36.04006) (xy -371.67566 36.04006)
			)
		)
	)
	(zone
		(layers "B.Cu" "In1.Cu" "In2.Cu" "In3.Cu" "In4.Cu" "In6.Cu")
		(hatch none 0.5)
		(connect_pads
			(clearance 0)
		)
		(min_thickness 0.25)
		(keepout
			(tracks not_allowed)
			(vias allowed)
			(pads allowed)
			(copperpour not_allowed)
			(footprints allowed)
		)
		(placement
			(enabled no)
			(sheetname "")
		)
		(fill yes
			(thermal_gap 0.5)
			(thermal_bridge_width 0.5)
			(island_removal_mode 0)
		)
		(polygon
			(pts
				(xy -372.94566 39.85006) (xy -372.13286 39.85006) (xy -372.13286 38.58006) (xy -372.94566 38.58006)
			)
		)
	)
	(zone
		(layers "B.Cu" "In1.Cu" "In3.Cu" "In4.Cu" "In5.Cu" "In6.Cu")
		(hatch none 0.5)
		(connect_pads
			(clearance 0)
		)
		(min_thickness 0.25)
		(keepout
			(tracks not_allowed)
			(vias allowed)
			(pads allowed)
			(copperpour not_allowed)
			(footprints allowed)
		)
		(placement
			(enabled no)
			(sheetname "")
		)
		(fill yes
			(thermal_gap 0.5)
			(thermal_bridge_width 0.5)
			(island_removal_mode 0)
		)
		(polygon
			(pts
				(xy -157.02566 39.85006) (xy -156.21286 39.85006) (xy -156.21286 38.58006) (xy -157.02566 38.58006)
			)
		)
	)
	(zone
		(layers "B.Cu" "In1.Cu" "In3.Cu" "In4.Cu" "In5.Cu" "In6.Cu")
		(hatch none 0.5)
		(connect_pads
			(clearance 0)
		)
		(min_thickness 0.25)
		(keepout
			(tracks not_allowed)
			(vias allowed)
			(pads allowed)
			(copperpour not_allowed)
			(footprints allowed)
		)
		(placement
			(enabled no)
			(sheetname "")
		)
		(fill yes
			(thermal_gap 0.5)
			(thermal_bridge_width 0.5)
			(island_removal_mode 0)
		)
		(polygon
			(pts
				(xy -378.02566 34.77006) (xy -377.21286 34.77006) (xy -377.21286 33.50006) (xy -378.02566 33.50006)
			)
		)
	)
	(zone
		(layers "B.Cu" "In1.Cu" "In3.Cu" "In4.Cu" "In5.Cu" "In6.Cu")
		(hatch none 0.5)
		(connect_pads
			(clearance 0)
		)
		(min_thickness 0.25)
		(keepout
			(tracks not_allowed)
			(vias allowed)
			(pads allowed)
			(copperpour not_allowed)
			(footprints allowed)
		)
		(placement
			(enabled no)
			(sheetname "")
		)
		(fill yes
			(thermal_gap 0.5)
			(thermal_bridge_width 0.5)
			(island_removal_mode 0)
		)
		(polygon
			(pts
				(xy -155.75566 27.15006) (xy -154.94286 27.15006) (xy -154.94286 25.88006) (xy -155.75566 25.88006)
			)
		)
	)
	(zone
		(layers "B.Cu" "In1.Cu" "In3.Cu" "In4.Cu" "In5.Cu" "In6.Cu")
		(hatch none 0.5)
		(connect_pads
			(clearance 0)
		)
		(min_thickness 0.25)
		(keepout
			(tracks not_allowed)
			(vias allowed)
			(pads allowed)
			(copperpour not_allowed)
			(footprints allowed)
		)
		(placement
			(enabled no)
			(sheetname "")
		)
		(fill yes
			(thermal_gap 0.5)
			(thermal_bridge_width 0.5)
			(island_removal_mode 0)
		)
		(polygon
			(pts
				(xy -378.02566 24.61006) (xy -377.21286 24.61006) (xy -377.21286 23.34006) (xy -378.02566 23.34006)
			)
		)
	)
	(zone
		(layers "B.Cu" "In1.Cu" "In3.Cu" "In4.Cu" "In5.Cu" "In6.Cu")
		(hatch none 0.5)
		(connect_pads
			(clearance 0)
		)
		(min_thickness 0.25)
		(keepout
			(tracks not_allowed)
			(vias allowed)
			(pads allowed)
			(copperpour not_allowed)
			(footprints allowed)
		)
		(placement
			(enabled no)
			(sheetname "")
		)
		(fill yes
			(thermal_gap 0.5)
			(thermal_bridge_width 0.5)
			(island_removal_mode 0)
		)
		(polygon
			(pts
				(xy -378.02566 39.85006) (xy -377.21286 39.85006) (xy -377.21286 38.58006) (xy -378.02566 38.58006)
			)
		)
	)
	(zone
		(layers "B.Cu" "In1.Cu" "In3.Cu" "In4.Cu" "In5.Cu" "In6.Cu")
		(hatch none 0.5)
		(connect_pads
			(clearance 0)
		)
		(min_thickness 0.25)
		(keepout
			(tracks not_allowed)
			(vias allowed)
			(pads allowed)
			(copperpour not_allowed)
			(footprints allowed)
		)
		(placement
			(enabled no)
			(sheetname "")
		)
		(fill yes
			(thermal_gap 0.5)
			(thermal_bridge_width 0.5)
			(island_removal_mode 0)
		)
		(polygon
			(pts
				(xy -155.75566 22.07006) (xy -154.94286 22.07006) (xy -154.94286 20.80006) (xy -155.75566 20.80006)
			)
		)
	)
	(zone
		(layers "B.Cu" "In1.Cu" "In3.Cu" "In4.Cu" "In5.Cu" "In6.Cu")
		(hatch none 0.5)
		(connect_pads
			(clearance 0)
		)
		(min_thickness 0.25)
		(keepout
			(tracks not_allowed)
			(vias allowed)
			(pads allowed)
			(copperpour not_allowed)
			(footprints allowed)
		)
		(placement
			(enabled no)
			(sheetname "")
		)
		(fill yes
			(thermal_gap 0.5)
			(thermal_bridge_width 0.5)
			(island_removal_mode 0)
		)
		(polygon
			(pts
				(xy -376.75566 27.15006) (xy -375.94286 27.15006) (xy -375.94286 25.88006) (xy -376.75566 25.88006)
			)
		)
	)
	(zone
		(layers "B.Cu" "In1.Cu" "In3.Cu" "In4.Cu" "In5.Cu" "In6.Cu")
		(hatch none 0.5)
		(connect_pads
			(clearance 0)
		)
		(min_thickness 0.25)
		(keepout
			(tracks not_allowed)
			(vias allowed)
			(pads allowed)
			(copperpour not_allowed)
			(footprints allowed)
		)
		(placement
			(enabled no)
			(sheetname "")
		)
		(fill yes
			(thermal_gap 0.5)
			(thermal_bridge_width 0.5)
			(island_removal_mode 0)
		)
		(polygon
			(pts
				(xy -155.75566 42.39006) (xy -154.94286 42.39006) (xy -154.94286 41.12006) (xy -155.75566 41.12006)
			)
		)
	)
	(zone
		(layers "B.Cu" "In1.Cu" "In3.Cu" "In4.Cu" "In5.Cu" "In6.Cu")
		(hatch none 0.5)
		(connect_pads
			(clearance 0)
		)
		(min_thickness 0.25)
		(keepout
			(tracks not_allowed)
			(vias allowed)
			(pads allowed)
			(copperpour not_allowed)
			(footprints allowed)
		)
		(placement
			(enabled no)
			(sheetname "")
		)
		(fill yes
			(thermal_gap 0.5)
			(thermal_bridge_width 0.5)
			(island_removal_mode 0)
		)
		(polygon
			(pts
				(xy -157.02566 24.61006) (xy -156.21286 24.61006) (xy -156.21286 23.34006) (xy -157.02566 23.34006)
			)
		)
	)
	(zone
		(layers "B.Cu" "In1.Cu" "In3.Cu" "In4.Cu" "In5.Cu" "In6.Cu")
		(hatch none 0.5)
		(connect_pads
			(clearance 0)
		)
		(min_thickness 0.25)
		(keepout
			(tracks not_allowed)
			(vias allowed)
			(pads allowed)
			(copperpour not_allowed)
			(footprints allowed)
		)
		(placement
			(enabled no)
			(sheetname "")
		)
		(fill yes
			(thermal_gap 0.5)
			(thermal_bridge_width 0.5)
			(island_removal_mode 0)
		)
		(polygon
			(pts
				(xy -376.75566 42.39006) (xy -375.94286 42.39006) (xy -375.94286 41.12006) (xy -376.75566 41.12006)
			)
		)
	)
	(zone
		(layers "B.Cu" "In1.Cu" "In3.Cu" "In4.Cu" "In5.Cu" "In6.Cu")
		(hatch none 0.5)
		(connect_pads
			(clearance 0)
		)
		(min_thickness 0.25)
		(keepout
			(tracks not_allowed)
			(vias allowed)
			(pads allowed)
			(copperpour not_allowed)
			(footprints allowed)
		)
		(placement
			(enabled no)
			(sheetname "")
		)
		(fill yes
			(thermal_gap 0.5)
			(thermal_bridge_width 0.5)
			(island_removal_mode 0)
		)
		(polygon
			(pts
				(xy -376.75566 22.07006) (xy -375.94286 22.07006) (xy -375.94286 20.80006) (xy -376.75566 20.80006)
			)
		)
	)
	(zone
		(layers "B.Cu" "In1.Cu" "In3.Cu" "In4.Cu" "In5.Cu" "In6.Cu")
		(hatch none 0.5)
		(connect_pads
			(clearance 0)
		)
		(min_thickness 0.25)
		(keepout
			(tracks not_allowed)
			(vias allowed)
			(pads allowed)
			(copperpour not_allowed)
			(footprints allowed)
		)
		(placement
			(enabled no)
			(sheetname "")
		)
		(fill yes
			(thermal_gap 0.5)
			(thermal_bridge_width 0.5)
			(island_removal_mode 0)
		)
		(polygon
			(pts
				(xy -155.75566 32.23006) (xy -154.94286 32.23006) (xy -154.94286 30.96006) (xy -155.75566 30.96006)
			)
		)
	)
	(zone
		(layers "B.Cu" "In1.Cu" "In3.Cu" "In4.Cu" "In5.Cu" "In6.Cu")
		(hatch none 0.5)
		(connect_pads
			(clearance 0)
		)
		(min_thickness 0.25)
		(keepout
			(tracks not_allowed)
			(vias allowed)
			(pads allowed)
			(copperpour not_allowed)
			(footprints allowed)
		)
		(placement
			(enabled no)
			(sheetname "")
		)
		(fill yes
			(thermal_gap 0.5)
			(thermal_bridge_width 0.5)
			(island_removal_mode 0)
		)
		(polygon
			(pts
				(xy -378.02566 29.69006) (xy -377.21286 29.69006) (xy -377.21286 28.42006) (xy -378.02566 28.42006)
			)
		)
	)
	(zone
		(layers "B.Cu" "In1.Cu" "In3.Cu" "In4.Cu" "In5.Cu" "In6.Cu")
		(hatch none 0.5)
		(connect_pads
			(clearance 0)
		)
		(min_thickness 0.25)
		(keepout
			(tracks not_allowed)
			(vias allowed)
			(pads allowed)
			(copperpour not_allowed)
			(footprints allowed)
		)
		(placement
			(enabled no)
			(sheetname "")
		)
		(fill yes
			(thermal_gap 0.5)
			(thermal_bridge_width 0.5)
			(island_removal_mode 0)
		)
		(polygon
			(pts
				(xy -157.02566 34.77006) (xy -156.21286 34.77006) (xy -156.21286 33.50006) (xy -157.02566 33.50006)
			)
		)
	)
	(zone
		(layers "B.Cu" "In1.Cu" "In3.Cu" "In4.Cu" "In5.Cu" "In6.Cu")
		(hatch none 0.5)
		(connect_pads
			(clearance 0)
		)
		(min_thickness 0.25)
		(keepout
			(tracks not_allowed)
			(vias allowed)
			(pads allowed)
			(copperpour not_allowed)
			(footprints allowed)
		)
		(placement
			(enabled no)
			(sheetname "")
		)
		(fill yes
			(thermal_gap 0.5)
			(thermal_bridge_width 0.5)
			(island_removal_mode 0)
		)
		(polygon
			(pts
				(xy -157.02566 29.69006) (xy -156.21286 29.69006) (xy -156.21286 28.42006) (xy -157.02566 28.42006)
			)
		)
	)
	(zone
		(layers "B.Cu" "In1.Cu" "In3.Cu" "In4.Cu" "In5.Cu" "In6.Cu")
		(hatch none 0.5)
		(connect_pads
			(clearance 0)
		)
		(min_thickness 0.25)
		(keepout
			(tracks not_allowed)
			(vias allowed)
			(pads allowed)
			(copperpour not_allowed)
			(footprints allowed)
		)
		(placement
			(enabled no)
			(sheetname "")
		)
		(fill yes
			(thermal_gap 0.5)
			(thermal_bridge_width 0.5)
			(island_removal_mode 0)
		)
		(polygon
			(pts
				(xy -376.75566 37.31006) (xy -375.94286 37.31006) (xy -375.94286 36.04006) (xy -376.75566 36.04006)
			)
		)
	)
	(zone
		(layers "B.Cu" "In1.Cu" "In3.Cu" "In4.Cu" "In5.Cu" "In6.Cu")
		(hatch none 0.5)
		(connect_pads
			(clearance 0)
		)
		(min_thickness 0.25)
		(keepout
			(tracks not_allowed)
			(vias allowed)
			(pads allowed)
			(copperpour not_allowed)
			(footprints allowed)
		)
		(placement
			(enabled no)
			(sheetname "")
		)
		(fill yes
			(thermal_gap 0.5)
			(thermal_bridge_width 0.5)
			(island_removal_mode 0)
		)
		(polygon
			(pts
				(xy -155.75566 37.31006) (xy -154.94286 37.31006) (xy -154.94286 36.04006) (xy -155.75566 36.04006)
			)
		)
	)
	(zone
		(layers "B.Cu" "In1.Cu" "In3.Cu" "In4.Cu" "In5.Cu" "In6.Cu")
		(hatch none 0.5)
		(connect_pads
			(clearance 0)
		)
		(min_thickness 0.25)
		(keepout
			(tracks not_allowed)
			(vias allowed)
			(pads allowed)
			(copperpour not_allowed)
			(footprints allowed)
		)
		(placement
			(enabled no)
			(sheetname "")
		)
		(fill yes
			(thermal_gap 0.5)
			(thermal_bridge_width 0.5)
			(island_removal_mode 0)
		)
		(polygon
			(pts
				(xy -376.75566 32.23006) (xy -375.94286 32.23006) (xy -375.94286 30.96006) (xy -376.75566 30.96006)
			)
		)
	)
	(zone
		(layer "In1.Cu")
		(hatch none 0.5)
		(connect_pads
			(clearance 0)
		)
		(min_thickness 0.25)
		(keepout
			(tracks not_allowed)
			(vias allowed)
			(pads allowed)
			(copperpour not_allowed)
			(footprints allowed)
		)
		(placement
			(enabled no)
			(sheetname "")
		)
		(fill
			(thermal_gap 0.5)
			(thermal_bridge_width 0.5)
			(island_removal_mode 0)
		)
		(polygon
			(pts
				(xy -335.76768 56.35752) (xy -335.76768 54.27472) (xy -335.51368 54.02072) (xy -334.14208 54.02072)
				(xy -333.88808 54.27472) (xy -333.88808 56.35752) (xy -334.14208 56.61152) (xy -335.51368 56.61152)
			)
		)
	)
	(zone
		(layer "In1.Cu")
		(hatch none 0.5)
		(connect_pads
			(clearance 0)
		)
		(min_thickness 0.25)
		(keepout
			(tracks not_allowed)
			(vias allowed)
			(pads allowed)
			(copperpour not_allowed)
			(footprints allowed)
		)
		(placement
			(enabled no)
			(sheetname "")
		)
		(fill
			(thermal_gap 0.5)
			(thermal_bridge_width 0.5)
			(island_removal_mode 0)
		)
		(polygon
			(pts
				(xy -307.19268 41.976035) (xy -307.19268 43.042835) (xy -306.37988 43.042835) (xy -306.37988 41.976035)
			)
		)
	)
	(zone
		(layer "In1.Cu")
		(hatch none 0.5)
		(connect_pads
			(clearance 0)
		)
		(min_thickness 0.25)
		(keepout
			(tracks not_allowed)
			(vias allowed)
			(pads allowed)
			(copperpour not_allowed)
			(footprints allowed)
		)
		(placement
			(enabled no)
			(sheetname "")
		)
		(fill
			(thermal_gap 0.5)
			(thermal_bridge_width 0.5)
			(island_removal_mode 0)
		)
		(polygon
			(pts
				(arc
					(start -281.140891 -7.233224)
					(mid -282.207691 -7.233224)
					(end -281.140891 -7.233224)
				)
			)
		)
	)
	(zone
		(layer "In1.Cu")
		(hatch none 0.5)
		(connect_pads
			(clearance 0)
		)
		(min_thickness 0.25)
		(keepout
			(tracks not_allowed)
			(vias allowed)
			(pads allowed)
			(copperpour not_allowed)
			(footprints allowed)
		)
		(placement
			(enabled no)
			(sheetname "")
		)
		(fill
			(thermal_gap 0.5)
			(thermal_bridge_width 0.5)
			(island_removal_mode 0)
		)
		(polygon
			(pts
				(xy -64.356399 38.883074) (xy -64.356399 39.949874) (xy -63.543599 39.949874) (xy -63.543599 38.883074)
			)
		)
	)
	(zone
		(layer "In1.Cu")
		(hatch none 0.5)
		(connect_pads
			(clearance 0)
		)
		(min_thickness 0.25)
		(keepout
			(tracks not_allowed)
			(vias allowed)
			(pads allowed)
			(copperpour not_allowed)
			(footprints allowed)
		)
		(placement
			(enabled no)
			(sheetname "")
		)
		(fill
			(thermal_gap 0.5)
			(thermal_bridge_width 0.5)
			(island_removal_mode 0)
		)
		(polygon
			(pts
				(xy -322.456401 46.11039) (xy -322.456401 47.17719) (xy -321.643601 47.17719) (xy -321.643601 46.11039)
			)
		)
	)
	(zone
		(layer "In1.Cu")
		(hatch none 0.5)
		(connect_pads
			(clearance 0)
		)
		(min_thickness 0.25)
		(keepout
			(tracks not_allowed)
			(vias allowed)
			(pads allowed)
			(copperpour not_allowed)
			(footprints allowed)
		)
		(placement
			(enabled no)
			(sheetname "")
		)
		(fill
			(thermal_gap 0.5)
			(thermal_bridge_width 0.5)
			(island_removal_mode 0)
		)
		(polygon
			(pts
				(xy -281.139105 -7.233323) (xy -282.205905 -7.233323) (xy -282.205905 -6.420523) (xy -281.139105 -6.420523)
			)
		)
	)
	(zone
		(layer "In1.Cu")
		(hatch none 0.5)
		(connect_pads
			(clearance 0)
		)
		(min_thickness 0.25)
		(keepout
			(tracks not_allowed)
			(vias allowed)
			(pads allowed)
			(copperpour not_allowed)
			(footprints allowed)
		)
		(placement
			(enabled no)
			(sheetname "")
		)
		(fill
			(thermal_gap 0.5)
			(thermal_bridge_width 0.5)
			(island_removal_mode 0)
		)
		(polygon
			(pts
				(xy -320.452854 36.153184) (xy -320.452854 37.219984) (xy -319.640054 37.219984) (xy -319.640054 36.153184)
			)
		)
	)
	(zone
		(layer "In1.Cu")
		(hatch none 0.5)
		(connect_pads
			(clearance 0)
		)
		(min_thickness 0.25)
		(keepout
			(tracks not_allowed)
			(vias allowed)
			(pads allowed)
			(copperpour not_allowed)
			(footprints allowed)
		)
		(placement
			(enabled no)
			(sheetname "")
		)
		(fill
			(thermal_gap 0.5)
			(thermal_bridge_width 0.5)
			(island_removal_mode 0)
		)
		(polygon
			(pts
				(xy -322.8564 38.018715) (xy -322.8564 39.085515) (xy -322.0436 39.085515) (xy -322.0436 38.018715)
			)
		)
	)
	(zone
		(layer "In1.Cu")
		(hatch none 0.5)
		(connect_pads
			(clearance 0)
		)
		(min_thickness 0.25)
		(keepout
			(tracks not_allowed)
			(vias allowed)
			(pads allowed)
			(copperpour not_allowed)
			(footprints allowed)
		)
		(placement
			(enabled no)
			(sheetname "")
		)
		(fill
			(thermal_gap 0.5)
			(thermal_bridge_width 0.5)
			(island_removal_mode 0)
		)
		(polygon
			(pts
				(arc
					(start -281.140891 -6.420424)
					(mid -282.207691 -6.420424)
					(end -281.140891 -6.420424)
				)
			)
		)
	)
	(zone
		(layer "In1.Cu")
		(hatch none 0.5)
		(connect_pads
			(clearance 0)
		)
		(min_thickness 0.25)
		(keepout
			(tracks not_allowed)
			(vias allowed)
			(pads allowed)
			(copperpour not_allowed)
			(footprints allowed)
		)
		(placement
			(enabled no)
			(sheetname "")
		)
		(fill
			(thermal_gap 0.5)
			(thermal_bridge_width 0.5)
			(island_removal_mode 0)
		)
		(polygon
			(pts
				(xy -92.82716 46.553115) (xy -92.82716 47.619915) (xy -92.01436 47.619915) (xy -92.01436 46.553115)
			)
		)
	)
	(zone
		(layer "In1.Cu")
		(hatch none 0.5)
		(connect_pads
			(clearance 0)
		)
		(min_thickness 0.25)
		(keepout
			(tracks not_allowed)
			(vias allowed)
			(pads allowed)
			(copperpour not_allowed)
			(footprints allowed)
		)
		(placement
			(enabled no)
			(sheetname "")
		)
		(fill
			(thermal_gap 0.5)
			(thermal_bridge_width 0.5)
			(island_removal_mode 0)
		)
		(polygon
			(pts
				(xy -313.256402 33.591495) (xy -313.256402 34.658295) (xy -312.443602 34.658295) (xy -312.443602 33.591495)
			)
		)
	)
	(zone
		(layer "In1.Cu")
		(hatch none 0.5)
		(connect_pads
			(clearance 0)
		)
		(min_thickness 0.25)
		(keepout
			(tracks not_allowed)
			(vias allowed)
			(pads allowed)
			(copperpour not_allowed)
			(footprints allowed)
		)
		(placement
			(enabled no)
			(sheetname "")
		)
		(fill
			(thermal_gap 0.5)
			(thermal_bridge_width 0.5)
			(island_removal_mode 0)
		)
		(polygon
			(pts
				(xy -89.842635 37.541195) (xy -89.842635 38.607995) (xy -89.029835 38.607995) (xy -89.029835 37.541195)
			)
		)
	)
	(zone
		(layer "In1.Cu")
		(hatch none 0.5)
		(connect_pads
			(clearance 0)
		)
		(min_thickness 0.25)
		(keepout
			(tracks not_allowed)
			(vias allowed)
			(pads allowed)
			(copperpour not_allowed)
			(footprints allowed)
		)
		(placement
			(enabled no)
			(sheetname "")
		)
		(fill
			(thermal_gap 0.5)
			(thermal_bridge_width 0.5)
			(island_removal_mode 0)
		)
		(polygon
			(pts
				(xy -285.356399 38.883074) (xy -285.356399 39.949874) (xy -284.543599 39.949874) (xy -284.543599 38.883074)
			)
		)
	)
	(zone
		(layer "In1.Cu")
		(hatch none 0.5)
		(connect_pads
			(clearance 0)
		)
		(min_thickness 0.25)
		(keepout
			(tracks not_allowed)
			(vias allowed)
			(pads allowed)
			(copperpour not_allowed)
			(footprints allowed)
		)
		(placement
			(enabled no)
			(sheetname "")
		)
		(fill
			(thermal_gap 0.5)
			(thermal_bridge_width 0.5)
			(island_removal_mode 0)
		)
		(polygon
			(pts
				(xy -101.456401 46.11039) (xy -101.456401 47.17719) (xy -100.643601 47.17719) (xy -100.643601 46.11039)
			)
		)
	)
	(zone
		(layer "In1.Cu")
		(hatch none 0.5)
		(connect_pads
			(clearance 0)
		)
		(min_thickness 0.25)
		(keepout
			(tracks not_allowed)
			(vias allowed)
			(pads allowed)
			(copperpour not_allowed)
			(footprints allowed)
		)
		(placement
			(enabled no)
			(sheetname "")
		)
		(fill
			(thermal_gap 0.5)
			(thermal_bridge_width 0.5)
			(island_removal_mode 0)
		)
		(polygon
			(pts
				(xy -101.8564 38.018715) (xy -101.8564 39.085515) (xy -101.0436 39.085515) (xy -101.0436 38.018715)
			)
		)
	)
	(zone
		(layer "In1.Cu")
		(hatch none 0.5)
		(connect_pads
			(clearance 0)
		)
		(min_thickness 0.25)
		(keepout
			(tracks not_allowed)
			(vias allowed)
			(pads allowed)
			(copperpour not_allowed)
			(footprints allowed)
		)
		(placement
			(enabled no)
			(sheetname "")
		)
		(fill
			(thermal_gap 0.5)
			(thermal_bridge_width 0.5)
			(island_removal_mode 0)
		)
		(polygon
			(pts
				(xy -86.19268 41.976035) (xy -86.19268 43.042835) (xy -85.37988 43.042835) (xy -85.37988 41.976035)
			)
		)
	)
	(zone
		(net "GND")
		(layer "In1.Cu")
		(hatch none 0.5)
		(connect_pads
			(clearance 0.5)
		)
		(min_thickness 0.25)
		(fill yes
			(thermal_gap 0.5)
			(thermal_bridge_width 0.5)
			(island_removal_mode 0)
		)
		(polygon
			(pts
				(xy -324.266199 49.441199)
				(arc
					(start -324.266199 47.960001)
					(mid -324.576315 47.211315)
					(end -325.325001 46.901199)
				)
				(arc
					(start -420.960001 46.901199)
					(mid -421.625529 46.625528)
					(end -421.901201 45.96)
				)
				(xy -421.901201 -4.108536) (xy -421.663797 -4.34594) (xy -412.806203 -4.34594) (xy -412.568799 -4.108536)
				(arc
					(start -412.568799 4.810001)
					(mid -411.66 5.7188)
					(end -410.7512 4.810001)
				)
				(xy -410.7512 -4.108536) (xy -410.518877 -4.34086) (xy -371.171125 -4.34086) (xy -370.938801 -4.108536)
				(arc
					(start -370.938801 3.66)
					(mid -370.335792 5.115791)
					(end -368.880001 5.7188)
				)
				(arc
					(start -367.879998 5.7188)
					(mid -366.424207 5.115791)
					(end -365.821199 3.66)
				)
				(arc
					(start -365.821199 -2.34)
					(mid -365.252635 -3.712635)
					(end -363.880001 -4.2812)
				)
				(arc
					(start 1.38 -4.2812)
					(mid 3.106189 -3.566189)
					(end 3.821199 -1.839999)
				)
				(arc
					(start 3.821199 34.5)
					(mid 4.131315 35.248685)
					(end 4.88 35.558801)
				)
				(xy 4.981199 35.558801)
				(arc
					(start 4.981199 44.46)
					(mid 4.266188 46.186188)
					(end 2.54 46.901199)
				)
				(arc
					(start -85.175001 46.901199)
					(mid -85.923686 47.211316)
					(end -86.2338 47.960001)
				)
				(xy -86.2338 49.441199) (xy -103.266199 49.441199)
				(arc
					(start -103.266199 47.960001)
					(mid -103.576315 47.211315)
					(end -104.325001 46.901199)
				)
				(xy -229.8192 46.901199) (xy -229.869901 46.9519) (xy -306.539143 46.9519)
				(arc
					(start -306.56151 46.974267)
					(mid -307.049727 47.363418)
					(end -307.2338 47.960001)
				)
				(xy -307.2338 49.441199)
			)
		)
	)
	(zone
		(layer "In1.Cu")
		(hatch none 0.5)
		(connect_pads
			(clearance 0)
		)
		(min_thickness 0.25)
		(keepout
			(tracks not_allowed)
			(vias allowed)
			(pads allowed)
			(copperpour not_allowed)
			(footprints allowed)
		)
		(placement
			(enabled no)
			(sheetname "")
		)
		(fill
			(thermal_gap 0.5)
			(thermal_bridge_width 0.5)
			(island_removal_mode 0)
		)
		(polygon
			(pts
				(xy -313.82716 46.553115) (xy -313.82716 47.619915) (xy -313.01436 47.619915) (xy -313.01436 46.553115)
			)
		)
	)
	(zone
		(layer "In1.Cu")
		(hatch none 0.5)
		(connect_pads
			(clearance 0)
		)
		(min_thickness 0.25)
		(keepout
			(tracks not_allowed)
			(vias allowed)
			(pads allowed)
			(copperpour not_allowed)
			(footprints allowed)
		)
		(placement
			(enabled no)
			(sheetname "")
		)
		(fill
			(thermal_gap 0.5)
			(thermal_bridge_width 0.5)
			(island_removal_mode 0)
		)
		(polygon
			(pts
				(xy -310.842635 37.541195) (xy -310.842635 38.607995) (xy -310.029835 38.607995) (xy -310.029835 37.541195)
			)
		)
	)
	(zone
		(layer "In1.Cu")
		(hatch none 0.5)
		(connect_pads
			(clearance 0)
		)
		(min_thickness 0.25)
		(keepout
			(tracks not_allowed)
			(vias allowed)
			(pads allowed)
			(copperpour not_allowed)
			(footprints allowed)
		)
		(placement
			(enabled no)
			(sheetname "")
		)
		(fill
			(thermal_gap 0.5)
			(thermal_bridge_width 0.5)
			(island_removal_mode 0)
		)
		(polygon
			(pts
				(xy -92.256402 33.591495) (xy -92.256402 34.658295) (xy -91.443602 34.658295) (xy -91.443602 33.591495)
			)
		)
	)
	(zone
		(layer "In1.Cu")
		(hatch none 0.5)
		(connect_pads
			(clearance 0)
		)
		(min_thickness 0.25)
		(keepout
			(tracks not_allowed)
			(vias allowed)
			(pads allowed)
			(copperpour not_allowed)
			(footprints allowed)
		)
		(placement
			(enabled no)
			(sheetname "")
		)
		(fill
			(thermal_gap 0.5)
			(thermal_bridge_width 0.5)
			(island_removal_mode 0)
		)
		(polygon
			(pts
				(xy -99.452854 36.153184) (xy -99.452854 37.219984) (xy -98.640054 37.219984) (xy -98.640054 36.153184)
			)
		)
	)
	(zone
		(layers "In1.Cu" "In2.Cu")
		(hatch none 0.5)
		(connect_pads
			(clearance 0)
		)
		(min_thickness 0.25)
		(keepout
			(tracks not_allowed)
			(vias allowed)
			(pads allowed)
			(copperpour not_allowed)
			(footprints allowed)
		)
		(placement
			(enabled no)
			(sheetname "")
		)
		(fill yes
			(thermal_gap 0.5)
			(thermal_bridge_width 0.5)
			(island_removal_mode 0)
		)
		(polygon
			(pts
				(xy -320.590261 44.88244) (xy -320.590261 42.79964) (xy -320.336261 42.54564) (xy -318.964661 42.54564)
				(xy -318.710661 42.79964) (xy -318.710661 44.88244) (xy -318.964661 45.13644) (xy -320.336261 45.13644)
			)
		)
	)
	(zone
		(layers "In1.Cu" "In2.Cu")
		(hatch none 0.5)
		(connect_pads
			(clearance 0)
		)
		(min_thickness 0.25)
		(keepout
			(tracks not_allowed)
			(vias allowed)
			(pads allowed)
			(copperpour not_allowed)
			(footprints allowed)
		)
		(placement
			(enabled no)
			(sheetname "")
		)
		(fill yes
			(thermal_gap 0.5)
			(thermal_bridge_width 0.5)
			(island_removal_mode 0)
		)
		(polygon
			(pts
				(xy -323.39026 42.38244) (xy -323.39026 40.29964) (xy -323.13626 40.04564) (xy -321.76466 40.04564)
				(xy -321.51066 40.29964) (xy -321.51066 42.38244) (xy -321.76466 42.63644) (xy -323.13626 42.63644)
			)
		)
	)
	(zone
		(layers "In1.Cu" "In2.Cu")
		(hatch none 0.5)
		(connect_pads
			(clearance 0)
		)
		(min_thickness 0.25)
		(keepout
			(tracks not_allowed)
			(vias allowed)
			(pads allowed)
			(copperpour not_allowed)
			(footprints allowed)
		)
		(placement
			(enabled no)
			(sheetname "")
		)
		(fill yes
			(thermal_gap 0.5)
			(thermal_bridge_width 0.5)
			(island_removal_mode 0)
		)
		(polygon
			(pts
				(xy -313.390262 44.88244) (xy -313.390262 42.79964) (xy -313.136262 42.54564) (xy -311.764662 42.54564)
				(xy -311.510662 42.79964) (xy -311.510662 44.88244) (xy -311.764662 45.13644) (xy -313.136262 45.13644)
			)
		)
	)
	(zone
		(layers "In1.Cu" "In2.Cu")
		(hatch none 0.5)
		(connect_pads
			(clearance 0)
		)
		(min_thickness 0.25)
		(keepout
			(tracks not_allowed)
			(vias allowed)
			(pads allowed)
			(copperpour not_allowed)
			(footprints allowed)
		)
		(placement
			(enabled no)
			(sheetname "")
		)
		(fill yes
			(thermal_gap 0.5)
			(thermal_bridge_width 0.5)
			(island_removal_mode 0)
		)
		(polygon
			(pts
				(xy -313.790261 42.38244) (xy -313.790261 40.29964) (xy -313.536261 40.04564) (xy -312.164661 40.04564)
				(xy -311.910661 40.29964) (xy -311.910661 42.38244) (xy -312.164661 42.63644) (xy -313.536261 42.63644)
			)
		)
	)
	(zone
		(layers "In1.Cu" "In2.Cu")
		(hatch none 0.5)
		(connect_pads
			(clearance 0)
		)
		(min_thickness 0.25)
		(keepout
			(tracks not_allowed)
			(vias allowed)
			(pads allowed)
			(copperpour not_allowed)
			(footprints allowed)
		)
		(placement
			(enabled no)
			(sheetname "")
		)
		(fill yes
			(thermal_gap 0.5)
			(thermal_bridge_width 0.5)
			(island_removal_mode 0)
		)
		(polygon
			(pts
				(xy -311.390261 42.38244) (xy -311.390261 40.29964) (xy -311.136261 40.04564) (xy -309.764661 40.04564)
				(xy -309.510661 40.29964) (xy -309.510661 42.38244) (xy -309.764661 42.63644) (xy -311.136261 42.63644)
			)
		)
	)
	(zone
		(layers "In1.Cu" "In2.Cu")
		(hatch none 0.5)
		(connect_pads
			(clearance 0)
		)
		(min_thickness 0.25)
		(keepout
			(tracks not_allowed)
			(vias allowed)
			(pads allowed)
			(copperpour not_allowed)
			(footprints allowed)
		)
		(placement
			(enabled no)
			(sheetname "")
		)
		(fill yes
			(thermal_gap 0.5)
			(thermal_bridge_width 0.5)
			(island_removal_mode 0)
		)
		(polygon
			(pts
				(xy -310.990262 44.88244) (xy -310.990262 42.79964) (xy -310.736262 42.54564) (xy -309.364662 42.54564)
				(xy -309.110662 42.79964) (xy -309.110662 44.88244) (xy -309.364662 45.13644) (xy -310.736262 45.13644)
			)
		)
	)
	(zone
		(layers "In1.Cu" "In2.Cu")
		(hatch none 0.5)
		(connect_pads
			(clearance 0)
		)
		(min_thickness 0.25)
		(keepout
			(tracks not_allowed)
			(vias allowed)
			(pads allowed)
			(copperpour not_allowed)
			(footprints allowed)
		)
		(placement
			(enabled no)
			(sheetname "")
		)
		(fill yes
			(thermal_gap 0.5)
			(thermal_bridge_width 0.5)
			(island_removal_mode 0)
		)
		(polygon
			(pts
				(xy -320.99026 42.38244) (xy -320.99026 40.29964) (xy -320.73626 40.04564) (xy -319.36466 40.04564)
				(xy -319.11066 40.29964) (xy -319.11066 42.38244) (xy -319.36466 42.63644) (xy -320.73626 42.63644)
			)
		)
	)
	(zone
		(layers "In1.Cu" "In2.Cu")
		(hatch none 0.5)
		(connect_pads
			(clearance 0)
		)
		(min_thickness 0.25)
		(keepout
			(tracks not_allowed)
			(vias allowed)
			(pads allowed)
			(copperpour not_allowed)
			(footprints allowed)
		)
		(placement
			(enabled no)
			(sheetname "")
		)
		(fill yes
			(thermal_gap 0.5)
			(thermal_bridge_width 0.5)
			(island_removal_mode 0)
		)
		(polygon
			(pts
				(xy -322.990261 44.88244) (xy -322.990261 42.79964) (xy -322.736261 42.54564) (xy -321.364661 42.54564)
				(xy -321.110661 42.79964) (xy -321.110661 44.88244) (xy -321.364661 45.13644) (xy -322.736261 45.13644)
			)
		)
	)
	(zone
		(layers "In1.Cu" "In2.Cu" "In3.Cu")
		(hatch none 0.5)
		(connect_pads
			(clearance 0)
		)
		(min_thickness 0.25)
		(keepout
			(tracks not_allowed)
			(vias allowed)
			(pads allowed)
			(copperpour not_allowed)
			(footprints allowed)
		)
		(placement
			(enabled no)
			(sheetname "")
		)
		(fill yes
			(thermal_gap 0.5)
			(thermal_bridge_width 0.5)
			(island_removal_mode 0)
		)
		(polygon
			(pts
				(xy -99.989099 42.479902) (xy -99.989099 40.193902) (xy -99.735099 39.939902) (xy -98.363499 39.939902)
				(xy -98.109499 40.193902) (xy -98.109499 42.479902) (xy -98.363499 42.733902) (xy -99.735099 42.733902)
			)
		)
	)
	(zone
		(layers "In1.Cu" "In2.Cu" "In3.Cu")
		(hatch none 0.5)
		(connect_pads
			(clearance 0)
		)
		(min_thickness 0.25)
		(keepout
			(tracks not_allowed)
			(vias allowed)
			(pads allowed)
			(copperpour not_allowed)
			(footprints allowed)
		)
		(placement
			(enabled no)
			(sheetname "")
		)
		(fill yes
			(thermal_gap 0.5)
			(thermal_bridge_width 0.5)
			(island_removal_mode 0)
		)
		(polygon
			(pts
				(xy -90.3891 42.479902) (xy -90.3891 40.193902) (xy -90.1351 39.939902) (xy -88.7635 39.939902)
				(xy -88.5095 40.193902) (xy -88.5095 42.479902) (xy -88.7635 42.733902) (xy -90.1351 42.733902)
			)
		)
	)
	(zone
		(layers "In1.Cu" "In2.Cu" "In3.Cu")
		(hatch none 0.5)
		(connect_pads
			(clearance 0)
		)
		(min_thickness 0.25)
		(keepout
			(tracks not_allowed)
			(vias allowed)
			(pads allowed)
			(copperpour not_allowed)
			(footprints allowed)
		)
		(placement
			(enabled no)
			(sheetname "")
		)
		(fill yes
			(thermal_gap 0.5)
			(thermal_bridge_width 0.5)
			(island_removal_mode 0)
		)
		(polygon
			(pts
				(xy -99.5891 44.979902) (xy -99.5891 42.693902) (xy -99.3351 42.439902) (xy -97.9635 42.439902)
				(xy -97.7095 42.693902) (xy -97.7095 44.979902) (xy -97.9635 45.233902) (xy -99.3351 45.233902)
			)
		)
	)
	(zone
		(layers "In1.Cu" "In2.Cu" "In3.Cu")
		(hatch none 0.5)
		(connect_pads
			(clearance 0)
		)
		(min_thickness 0.25)
		(keepout
			(tracks not_allowed)
			(vias allowed)
			(pads allowed)
			(copperpour not_allowed)
			(footprints allowed)
		)
		(placement
			(enabled no)
			(sheetname "")
		)
		(fill yes
			(thermal_gap 0.5)
			(thermal_bridge_width 0.5)
			(island_removal_mode 0)
		)
		(polygon
			(pts
				(xy -92.789101 42.479902) (xy -92.789101 40.193902) (xy -92.535101 39.939902) (xy -91.163501 39.939902)
				(xy -90.909501 40.193902) (xy -90.909501 42.479902) (xy -91.163501 42.733902) (xy -92.535101 42.733902)
			)
		)
	)
	(zone
		(layers "In1.Cu" "In2.Cu" "In3.Cu")
		(hatch none 0.5)
		(connect_pads
			(clearance 0)
		)
		(min_thickness 0.25)
		(keepout
			(tracks not_allowed)
			(vias allowed)
			(pads allowed)
			(copperpour not_allowed)
			(footprints allowed)
		)
		(placement
			(enabled no)
			(sheetname "")
		)
		(fill yes
			(thermal_gap 0.5)
			(thermal_bridge_width 0.5)
			(island_removal_mode 0)
		)
		(polygon
			(pts
				(xy -101.9891 44.979902) (xy -101.9891 42.693902) (xy -101.7351 42.439902) (xy -100.3635 42.439902)
				(xy -100.1095 42.693902) (xy -100.1095 44.979902) (xy -100.3635 45.233902) (xy -101.7351 45.233902)
			)
		)
	)
	(zone
		(layers "In1.Cu" "In2.Cu" "In3.Cu")
		(hatch none 0.5)
		(connect_pads
			(clearance 0)
		)
		(min_thickness 0.25)
		(keepout
			(tracks not_allowed)
			(vias allowed)
			(pads allowed)
			(copperpour not_allowed)
			(footprints allowed)
		)
		(placement
			(enabled no)
			(sheetname "")
		)
		(fill yes
			(thermal_gap 0.5)
			(thermal_bridge_width 0.5)
			(island_removal_mode 0)
		)
		(polygon
			(pts
				(xy -92.389101 44.979902) (xy -92.389101 42.693902) (xy -92.135101 42.439902) (xy -90.763501 42.439902)
				(xy -90.509501 42.693902) (xy -90.509501 44.979902) (xy -90.763501 45.233902) (xy -92.135101 45.233902)
			)
		)
	)
	(zone
		(layers "In1.Cu" "In2.Cu" "In3.Cu")
		(hatch none 0.5)
		(connect_pads
			(clearance 0)
		)
		(min_thickness 0.25)
		(keepout
			(tracks not_allowed)
			(vias allowed)
			(pads allowed)
			(copperpour not_allowed)
			(footprints allowed)
		)
		(placement
			(enabled no)
			(sheetname "")
		)
		(fill yes
			(thermal_gap 0.5)
			(thermal_bridge_width 0.5)
			(island_removal_mode 0)
		)
		(polygon
			(pts
				(xy -89.989101 44.979902) (xy -89.989101 42.693902) (xy -89.735101 42.439902) (xy -88.363501 42.439902)
				(xy -88.109501 42.693902) (xy -88.109501 44.979902) (xy -88.363501 45.233902) (xy -89.735101 45.233902)
			)
		)
	)
	(zone
		(layers "In1.Cu" "In2.Cu" "In3.Cu")
		(hatch none 0.5)
		(connect_pads
			(clearance 0)
		)
		(min_thickness 0.25)
		(keepout
			(tracks not_allowed)
			(vias allowed)
			(pads allowed)
			(copperpour not_allowed)
			(footprints allowed)
		)
		(placement
			(enabled no)
			(sheetname "")
		)
		(fill yes
			(thermal_gap 0.5)
			(thermal_bridge_width 0.5)
			(island_removal_mode 0)
		)
		(polygon
			(pts
				(xy -102.389099 42.479902) (xy -102.389099 40.193902) (xy -102.135099 39.939902) (xy -100.763499 39.939902)
				(xy -100.509499 40.193902) (xy -100.509499 42.479902) (xy -100.763499 42.733902) (xy -102.135099 42.733902)
			)
		)
	)
	(zone
		(layers "In1.Cu" "In2.Cu" "In3.Cu" "In4.Cu" "In5.Cu" "In6.Cu")
		(hatch none 0.5)
		(connect_pads
			(clearance 0)
		)
		(min_thickness 0.25)
		(keepout
			(tracks not_allowed)
			(vias allowed)
			(pads allowed)
			(copperpour not_allowed)
			(footprints allowed)
		)
		(placement
			(enabled no)
			(sheetname "")
		)
		(fill yes
			(thermal_gap 0.5)
			(thermal_bridge_width 0.5)
			(island_removal_mode 0)
		)
		(polygon
			(pts
				(xy -374.21566 37.31006) (xy -373.40286 37.31006) (xy -373.40286 36.04006) (xy -374.21566 36.04006)
			)
		)
	)
	(zone
		(layers "In1.Cu" "In2.Cu" "In3.Cu" "In4.Cu" "In5.Cu" "In6.Cu")
		(hatch none 0.5)
		(connect_pads
			(clearance 0)
		)
		(min_thickness 0.25)
		(keepout
			(tracks not_allowed)
			(vias allowed)
			(pads allowed)
			(copperpour not_allowed)
			(footprints allowed)
		)
		(placement
			(enabled no)
			(sheetname "")
		)
		(fill yes
			(thermal_gap 0.5)
			(thermal_bridge_width 0.5)
			(island_removal_mode 0)
		)
		(polygon
			(pts
				(arc
					(start -98.106555 36.68837)
					(mid -99.173355 36.68837)
					(end -98.106555 36.68837)
				)
			)
		)
	)
	(zone
		(layers "In1.Cu" "In2.Cu" "In3.Cu" "In4.Cu" "In5.Cu" "In6.Cu")
		(hatch none 0.5)
		(connect_pads
			(clearance 0)
		)
		(min_thickness 0.25)
		(keepout
			(tracks not_allowed)
			(vias allowed)
			(pads allowed)
			(copperpour not_allowed)
			(footprints allowed)
		)
		(placement
			(enabled no)
			(sheetname "")
		)
		(fill yes
			(thermal_gap 0.5)
			(thermal_bridge_width 0.5)
			(island_removal_mode 0)
		)
		(polygon
			(pts
				(arc
					(start -310.309136 38.076381)
					(mid -311.375936 38.076381)
					(end -310.309136 38.076381)
				)
			)
		)
	)
	(zone
		(layers "In1.Cu" "In2.Cu" "In3.Cu" "In4.Cu" "In5.Cu" "In6.Cu")
		(hatch none 0.5)
		(connect_pads
			(clearance 0)
		)
		(min_thickness 0.25)
		(keepout
			(tracks not_allowed)
			(vias allowed)
			(pads allowed)
			(copperpour not_allowed)
			(footprints allowed)
		)
		(placement
			(enabled no)
			(sheetname "")
		)
		(fill yes
			(thermal_gap 0.5)
			(thermal_bridge_width 0.5)
			(island_removal_mode 0)
		)
		(polygon
			(pts
				(xy -154.48566 39.85006) (xy -153.67286 39.85006) (xy -153.67286 38.58006) (xy -154.48566 38.58006)
			)
		)
	)
	(zone
		(layers "In1.Cu" "In2.Cu" "In3.Cu" "In4.Cu" "In5.Cu" "In6.Cu")
		(hatch none 0.5)
		(connect_pads
			(clearance 0)
		)
		(min_thickness 0.25)
		(keepout
			(tracks not_allowed)
			(vias allowed)
			(pads allowed)
			(copperpour not_allowed)
			(footprints allowed)
		)
		(placement
			(enabled no)
			(sheetname "")
		)
		(fill yes
			(thermal_gap 0.5)
			(thermal_bridge_width 0.5)
			(island_removal_mode 0)
		)
		(polygon
			(pts
				(arc
					(start -101.322901 38.553901)
					(mid -102.389701 38.553901)
					(end -101.322901 38.553901)
				)
			)
		)
	)
	(zone
		(layers "In1.Cu" "In2.Cu" "In3.Cu" "In4.Cu" "In5.Cu" "In6.Cu")
		(hatch none 0.5)
		(connect_pads
			(clearance 0)
		)
		(min_thickness 0.25)
		(keepout
			(tracks not_allowed)
			(vias allowed)
			(pads allowed)
			(copperpour not_allowed)
			(footprints allowed)
		)
		(placement
			(enabled no)
			(sheetname "")
		)
		(fill yes
			(thermal_gap 0.5)
			(thermal_bridge_width 0.5)
			(island_removal_mode 0)
		)
		(polygon
			(pts
				(arc
					(start -98.919355 36.68837)
					(mid -99.986155 36.68837)
					(end -98.919355 36.68837)
				)
			)
		)
	)
	(zone
		(layers "In1.Cu" "In2.Cu" "In3.Cu" "In4.Cu" "In5.Cu" "In6.Cu")
		(hatch none 0.5)
		(connect_pads
			(clearance 0)
		)
		(min_thickness 0.25)
		(keepout
			(tracks not_allowed)
			(vias allowed)
			(pads allowed)
			(copperpour not_allowed)
			(footprints allowed)
		)
		(placement
			(enabled no)
			(sheetname "")
		)
		(fill yes
			(thermal_gap 0.5)
			(thermal_bridge_width 0.5)
			(island_removal_mode 0)
		)
		(polygon
			(pts
				(arc
					(start -321.510101 38.553901)
					(mid -322.576901 38.553901)
					(end -321.510101 38.553901)
				)
			)
		)
	)
	(zone
		(layers "In1.Cu" "In2.Cu" "In3.Cu" "In4.Cu" "In5.Cu" "In6.Cu")
		(hatch none 0.5)
		(connect_pads
			(clearance 0)
		)
		(min_thickness 0.25)
		(keepout
			(tracks not_allowed)
			(vias allowed)
			(pads allowed)
			(copperpour not_allowed)
			(footprints allowed)
		)
		(placement
			(enabled no)
			(sheetname "")
		)
		(fill yes
			(thermal_gap 0.5)
			(thermal_bridge_width 0.5)
			(island_removal_mode 0)
		)
		(polygon
			(pts
				(xy -153.21566 37.31006) (xy -152.40286 37.31006) (xy -152.40286 36.04006) (xy -153.21566 36.04006)
			)
		)
	)
	(zone
		(layers "In1.Cu" "In2.Cu" "In3.Cu" "In4.Cu" "In5.Cu" "In6.Cu")
		(hatch none 0.5)
		(connect_pads
			(clearance 0)
		)
		(min_thickness 0.25)
		(keepout
			(tracks not_allowed)
			(vias allowed)
			(pads allowed)
			(copperpour not_allowed)
			(footprints allowed)
		)
		(placement
			(enabled no)
			(sheetname "")
		)
		(fill yes
			(thermal_gap 0.5)
			(thermal_bridge_width 0.5)
			(island_removal_mode 0)
		)
		(polygon
			(pts
				(arc
					(start -322.322901 38.553901)
					(mid -323.389701 38.553901)
					(end -322.322901 38.553901)
				)
			)
		)
	)
	(zone
		(layers "In1.Cu" "In2.Cu" "In3.Cu" "In4.Cu" "In5.Cu" "In6.Cu")
		(hatch none 0.5)
		(connect_pads
			(clearance 0)
		)
		(min_thickness 0.25)
		(keepout
			(tracks not_allowed)
			(vias allowed)
			(pads allowed)
			(copperpour not_allowed)
			(footprints allowed)
		)
		(placement
			(enabled no)
			(sheetname "")
		)
		(fill yes
			(thermal_gap 0.5)
			(thermal_bridge_width 0.5)
			(island_removal_mode 0)
		)
		(polygon
			(pts
				(xy -374.21566 27.15006) (xy -373.40286 27.15006) (xy -373.40286 25.88006) (xy -374.21566 25.88006)
			)
		)
	)
	(zone
		(layers "In1.Cu" "In2.Cu" "In3.Cu" "In4.Cu" "In5.Cu" "In6.Cu")
		(hatch none 0.5)
		(connect_pads
			(clearance 0)
		)
		(min_thickness 0.25)
		(keepout
			(tracks not_allowed)
			(vias allowed)
			(pads allowed)
			(copperpour not_allowed)
			(footprints allowed)
		)
		(placement
			(enabled no)
			(sheetname "")
		)
		(fill yes
			(thermal_gap 0.5)
			(thermal_bridge_width 0.5)
			(island_removal_mode 0)
		)
		(polygon
			(pts
				(arc
					(start -100.510101 38.553901)
					(mid -101.576901 38.553901)
					(end -100.510101 38.553901)
				)
			)
		)
	)
	(zone
		(layers "In1.Cu" "In2.Cu" "In3.Cu" "In4.Cu" "In5.Cu" "In6.Cu")
		(hatch none 0.5)
		(connect_pads
			(clearance 0)
		)
		(min_thickness 0.25)
		(keepout
			(tracks not_allowed)
			(vias allowed)
			(pads allowed)
			(copperpour not_allowed)
			(footprints allowed)
		)
		(placement
			(enabled no)
			(sheetname "")
		)
		(fill yes
			(thermal_gap 0.5)
			(thermal_bridge_width 0.5)
			(island_removal_mode 0)
		)
		(polygon
			(pts
				(arc
					(start -60.080421 30.900428)
					(mid -61.147221 30.900428)
					(end -60.080421 30.900428)
				)
			)
		)
	)
	(zone
		(layers "In1.Cu" "In2.Cu" "In3.Cu" "In4.Cu" "In5.Cu" "In6.Cu")
		(hatch none 0.5)
		(connect_pads
			(clearance 0)
		)
		(min_thickness 0.25)
		(keepout
			(tracks not_allowed)
			(vias allowed)
			(pads allowed)
			(copperpour not_allowed)
			(footprints allowed)
		)
		(placement
			(enabled no)
			(sheetname "")
		)
		(fill yes
			(thermal_gap 0.5)
			(thermal_bridge_width 0.5)
			(island_removal_mode 0)
		)
		(polygon
			(pts
				(xy -154.48566 34.77006) (xy -153.67286 34.77006) (xy -153.67286 33.50006) (xy -154.48566 33.50006)
			)
		)
	)
	(zone
		(layers "In1.Cu" "In2.Cu" "In3.Cu" "In4.Cu" "In5.Cu" "In6.Cu")
		(hatch none 0.5)
		(connect_pads
			(clearance 0)
		)
		(min_thickness 0.25)
		(keepout
			(tracks not_allowed)
			(vias allowed)
			(pads allowed)
			(copperpour not_allowed)
			(footprints allowed)
		)
		(placement
			(enabled no)
			(sheetname "")
		)
		(fill yes
			(thermal_gap 0.5)
			(thermal_bridge_width 0.5)
			(island_removal_mode 0)
		)
		(polygon
			(pts
				(arc
					(start -281.080421 30.087628)
					(mid -282.147221 30.087628)
					(end -281.080421 30.087628)
				)
			)
		)
	)
	(zone
		(layers "In1.Cu" "In2.Cu" "In3.Cu" "In4.Cu" "In5.Cu" "In6.Cu")
		(hatch none 0.5)
		(connect_pads
			(clearance 0)
		)
		(min_thickness 0.25)
		(keepout
			(tracks not_allowed)
			(vias allowed)
			(pads allowed)
			(copperpour not_allowed)
			(footprints allowed)
		)
		(placement
			(enabled no)
			(sheetname "")
		)
		(fill yes
			(thermal_gap 0.5)
			(thermal_bridge_width 0.5)
			(island_removal_mode 0)
		)
		(polygon
			(pts
				(xy -375.48566 29.69006) (xy -374.67286 29.69006) (xy -374.67286 28.42006) (xy -375.48566 28.42006)
			)
		)
	)
	(zone
		(layers "In1.Cu" "In2.Cu" "In3.Cu" "In4.Cu" "In5.Cu" "In6.Cu")
		(hatch none 0.5)
		(connect_pads
			(clearance 0)
		)
		(min_thickness 0.25)
		(keepout
			(tracks not_allowed)
			(vias allowed)
			(pads allowed)
			(copperpour not_allowed)
			(footprints allowed)
		)
		(placement
			(enabled no)
			(sheetname "")
		)
		(fill yes
			(thermal_gap 0.5)
			(thermal_bridge_width 0.5)
			(island_removal_mode 0)
		)
		(polygon
			(pts
				(xy -153.21566 42.39006) (xy -152.40286 42.39006) (xy -152.40286 41.12006) (xy -153.21566 41.12006)
			)
		)
	)
	(zone
		(layers "In1.Cu" "In2.Cu" "In3.Cu" "In4.Cu" "In5.Cu" "In6.Cu")
		(hatch none 0.5)
		(connect_pads
			(clearance 0)
		)
		(min_thickness 0.25)
		(keepout
			(tracks not_allowed)
			(vias allowed)
			(pads allowed)
			(copperpour not_allowed)
			(footprints allowed)
		)
		(placement
			(enabled no)
			(sheetname "")
		)
		(fill yes
			(thermal_gap 0.5)
			(thermal_bridge_width 0.5)
			(island_removal_mode 0)
		)
		(polygon
			(pts
				(arc
					(start -100.922902 46.645576)
					(mid -101.989702 46.645576)
					(end -100.922902 46.645576)
				)
			)
		)
	)
	(zone
		(layers "In1.Cu" "In2.Cu" "In3.Cu" "In4.Cu" "In5.Cu" "In6.Cu")
		(hatch none 0.5)
		(connect_pads
			(clearance 0)
		)
		(min_thickness 0.25)
		(keepout
			(tracks not_allowed)
			(vias allowed)
			(pads allowed)
			(copperpour not_allowed)
			(footprints allowed)
		)
		(placement
			(enabled no)
			(sheetname "")
		)
		(fill yes
			(thermal_gap 0.5)
			(thermal_bridge_width 0.5)
			(island_removal_mode 0)
		)
		(polygon
			(pts
				(arc
					(start -88.496336 38.076381)
					(mid -89.563136 38.076381)
					(end -88.496336 38.076381)
				)
			)
		)
	)
	(zone
		(layers "In1.Cu" "In2.Cu" "In3.Cu" "In4.Cu" "In5.Cu" "In6.Cu")
		(hatch none 0.5)
		(connect_pads
			(clearance 0)
		)
		(min_thickness 0.25)
		(keepout
			(tracks not_allowed)
			(vias allowed)
			(pads allowed)
			(copperpour not_allowed)
			(footprints allowed)
		)
		(placement
			(enabled no)
			(sheetname "")
		)
		(fill yes
			(thermal_gap 0.5)
			(thermal_bridge_width 0.5)
			(island_removal_mode 0)
		)
		(polygon
			(pts
				(arc
					(start -281.080421 30.900428)
					(mid -282.147221 30.900428)
					(end -281.080421 30.900428)
				)
			)
		)
	)
	(zone
		(layers "In1.Cu" "In2.Cu" "In3.Cu" "In4.Cu" "In5.Cu" "In6.Cu")
		(hatch none 0.5)
		(connect_pads
			(clearance 0)
		)
		(min_thickness 0.25)
		(keepout
			(tracks not_allowed)
			(vias allowed)
			(pads allowed)
			(copperpour not_allowed)
			(footprints allowed)
		)
		(placement
			(enabled no)
			(sheetname "")
		)
		(fill yes
			(thermal_gap 0.5)
			(thermal_bridge_width 0.5)
			(island_removal_mode 0)
		)
		(polygon
			(pts
				(xy -153.21566 32.23006) (xy -152.40286 32.23006) (xy -152.40286 30.96006) (xy -153.21566 30.96006)
			)
		)
	)
	(zone
		(layers "In1.Cu" "In2.Cu" "In3.Cu" "In4.Cu" "In5.Cu" "In6.Cu")
		(hatch none 0.5)
		(connect_pads
			(clearance 0)
		)
		(min_thickness 0.25)
		(keepout
			(tracks not_allowed)
			(vias allowed)
			(pads allowed)
			(copperpour not_allowed)
			(footprints allowed)
		)
		(placement
			(enabled no)
			(sheetname "")
		)
		(fill yes
			(thermal_gap 0.5)
			(thermal_bridge_width 0.5)
			(island_removal_mode 0)
		)
		(polygon
			(pts
				(arc
					(start -60.080421 30.087628)
					(mid -61.147221 30.087628)
					(end -60.080421 30.087628)
				)
			)
		)
	)
	(zone
		(layers "In1.Cu" "In2.Cu" "In3.Cu" "In4.Cu" "In5.Cu" "In6.Cu")
		(hatch none 0.5)
		(connect_pads
			(clearance 0)
		)
		(min_thickness 0.25)
		(keepout
			(tracks not_allowed)
			(vias allowed)
			(pads allowed)
			(copperpour not_allowed)
			(footprints allowed)
		)
		(placement
			(enabled no)
			(sheetname "")
		)
		(fill yes
			(thermal_gap 0.5)
			(thermal_bridge_width 0.5)
			(island_removal_mode 0)
		)
		(polygon
			(pts
				(xy -61.149006 30.900527) (xy -60.082206 30.900527) (xy -60.082206 30.087727) (xy -61.149006 30.087727)
			)
		)
	)
	(zone
		(layers "In1.Cu" "In2.Cu" "In3.Cu" "In4.Cu" "In5.Cu" "In6.Cu")
		(hatch none 0.5)
		(connect_pads
			(clearance 0)
		)
		(min_thickness 0.25)
		(keepout
			(tracks not_allowed)
			(vias allowed)
			(pads allowed)
			(copperpour not_allowed)
			(footprints allowed)
		)
		(placement
			(enabled no)
			(sheetname "")
		)
		(fill yes
			(thermal_gap 0.5)
			(thermal_bridge_width 0.5)
			(island_removal_mode 0)
		)
		(polygon
			(pts
				(xy -154.48566 24.61006) (xy -153.67286 24.61006) (xy -153.67286 23.34006) (xy -154.48566 23.34006)
			)
		)
	)
	(zone
		(layers "In1.Cu" "In2.Cu" "In3.Cu" "In4.Cu" "In5.Cu" "In6.Cu")
		(hatch none 0.5)
		(connect_pads
			(clearance 0)
		)
		(min_thickness 0.25)
		(keepout
			(tracks not_allowed)
			(vias allowed)
			(pads allowed)
			(copperpour not_allowed)
			(footprints allowed)
		)
		(placement
			(enabled no)
			(sheetname "")
		)
		(fill yes
			(thermal_gap 0.5)
			(thermal_bridge_width 0.5)
			(island_removal_mode 0)
		)
		(polygon
			(pts
				(xy -375.48566 24.61006) (xy -374.67286 24.61006) (xy -374.67286 23.34006) (xy -375.48566 23.34006)
			)
		)
	)
	(zone
		(layers "In1.Cu" "In2.Cu" "In3.Cu" "In4.Cu" "In5.Cu" "In6.Cu")
		(hatch none 0.5)
		(connect_pads
			(clearance 0)
		)
		(min_thickness 0.25)
		(keepout
			(tracks not_allowed)
			(vias allowed)
			(pads allowed)
			(copperpour not_allowed)
			(footprints allowed)
		)
		(placement
			(enabled no)
			(sheetname "")
		)
		(fill yes
			(thermal_gap 0.5)
			(thermal_bridge_width 0.5)
			(island_removal_mode 0)
		)
		(polygon
			(pts
				(xy -374.21566 32.23006) (xy -373.40286 32.23006) (xy -373.40286 30.96006) (xy -374.21566 30.96006)
			)
		)
	)
	(zone
		(layers "In1.Cu" "In2.Cu" "In3.Cu" "In4.Cu" "In5.Cu" "In6.Cu")
		(hatch none 0.5)
		(connect_pads
			(clearance 0)
		)
		(min_thickness 0.25)
		(keepout
			(tracks not_allowed)
			(vias allowed)
			(pads allowed)
			(copperpour not_allowed)
			(footprints allowed)
		)
		(placement
			(enabled no)
			(sheetname "")
		)
		(fill yes
			(thermal_gap 0.5)
			(thermal_bridge_width 0.5)
			(island_removal_mode 0)
		)
		(polygon
			(pts
				(arc
					(start -89.309136 38.076381)
					(mid -90.375936 38.076381)
					(end -89.309136 38.076381)
				)
			)
		)
	)
	(zone
		(layers "In1.Cu" "In2.Cu" "In3.Cu" "In4.Cu" "In5.Cu" "In6.Cu")
		(hatch none 0.5)
		(connect_pads
			(clearance 0)
		)
		(min_thickness 0.25)
		(keepout
			(tracks not_allowed)
			(vias allowed)
			(pads allowed)
			(copperpour not_allowed)
			(footprints allowed)
		)
		(placement
			(enabled no)
			(sheetname "")
		)
		(fill yes
			(thermal_gap 0.5)
			(thermal_bridge_width 0.5)
			(island_removal_mode 0)
		)
		(polygon
			(pts
				(arc
					(start -309.496336 38.076381)
					(mid -310.563136 38.076381)
					(end -309.496336 38.076381)
				)
			)
		)
	)
	(zone
		(layers "In1.Cu" "In2.Cu" "In3.Cu" "In4.Cu" "In5.Cu" "In6.Cu")
		(hatch none 0.5)
		(connect_pads
			(clearance 0)
		)
		(min_thickness 0.25)
		(keepout
			(tracks not_allowed)
			(vias allowed)
			(pads allowed)
			(copperpour not_allowed)
			(footprints allowed)
		)
		(placement
			(enabled no)
			(sheetname "")
		)
		(fill yes
			(thermal_gap 0.5)
			(thermal_bridge_width 0.5)
			(island_removal_mode 0)
		)
		(polygon
			(pts
				(arc
					(start -63.0101 39.41826)
					(mid -64.0769 39.41826)
					(end -63.0101 39.41826)
				)
			)
		)
	)
	(zone
		(layers "In1.Cu" "In2.Cu" "In3.Cu" "In4.Cu" "In5.Cu" "In6.Cu")
		(hatch none 0.5)
		(connect_pads
			(clearance 0)
		)
		(min_thickness 0.25)
		(keepout
			(tracks not_allowed)
			(vias allowed)
			(pads allowed)
			(copperpour not_allowed)
			(footprints allowed)
		)
		(placement
			(enabled no)
			(sheetname "")
		)
		(fill yes
			(thermal_gap 0.5)
			(thermal_bridge_width 0.5)
			(island_removal_mode 0)
		)
		(polygon
			(pts
				(arc
					(start -321.110102 46.645576)
					(mid -322.176902 46.645576)
					(end -321.110102 46.645576)
				)
			)
		)
	)
	(zone
		(layers "In1.Cu" "In2.Cu" "In3.Cu" "In4.Cu" "In5.Cu" "In6.Cu")
		(hatch none 0.5)
		(connect_pads
			(clearance 0)
		)
		(min_thickness 0.25)
		(keepout
			(tracks not_allowed)
			(vias allowed)
			(pads allowed)
			(copperpour not_allowed)
			(footprints allowed)
		)
		(placement
			(enabled no)
			(sheetname "")
		)
		(fill yes
			(thermal_gap 0.5)
			(thermal_bridge_width 0.5)
			(island_removal_mode 0)
		)
		(polygon
			(pts
				(arc
					(start -319.106555 36.68837)
					(mid -320.173355 36.68837)
					(end -319.106555 36.68837)
				)
			)
		)
	)
	(zone
		(layers "In1.Cu" "In2.Cu" "In3.Cu" "In4.Cu" "In5.Cu" "In6.Cu")
		(hatch none 0.5)
		(connect_pads
			(clearance 0)
		)
		(min_thickness 0.25)
		(keepout
			(tracks not_allowed)
			(vias allowed)
			(pads allowed)
			(copperpour not_allowed)
			(footprints allowed)
		)
		(placement
			(enabled no)
			(sheetname "")
		)
		(fill yes
			(thermal_gap 0.5)
			(thermal_bridge_width 0.5)
			(island_removal_mode 0)
		)
		(polygon
			(pts
				(arc
					(start -319.919355 36.68837)
					(mid -320.986155 36.68837)
					(end -319.919355 36.68837)
				)
			)
		)
	)
	(zone
		(layers "In1.Cu" "In2.Cu" "In3.Cu" "In4.Cu" "In5.Cu" "In6.Cu")
		(hatch none 0.5)
		(connect_pads
			(clearance 0)
		)
		(min_thickness 0.25)
		(keepout
			(tracks not_allowed)
			(vias allowed)
			(pads allowed)
			(copperpour not_allowed)
			(footprints allowed)
		)
		(placement
			(enabled no)
			(sheetname "")
		)
		(fill yes
			(thermal_gap 0.5)
			(thermal_bridge_width 0.5)
			(island_removal_mode 0)
		)
		(polygon
			(pts
				(arc
					(start -284.8229 39.41826)
					(mid -285.8897 39.41826)
					(end -284.8229 39.41826)
				)
			)
		)
	)
	(zone
		(layers "In1.Cu" "In2.Cu" "In3.Cu" "In4.Cu" "In5.Cu" "In6.Cu")
		(hatch none 0.5)
		(connect_pads
			(clearance 0)
		)
		(min_thickness 0.25)
		(keepout
			(tracks not_allowed)
			(vias allowed)
			(pads allowed)
			(copperpour not_allowed)
			(footprints allowed)
		)
		(placement
			(enabled no)
			(sheetname "")
		)
		(fill yes
			(thermal_gap 0.5)
			(thermal_bridge_width 0.5)
			(island_removal_mode 0)
		)
		(polygon
			(pts
				(xy -374.21566 22.07006) (xy -373.40286 22.07006) (xy -373.40286 20.80006) (xy -374.21566 20.80006)
			)
		)
	)
	(zone
		(layers "In1.Cu" "In2.Cu" "In3.Cu" "In4.Cu" "In5.Cu" "In6.Cu")
		(hatch none 0.5)
		(connect_pads
			(clearance 0)
		)
		(min_thickness 0.25)
		(keepout
			(tracks not_allowed)
			(vias allowed)
			(pads allowed)
			(copperpour not_allowed)
			(footprints allowed)
		)
		(placement
			(enabled no)
			(sheetname "")
		)
		(fill yes
			(thermal_gap 0.5)
			(thermal_bridge_width 0.5)
			(island_removal_mode 0)
		)
		(polygon
			(pts
				(xy -374.21566 42.39006) (xy -373.40286 42.39006) (xy -373.40286 41.12006) (xy -374.21566 41.12006)
			)
		)
	)
	(zone
		(layers "In1.Cu" "In2.Cu" "In3.Cu" "In4.Cu" "In5.Cu" "In6.Cu")
		(hatch none 0.5)
		(connect_pads
			(clearance 0)
		)
		(min_thickness 0.25)
		(keepout
			(tracks not_allowed)
			(vias allowed)
			(pads allowed)
			(copperpour not_allowed)
			(footprints allowed)
		)
		(placement
			(enabled no)
			(sheetname "")
		)
		(fill yes
			(thermal_gap 0.5)
			(thermal_bridge_width 0.5)
			(island_removal_mode 0)
		)
		(polygon
			(pts
				(xy -153.21566 27.15006) (xy -152.40286 27.15006) (xy -152.40286 25.88006) (xy -153.21566 25.88006)
			)
		)
	)
	(zone
		(layers "In1.Cu" "In2.Cu" "In3.Cu" "In4.Cu" "In5.Cu" "In6.Cu")
		(hatch none 0.5)
		(connect_pads
			(clearance 0)
		)
		(min_thickness 0.25)
		(keepout
			(tracks not_allowed)
			(vias allowed)
			(pads allowed)
			(copperpour not_allowed)
			(footprints allowed)
		)
		(placement
			(enabled no)
			(sheetname "")
		)
		(fill yes
			(thermal_gap 0.5)
			(thermal_bridge_width 0.5)
			(island_removal_mode 0)
		)
		(polygon
			(pts
				(xy -282.149006 30.900527) (xy -281.082206 30.900527) (xy -281.082206 30.087727) (xy -282.149006 30.087727)
			)
		)
	)
	(zone
		(layers "In1.Cu" "In2.Cu" "In3.Cu" "In4.Cu" "In5.Cu" "In6.Cu")
		(hatch none 0.5)
		(connect_pads
			(clearance 0)
		)
		(min_thickness 0.25)
		(keepout
			(tracks not_allowed)
			(vias allowed)
			(pads allowed)
			(copperpour not_allowed)
			(footprints allowed)
		)
		(placement
			(enabled no)
			(sheetname "")
		)
		(fill yes
			(thermal_gap 0.5)
			(thermal_bridge_width 0.5)
			(island_removal_mode 0)
		)
		(polygon
			(pts
				(arc
					(start -63.8229 39.41826)
					(mid -64.8897 39.41826)
					(end -63.8229 39.41826)
				)
			)
		)
	)
	(zone
		(layers "In1.Cu" "In2.Cu" "In3.Cu" "In4.Cu" "In5.Cu" "In6.Cu")
		(hatch none 0.5)
		(connect_pads
			(clearance 0)
		)
		(min_thickness 0.25)
		(keepout
			(tracks not_allowed)
			(vias allowed)
			(pads allowed)
			(copperpour not_allowed)
			(footprints allowed)
		)
		(placement
			(enabled no)
			(sheetname "")
		)
		(fill yes
			(thermal_gap 0.5)
			(thermal_bridge_width 0.5)
			(island_removal_mode 0)
		)
		(polygon
			(pts
				(xy -153.21566 22.07006) (xy -152.40286 22.07006) (xy -152.40286 20.80006) (xy -153.21566 20.80006)
			)
		)
	)
	(zone
		(layers "In1.Cu" "In2.Cu" "In3.Cu" "In4.Cu" "In5.Cu" "In6.Cu")
		(hatch none 0.5)
		(connect_pads
			(clearance 0)
		)
		(min_thickness 0.25)
		(keepout
			(tracks not_allowed)
			(vias allowed)
			(pads allowed)
			(copperpour not_allowed)
			(footprints allowed)
		)
		(placement
			(enabled no)
			(sheetname "")
		)
		(fill yes
			(thermal_gap 0.5)
			(thermal_bridge_width 0.5)
			(island_removal_mode 0)
		)
		(polygon
			(pts
				(arc
					(start -321.922902 46.645576)
					(mid -322.989702 46.645576)
					(end -321.922902 46.645576)
				)
			)
		)
	)
	(zone
		(layers "In1.Cu" "In2.Cu" "In3.Cu" "In4.Cu" "In5.Cu" "In6.Cu")
		(hatch none 0.5)
		(connect_pads
			(clearance 0)
		)
		(min_thickness 0.25)
		(keepout
			(tracks not_allowed)
			(vias allowed)
			(pads allowed)
			(copperpour not_allowed)
			(footprints allowed)
		)
		(placement
			(enabled no)
			(sheetname "")
		)
		(fill yes
			(thermal_gap 0.5)
			(thermal_bridge_width 0.5)
			(island_removal_mode 0)
		)
		(polygon
			(pts
				(xy -375.48566 39.85006) (xy -374.67286 39.85006) (xy -374.67286 38.58006) (xy -375.48566 38.58006)
			)
		)
	)
	(zone
		(layers "In1.Cu" "In2.Cu" "In3.Cu" "In4.Cu" "In5.Cu" "In6.Cu")
		(hatch none 0.5)
		(connect_pads
			(clearance 0)
		)
		(min_thickness 0.25)
		(keepout
			(tracks not_allowed)
			(vias allowed)
			(pads allowed)
			(copperpour not_allowed)
			(footprints allowed)
		)
		(placement
			(enabled no)
			(sheetname "")
		)
		(fill yes
			(thermal_gap 0.5)
			(thermal_bridge_width 0.5)
			(island_removal_mode 0)
		)
		(polygon
			(pts
				(arc
					(start -284.0101 39.41826)
					(mid -285.0769 39.41826)
					(end -284.0101 39.41826)
				)
			)
		)
	)
	(zone
		(layers "In1.Cu" "In2.Cu" "In3.Cu" "In4.Cu" "In5.Cu" "In6.Cu")
		(hatch none 0.5)
		(connect_pads
			(clearance 0)
		)
		(min_thickness 0.25)
		(keepout
			(tracks not_allowed)
			(vias allowed)
			(pads allowed)
			(copperpour not_allowed)
			(footprints allowed)
		)
		(placement
			(enabled no)
			(sheetname "")
		)
		(fill yes
			(thermal_gap 0.5)
			(thermal_bridge_width 0.5)
			(island_removal_mode 0)
		)
		(polygon
			(pts
				(arc
					(start -100.110102 46.645576)
					(mid -101.176902 46.645576)
					(end -100.110102 46.645576)
				)
			)
		)
	)
	(zone
		(layers "In1.Cu" "In2.Cu" "In3.Cu" "In4.Cu" "In5.Cu" "In6.Cu")
		(hatch none 0.5)
		(connect_pads
			(clearance 0)
		)
		(min_thickness 0.25)
		(keepout
			(tracks not_allowed)
			(vias allowed)
			(pads allowed)
			(copperpour not_allowed)
			(footprints allowed)
		)
		(placement
			(enabled no)
			(sheetname "")
		)
		(fill yes
			(thermal_gap 0.5)
			(thermal_bridge_width 0.5)
			(island_removal_mode 0)
		)
		(polygon
			(pts
				(xy -375.48566 34.77006) (xy -374.67286 34.77006) (xy -374.67286 33.50006) (xy -375.48566 33.50006)
			)
		)
	)
	(zone
		(layers "In1.Cu" "In2.Cu" "In3.Cu" "In4.Cu" "In5.Cu" "In6.Cu")
		(hatch none 0.5)
		(connect_pads
			(clearance 0)
		)
		(min_thickness 0.25)
		(keepout
			(tracks not_allowed)
			(vias allowed)
			(pads allowed)
			(copperpour not_allowed)
			(footprints allowed)
		)
		(placement
			(enabled no)
			(sheetname "")
		)
		(fill yes
			(thermal_gap 0.5)
			(thermal_bridge_width 0.5)
			(island_removal_mode 0)
		)
		(polygon
			(pts
				(xy -154.48566 29.69006) (xy -153.67286 29.69006) (xy -153.67286 28.42006) (xy -154.48566 28.42006)
			)
		)
	)
	(zone
		(layers "In1.Cu" "In2.Cu" "In3.Cu" "In4.Cu" "In6.Cu")
		(hatch none 0.5)
		(connect_pads
			(clearance 0)
		)
		(min_thickness 0.25)
		(keepout
			(tracks not_allowed)
			(vias allowed)
			(pads allowed)
			(copperpour not_allowed)
			(footprints allowed)
		)
		(placement
			(enabled no)
			(sheetname "")
		)
		(fill yes
			(thermal_gap 0.5)
			(thermal_bridge_width 0.5)
			(island_removal_mode 0)
		)
		(polygon
			(pts
				(arc
					(start -311.910103 34.126681)
					(mid -312.976903 34.126681)
					(end -311.910103 34.126681)
				)
			)
		)
	)
	(zone
		(layers "In1.Cu" "In2.Cu" "In3.Cu" "In4.Cu" "In6.Cu")
		(hatch none 0.5)
		(connect_pads
			(clearance 0)
		)
		(min_thickness 0.25)
		(keepout
			(tracks not_allowed)
			(vias allowed)
			(pads allowed)
			(copperpour not_allowed)
			(footprints allowed)
		)
		(placement
			(enabled no)
			(sheetname "")
		)
		(fill yes
			(thermal_gap 0.5)
			(thermal_bridge_width 0.5)
			(island_removal_mode 0)
		)
		(polygon
			(pts
				(arc
					(start -312.480861 47.088301)
					(mid -313.547661 47.088301)
					(end -312.480861 47.088301)
				)
			)
		)
	)
	(zone
		(layers "In1.Cu" "In2.Cu" "In3.Cu" "In4.Cu" "In6.Cu")
		(hatch none 0.5)
		(connect_pads
			(clearance 0)
		)
		(min_thickness 0.25)
		(keepout
			(tracks not_allowed)
			(vias allowed)
			(pads allowed)
			(copperpour not_allowed)
			(footprints allowed)
		)
		(placement
			(enabled no)
			(sheetname "")
		)
		(fill yes
			(thermal_gap 0.5)
			(thermal_bridge_width 0.5)
			(island_removal_mode 0)
		)
		(polygon
			(pts
				(arc
					(start -315.880138 47.423128)
					(mid -316.946938 47.423128)
					(end -315.880138 47.423128)
				)
			)
		)
	)
	(zone
		(layers "In1.Cu" "In2.Cu" "In3.Cu" "In4.Cu" "In6.Cu")
		(hatch none 0.5)
		(connect_pads
			(clearance 0)
		)
		(min_thickness 0.25)
		(keepout
			(tracks not_allowed)
			(vias allowed)
			(pads allowed)
			(copperpour not_allowed)
			(footprints allowed)
		)
		(placement
			(enabled no)
			(sheetname "")
		)
		(fill yes
			(thermal_gap 0.5)
			(thermal_bridge_width 0.5)
			(island_removal_mode 0)
		)
		(polygon
			(pts
				(arc
					(start -94.880138 48.235928)
					(mid -95.946938 48.235928)
					(end -94.880138 48.235928)
				)
			)
		)
	)
	(zone
		(layers "In1.Cu" "In2.Cu" "In3.Cu" "In4.Cu" "In6.Cu")
		(hatch none 0.5)
		(connect_pads
			(clearance 0)
		)
		(min_thickness 0.25)
		(keepout
			(tracks not_allowed)
			(vias allowed)
			(pads allowed)
			(copperpour not_allowed)
			(footprints allowed)
		)
		(placement
			(enabled no)
			(sheetname "")
		)
		(fill yes
			(thermal_gap 0.5)
			(thermal_bridge_width 0.5)
			(island_removal_mode 0)
		)
		(polygon
			(pts
				(arc
					(start -306.659181 42.511221)
					(mid -307.725981 42.511221)
					(end -306.659181 42.511221)
				)
			)
		)
	)
	(zone
		(layers "In1.Cu" "In2.Cu" "In3.Cu" "In4.Cu" "In6.Cu")
		(hatch none 0.5)
		(connect_pads
			(clearance 0)
		)
		(min_thickness 0.25)
		(keepout
			(tracks not_allowed)
			(vias allowed)
			(pads allowed)
			(copperpour not_allowed)
			(footprints allowed)
		)
		(placement
			(enabled no)
			(sheetname "")
		)
		(fill yes
			(thermal_gap 0.5)
			(thermal_bridge_width 0.5)
			(island_removal_mode 0)
		)
		(polygon
			(pts
				(arc
					(start -84.846381 42.511221)
					(mid -85.913181 42.511221)
					(end -84.846381 42.511221)
				)
			)
		)
	)
	(zone
		(layers "In1.Cu" "In2.Cu" "In3.Cu" "In4.Cu" "In6.Cu")
		(hatch none 0.5)
		(connect_pads
			(clearance 0)
		)
		(min_thickness 0.25)
		(keepout
			(tracks not_allowed)
			(vias allowed)
			(pads allowed)
			(copperpour not_allowed)
			(footprints allowed)
		)
		(placement
			(enabled no)
			(sheetname "")
		)
		(fill yes
			(thermal_gap 0.5)
			(thermal_bridge_width 0.5)
			(island_removal_mode 0)
		)
		(polygon
			(pts
				(arc
					(start -92.293661 47.088301)
					(mid -93.360461 47.088301)
					(end -92.293661 47.088301)
				)
			)
		)
	)
	(zone
		(layers "In1.Cu" "In2.Cu" "In3.Cu" "In4.Cu" "In6.Cu")
		(hatch none 0.5)
		(connect_pads
			(clearance 0)
		)
		(min_thickness 0.25)
		(keepout
			(tracks not_allowed)
			(vias allowed)
			(pads allowed)
			(copperpour not_allowed)
			(footprints allowed)
		)
		(placement
			(enabled no)
			(sheetname "")
		)
		(fill yes
			(thermal_gap 0.5)
			(thermal_bridge_width 0.5)
			(island_removal_mode 0)
		)
		(polygon
			(pts
				(arc
					(start -85.659181 42.511221)
					(mid -86.725981 42.511221)
					(end -85.659181 42.511221)
				)
			)
		)
	)
	(zone
		(layers "In1.Cu" "In2.Cu" "In3.Cu" "In4.Cu" "In6.Cu")
		(hatch none 0.5)
		(connect_pads
			(clearance 0)
		)
		(min_thickness 0.25)
		(keepout
			(tracks not_allowed)
			(vias allowed)
			(pads allowed)
			(copperpour not_allowed)
			(footprints allowed)
		)
		(placement
			(enabled no)
			(sheetname "")
		)
		(fill yes
			(thermal_gap 0.5)
			(thermal_bridge_width 0.5)
			(island_removal_mode 0)
		)
		(polygon
			(pts
				(arc
					(start -91.722903 34.126681)
					(mid -92.789703 34.126681)
					(end -91.722903 34.126681)
				)
			)
		)
	)
	(zone
		(layers "In1.Cu" "In2.Cu" "In3.Cu" "In4.Cu" "In6.Cu")
		(hatch none 0.5)
		(connect_pads
			(clearance 0)
		)
		(min_thickness 0.25)
		(keepout
			(tracks not_allowed)
			(vias allowed)
			(pads allowed)
			(copperpour not_allowed)
			(footprints allowed)
		)
		(placement
			(enabled no)
			(sheetname "")
		)
		(fill yes
			(thermal_gap 0.5)
			(thermal_bridge_width 0.5)
			(island_removal_mode 0)
		)
		(polygon
			(pts
				(arc
					(start -90.910103 34.126681)
					(mid -91.976903 34.126681)
					(end -90.910103 34.126681)
				)
			)
		)
	)
	(zone
		(layers "In1.Cu" "In2.Cu" "In3.Cu" "In4.Cu" "In6.Cu")
		(hatch none 0.5)
		(connect_pads
			(clearance 0)
		)
		(min_thickness 0.25)
		(keepout
			(tracks not_allowed)
			(vias allowed)
			(pads allowed)
			(copperpour not_allowed)
			(footprints allowed)
		)
		(placement
			(enabled no)
			(sheetname "")
		)
		(fill yes
			(thermal_gap 0.5)
			(thermal_bridge_width 0.5)
			(island_removal_mode 0)
		)
		(polygon
			(pts
				(arc
					(start -315.880138 48.235928)
					(mid -316.946938 48.235928)
					(end -315.880138 48.235928)
				)
			)
		)
	)
	(zone
		(layers "In1.Cu" "In2.Cu" "In3.Cu" "In4.Cu" "In6.Cu")
		(hatch none 0.5)
		(connect_pads
			(clearance 0)
		)
		(min_thickness 0.25)
		(keepout
			(tracks not_allowed)
			(vias allowed)
			(pads allowed)
			(copperpour not_allowed)
			(footprints allowed)
		)
		(placement
			(enabled no)
			(sheetname "")
		)
		(fill yes
			(thermal_gap 0.5)
			(thermal_bridge_width 0.5)
			(island_removal_mode 0)
		)
		(polygon
			(pts
				(arc
					(start -305.846381 42.511221)
					(mid -306.913181 42.511221)
					(end -305.846381 42.511221)
				)
			)
		)
	)
	(zone
		(layers "In1.Cu" "In2.Cu" "In3.Cu" "In4.Cu" "In6.Cu")
		(hatch none 0.5)
		(connect_pads
			(clearance 0)
		)
		(min_thickness 0.25)
		(keepout
			(tracks not_allowed)
			(vias allowed)
			(pads allowed)
			(copperpour not_allowed)
			(footprints allowed)
		)
		(placement
			(enabled no)
			(sheetname "")
		)
		(fill yes
			(thermal_gap 0.5)
			(thermal_bridge_width 0.5)
			(island_removal_mode 0)
		)
		(polygon
			(pts
				(xy -95.948724 48.236027) (xy -94.881924 48.236027) (xy -94.881924 47.423227) (xy -95.948724 47.423227)
			)
		)
	)
	(zone
		(layers "In1.Cu" "In2.Cu" "In3.Cu" "In4.Cu" "In6.Cu")
		(hatch none 0.5)
		(connect_pads
			(clearance 0)
		)
		(min_thickness 0.25)
		(keepout
			(tracks not_allowed)
			(vias allowed)
			(pads allowed)
			(copperpour not_allowed)
			(footprints allowed)
		)
		(placement
			(enabled no)
			(sheetname "")
		)
		(fill yes
			(thermal_gap 0.5)
			(thermal_bridge_width 0.5)
			(island_removal_mode 0)
		)
		(polygon
			(pts
				(arc
					(start -91.480861 47.088301)
					(mid -92.547661 47.088301)
					(end -91.480861 47.088301)
				)
			)
		)
	)
	(zone
		(layers "In1.Cu" "In2.Cu" "In3.Cu" "In4.Cu" "In6.Cu")
		(hatch none 0.5)
		(connect_pads
			(clearance 0)
		)
		(min_thickness 0.25)
		(keepout
			(tracks not_allowed)
			(vias allowed)
			(pads allowed)
			(copperpour not_allowed)
			(footprints allowed)
		)
		(placement
			(enabled no)
			(sheetname "")
		)
		(fill yes
			(thermal_gap 0.5)
			(thermal_bridge_width 0.5)
			(island_removal_mode 0)
		)
		(polygon
			(pts
				(xy -316.948723 48.236027) (xy -315.881923 48.236027) (xy -315.881923 47.423227) (xy -316.948723 47.423227)
			)
		)
	)
	(zone
		(layers "In1.Cu" "In2.Cu" "In3.Cu" "In4.Cu" "In6.Cu")
		(hatch none 0.5)
		(connect_pads
			(clearance 0)
		)
		(min_thickness 0.25)
		(keepout
			(tracks not_allowed)
			(vias allowed)
			(pads allowed)
			(copperpour not_allowed)
			(footprints allowed)
		)
		(placement
			(enabled no)
			(sheetname "")
		)
		(fill yes
			(thermal_gap 0.5)
			(thermal_bridge_width 0.5)
			(island_removal_mode 0)
		)
		(polygon
			(pts
				(arc
					(start -312.722903 34.126681)
					(mid -313.789703 34.126681)
					(end -312.722903 34.126681)
				)
			)
		)
	)
	(zone
		(layers "In1.Cu" "In2.Cu" "In3.Cu" "In4.Cu" "In6.Cu")
		(hatch none 0.5)
		(connect_pads
			(clearance 0)
		)
		(min_thickness 0.25)
		(keepout
			(tracks not_allowed)
			(vias allowed)
			(pads allowed)
			(copperpour not_allowed)
			(footprints allowed)
		)
		(placement
			(enabled no)
			(sheetname "")
		)
		(fill yes
			(thermal_gap 0.5)
			(thermal_bridge_width 0.5)
			(island_removal_mode 0)
		)
		(polygon
			(pts
				(arc
					(start -313.293661 47.088301)
					(mid -314.360461 47.088301)
					(end -313.293661 47.088301)
				)
			)
		)
	)
	(zone
		(layers "In1.Cu" "In2.Cu" "In3.Cu" "In4.Cu" "In6.Cu")
		(hatch none 0.5)
		(connect_pads
			(clearance 0)
		)
		(min_thickness 0.25)
		(keepout
			(tracks not_allowed)
			(vias allowed)
			(pads allowed)
			(copperpour not_allowed)
			(footprints allowed)
		)
		(placement
			(enabled no)
			(sheetname "")
		)
		(fill yes
			(thermal_gap 0.5)
			(thermal_bridge_width 0.5)
			(island_removal_mode 0)
		)
		(polygon
			(pts
				(arc
					(start -94.880138 47.423128)
					(mid -95.946938 47.423128)
					(end -94.880138 47.423128)
				)
			)
		)
	)
	(zone
		(net "GND")
		(layer "In2.Cu")
		(hatch none 0.5)
		(connect_pads
			(clearance 0.5)
		)
		(min_thickness 0.25)
		(fill yes
			(thermal_gap 0.5)
			(thermal_bridge_width 0.5)
			(island_removal_mode 0)
		)
		(polygon
			(pts
				(xy -260.858 46.482) (xy -260.858 -3.8862) (xy -260.858 -4.1783) (xy -260.8453 -4.191) (xy -260.5913 -4.191)
				(xy -116.586 -4.191) (xy -116.586 21.971) (xy -112.522 26.035) (xy -108.585 26.035) (xy -107.188 27.432)
				(xy -107.188 45.974) (xy -120.269 45.974) (xy -120.396 46.101) (xy -148.463 46.101) (xy -148.463 18.034)
				(xy -152.6794 13.8176) (xy -152.6794 13.7922) (xy -181.6608 13.7922) (xy -182.4736 14.605) (xy -182.4736 14.6304)
				(xy -191.516 23.6728) (xy -191.516 46.482)
			)
		)
	)
	(zone
		(net "P12V")
		(layer "In2.Cu")
		(hatch none 0.5)
		(connect_pads
			(clearance 0.5)
		)
		(min_thickness 0.25)
		(fill yes
			(thermal_gap 0.5)
			(thermal_bridge_width 0.5)
			(island_removal_mode 0)
		)
		(polygon
			(pts
				(xy -369.3414 46.7233) (xy -369.32235 46.70425) (xy -369.67795 46.70425) (xy -369.697 46.6852) (xy -369.697 22.86)
				(xy -367.9444 21.1074) (xy -367.9444 21.082) (xy -367.2078 20.3454) (xy -367.2078 15.0622) (xy -369.4684 12.8016)
				(xy -408.178 12.8016) (xy -411.81529 9.16431)
				(arc
					(start -411.81529 5.705434)
					(mid -411.074856 5.505358)
					(end -410.7512 4.810001)
				)
				(xy -410.7512 -4.108536) (xy -410.521417 -4.33832) (xy -371.168585 -4.33832) (xy -370.938801 -4.108536)
				(arc
					(start -370.938801 3.66)
					(mid -370.335792 5.115791)
					(end -368.880001 5.7188)
				)
				(arc
					(start -367.879998 5.7188)
					(mid -366.424207 5.115791)
					(end -365.821199 3.66)
				)
				(arc
					(start -365.821199 -2.34)
					(mid -365.252635 -3.712635)
					(end -363.880001 -4.2812)
				)
				(xy -337.0212 -4.2812) (xy -336.677 -3.937) (xy -336.677 20.66544) (xy -335.534 21.80844) (xy -335.534 22.987)
				(xy -336.00644 23.45944) (xy -336.00644 24.37892) (xy -335.36636 25.019) (xy -331.2922 25.019) (xy -327.6092 28.702)
				(xy -327.6092 45.6438) (xy -328.6887 46.7233)
			)
		)
	)
	(zone
		(layers "In2.Cu" "In3.Cu" "In4.Cu" "In5.Cu" "In6.Cu")
		(hatch none 0.5)
		(connect_pads
			(clearance 0)
		)
		(min_thickness 0.25)
		(keepout
			(tracks not_allowed)
			(vias allowed)
			(pads allowed)
			(copperpour not_allowed)
			(footprints allowed)
		)
		(placement
			(enabled no)
			(sheetname "")
		)
		(fill yes
			(thermal_gap 0.5)
			(thermal_bridge_width 0.5)
			(island_removal_mode 0)
		)
		(polygon
			(pts
				(xy -322.8564 39.085515) (xy -322.0436 39.085515) (xy -322.0436 38.018715) (xy -322.8564 38.018715)
			)
		)
	)
	(zone
		(layers "In2.Cu" "In3.Cu" "In4.Cu" "In5.Cu" "In6.Cu")
		(hatch none 0.5)
		(connect_pads
			(clearance 0)
		)
		(min_thickness 0.25)
		(keepout
			(tracks not_allowed)
			(vias allowed)
			(pads allowed)
			(copperpour not_allowed)
			(footprints allowed)
		)
		(placement
			(enabled no)
			(sheetname "")
		)
		(fill yes
			(thermal_gap 0.5)
			(thermal_bridge_width 0.5)
			(island_removal_mode 0)
		)
		(polygon
			(pts
				(xy -99.452854 37.219984) (xy -98.640054 37.219984) (xy -98.640054 36.153184) (xy -99.452854 36.153184)
			)
		)
	)
	(zone
		(layers "In2.Cu" "In3.Cu" "In4.Cu" "In5.Cu" "In6.Cu")
		(hatch none 0.5)
		(connect_pads
			(clearance 0)
		)
		(min_thickness 0.25)
		(keepout
			(tracks not_allowed)
			(vias allowed)
			(pads allowed)
			(copperpour not_allowed)
			(footprints allowed)
		)
		(placement
			(enabled no)
			(sheetname "")
		)
		(fill yes
			(thermal_gap 0.5)
			(thermal_bridge_width 0.5)
			(island_removal_mode 0)
		)
		(polygon
			(pts
				(xy -89.842635 38.607995) (xy -89.029835 38.607995) (xy -89.029835 37.541195) (xy -89.842635 37.541195)
			)
		)
	)
	(zone
		(layers "In2.Cu" "In3.Cu" "In4.Cu" "In5.Cu" "In6.Cu")
		(hatch none 0.5)
		(connect_pads
			(clearance 0)
		)
		(min_thickness 0.25)
		(keepout
			(tracks not_allowed)
			(vias allowed)
			(pads allowed)
			(copperpour not_allowed)
			(footprints allowed)
		)
		(placement
			(enabled no)
			(sheetname "")
		)
		(fill yes
			(thermal_gap 0.5)
			(thermal_bridge_width 0.5)
			(island_removal_mode 0)
		)
		(polygon
			(pts
				(xy -101.456401 47.17719) (xy -100.643601 47.17719) (xy -100.643601 46.11039) (xy -101.456401 46.11039)
			)
		)
	)
	(zone
		(layers "In2.Cu" "In3.Cu" "In4.Cu" "In5.Cu" "In6.Cu")
		(hatch none 0.5)
		(connect_pads
			(clearance 0)
		)
		(min_thickness 0.25)
		(keepout
			(tracks not_allowed)
			(vias allowed)
			(pads allowed)
			(copperpour not_allowed)
			(footprints allowed)
		)
		(placement
			(enabled no)
			(sheetname "")
		)
		(fill yes
			(thermal_gap 0.5)
			(thermal_bridge_width 0.5)
			(island_removal_mode 0)
		)
		(polygon
			(pts
				(xy -285.356399 39.949874) (xy -284.543599 39.949874) (xy -284.543599 38.883074) (xy -285.356399 38.883074)
			)
		)
	)
	(zone
		(layers "In2.Cu" "In3.Cu" "In4.Cu" "In5.Cu" "In6.Cu")
		(hatch none 0.5)
		(connect_pads
			(clearance 0)
		)
		(min_thickness 0.25)
		(keepout
			(tracks not_allowed)
			(vias allowed)
			(pads allowed)
			(copperpour not_allowed)
			(footprints allowed)
		)
		(placement
			(enabled no)
			(sheetname "")
		)
		(fill yes
			(thermal_gap 0.5)
			(thermal_bridge_width 0.5)
			(island_removal_mode 0)
		)
		(polygon
			(pts
				(xy -322.456401 47.17719) (xy -321.643601 47.17719) (xy -321.643601 46.11039) (xy -322.456401 46.11039)
			)
		)
	)
	(zone
		(layers "In2.Cu" "In3.Cu" "In4.Cu" "In5.Cu" "In6.Cu")
		(hatch none 0.5)
		(connect_pads
			(clearance 0)
		)
		(min_thickness 0.25)
		(keepout
			(tracks not_allowed)
			(vias allowed)
			(pads allowed)
			(copperpour not_allowed)
			(footprints allowed)
		)
		(placement
			(enabled no)
			(sheetname "")
		)
		(fill yes
			(thermal_gap 0.5)
			(thermal_bridge_width 0.5)
			(island_removal_mode 0)
		)
		(polygon
			(pts
				(xy -101.8564 39.085515) (xy -101.0436 39.085515) (xy -101.0436 38.018715) (xy -101.8564 38.018715)
			)
		)
	)
	(zone
		(layers "In2.Cu" "In3.Cu" "In4.Cu" "In5.Cu" "In6.Cu")
		(hatch none 0.5)
		(connect_pads
			(clearance 0)
		)
		(min_thickness 0.25)
		(keepout
			(tracks not_allowed)
			(vias allowed)
			(pads allowed)
			(copperpour not_allowed)
			(footprints allowed)
		)
		(placement
			(enabled no)
			(sheetname "")
		)
		(fill yes
			(thermal_gap 0.5)
			(thermal_bridge_width 0.5)
			(island_removal_mode 0)
		)
		(polygon
			(pts
				(xy -64.356399 39.949874) (xy -63.543599 39.949874) (xy -63.543599 38.883074) (xy -64.356399 38.883074)
			)
		)
	)
	(zone
		(layers "In2.Cu" "In3.Cu" "In4.Cu" "In5.Cu" "In6.Cu")
		(hatch none 0.5)
		(connect_pads
			(clearance 0)
		)
		(min_thickness 0.25)
		(keepout
			(tracks not_allowed)
			(vias allowed)
			(pads allowed)
			(copperpour not_allowed)
			(footprints allowed)
		)
		(placement
			(enabled no)
			(sheetname "")
		)
		(fill yes
			(thermal_gap 0.5)
			(thermal_bridge_width 0.5)
			(island_removal_mode 0)
		)
		(polygon
			(pts
				(xy -320.452854 37.219984) (xy -319.640054 37.219984) (xy -319.640054 36.153184) (xy -320.452854 36.153184)
			)
		)
	)
	(zone
		(layers "In2.Cu" "In3.Cu" "In4.Cu" "In5.Cu" "In6.Cu")
		(hatch none 0.5)
		(connect_pads
			(clearance 0)
		)
		(min_thickness 0.25)
		(keepout
			(tracks not_allowed)
			(vias allowed)
			(pads allowed)
			(copperpour not_allowed)
			(footprints allowed)
		)
		(placement
			(enabled no)
			(sheetname "")
		)
		(fill yes
			(thermal_gap 0.5)
			(thermal_bridge_width 0.5)
			(island_removal_mode 0)
		)
		(polygon
			(pts
				(xy -310.842635 38.607995) (xy -310.029835 38.607995) (xy -310.029835 37.541195) (xy -310.842635 37.541195)
			)
		)
	)
	(zone
		(layers "In2.Cu" "In3.Cu" "In4.Cu" "In6.Cu")
		(hatch none 0.5)
		(connect_pads
			(clearance 0)
		)
		(min_thickness 0.25)
		(keepout
			(tracks not_allowed)
			(vias allowed)
			(pads allowed)
			(copperpour not_allowed)
			(footprints allowed)
		)
		(placement
			(enabled no)
			(sheetname "")
		)
		(fill yes
			(thermal_gap 0.5)
			(thermal_bridge_width 0.5)
			(island_removal_mode 0)
		)
		(polygon
			(pts
				(xy -313.256402 34.658295) (xy -312.443602 34.658295) (xy -312.443602 33.591495) (xy -313.256402 33.591495)
			)
		)
	)
	(zone
		(layers "In2.Cu" "In3.Cu" "In4.Cu" "In6.Cu")
		(hatch none 0.5)
		(connect_pads
			(clearance 0)
		)
		(min_thickness 0.25)
		(keepout
			(tracks not_allowed)
			(vias allowed)
			(pads allowed)
			(copperpour not_allowed)
			(footprints allowed)
		)
		(placement
			(enabled no)
			(sheetname "")
		)
		(fill yes
			(thermal_gap 0.5)
			(thermal_bridge_width 0.5)
			(island_removal_mode 0)
		)
		(polygon
			(pts
				(xy -92.82716 47.619915) (xy -92.01436 47.619915) (xy -92.01436 46.553115) (xy -92.82716 46.553115)
			)
		)
	)
	(zone
		(layers "In2.Cu" "In3.Cu" "In4.Cu" "In6.Cu")
		(hatch none 0.5)
		(connect_pads
			(clearance 0)
		)
		(min_thickness 0.25)
		(keepout
			(tracks not_allowed)
			(vias allowed)
			(pads allowed)
			(copperpour not_allowed)
			(footprints allowed)
		)
		(placement
			(enabled no)
			(sheetname "")
		)
		(fill yes
			(thermal_gap 0.5)
			(thermal_bridge_width 0.5)
			(island_removal_mode 0)
		)
		(polygon
			(pts
				(xy -313.82716 47.619915) (xy -313.01436 47.619915) (xy -313.01436 46.553115) (xy -313.82716 46.553115)
			)
		)
	)
	(zone
		(layers "In2.Cu" "In3.Cu" "In4.Cu" "In6.Cu")
		(hatch none 0.5)
		(connect_pads
			(clearance 0)
		)
		(min_thickness 0.25)
		(keepout
			(tracks not_allowed)
			(vias allowed)
			(pads allowed)
			(copperpour not_allowed)
			(footprints allowed)
		)
		(placement
			(enabled no)
			(sheetname "")
		)
		(fill yes
			(thermal_gap 0.5)
			(thermal_bridge_width 0.5)
			(island_removal_mode 0)
		)
		(polygon
			(pts
				(xy -92.256402 34.658295) (xy -91.443602 34.658295) (xy -91.443602 33.591495) (xy -92.256402 33.591495)
			)
		)
	)
	(zone
		(layers "In2.Cu" "In3.Cu" "In4.Cu" "In6.Cu")
		(hatch none 0.5)
		(connect_pads
			(clearance 0)
		)
		(min_thickness 0.25)
		(keepout
			(tracks not_allowed)
			(vias allowed)
			(pads allowed)
			(copperpour not_allowed)
			(footprints allowed)
		)
		(placement
			(enabled no)
			(sheetname "")
		)
		(fill yes
			(thermal_gap 0.5)
			(thermal_bridge_width 0.5)
			(island_removal_mode 0)
		)
		(polygon
			(pts
				(xy -307.19268 43.042835) (xy -306.37988 43.042835) (xy -306.37988 41.976035) (xy -307.19268 41.976035)
			)
		)
	)
	(zone
		(layers "In2.Cu" "In3.Cu" "In4.Cu" "In6.Cu")
		(hatch none 0.5)
		(connect_pads
			(clearance 0)
		)
		(min_thickness 0.25)
		(keepout
			(tracks not_allowed)
			(vias allowed)
			(pads allowed)
			(copperpour not_allowed)
			(footprints allowed)
		)
		(placement
			(enabled no)
			(sheetname "")
		)
		(fill yes
			(thermal_gap 0.5)
			(thermal_bridge_width 0.5)
			(island_removal_mode 0)
		)
		(polygon
			(pts
				(xy -86.19268 43.042835) (xy -85.37988 43.042835) (xy -85.37988 41.976035) (xy -86.19268 41.976035)
			)
		)
	)
	(zone
		(net "GND")
		(layer "In3.Cu")
		(hatch none 0.5)
		(connect_pads
			(clearance 0.5)
		)
		(min_thickness 0.25)
		(fill yes
			(thermal_gap 0.5)
			(thermal_bridge_width 0.5)
			(island_removal_mode 0)
		)
		(polygon
			(pts
				(xy -41.0464 46.863) (xy -41.0464 -3.81) (xy -37.93998 -3.81) (xy -37.91458 -3.7846) (xy -37.8714 -3.7846)
				(xy -15.9258 -3.7846) (xy -15.9258 46.863)
			)
		)
	)
	(zone
		(net "P3V3_B1_QSFP")
		(layer "In3.Cu")
		(hatch none 0.5)
		(connect_pads
			(clearance 0.5)
		)
		(min_thickness 0.25)
		(fill yes
			(thermal_gap 0.5)
			(thermal_bridge_width 0.5)
			(island_removal_mode 0)
		)
		(polygon
			(pts
				(xy -305.054 46.736) (xy -305.054 32.258) (xy -305.054 31.75) (xy -304.673 31.369) (xy -292.3794 31.369)
				(xy -291.312585 32.435815) (xy -291.312585 38.227015) (xy -288.5186 41.021) (xy -273.9898 41.021)
				(xy -273.9898 46.736)
			)
		)
	)
	(zone
		(net "P12V")
		(layer "In3.Cu")
		(hatch none 0.5)
		(connect_pads
			(clearance 0.5)
		)
		(min_thickness 0.25)
		(fill yes
			(thermal_gap 0.5)
			(thermal_bridge_width 0.5)
			(island_removal_mode 0)
		)
		(polygon
			(pts
				(xy -369.697 46.6598) (xy -369.697 18.8976) (xy -372.3386 16.256) (xy -410.0322 16.256) (xy -412.8897 13.3985)
				(xy -412.8897 7.8867) (xy -412.877 7.874) (xy -412.877 6.858714)
				(arc
					(start -411.734064 5.715777)
					(mid -411.044124 5.478292)
					(end -410.7512 4.810001)
				)
				(xy -410.7512 -4.108536) (xy -410.521417 -4.33832) (xy -371.168585 -4.33832) (xy -370.938801 -4.108536)
				(arc
					(start -370.938801 3.66)
					(mid -370.335792 5.115791)
					(end -368.880001 5.7188)
				)
				(arc
					(start -367.879998 5.7188)
					(mid -366.424207 5.115791)
					(end -365.821199 3.66)
				)
				(arc
					(start -365.821199 -2.34)
					(mid -365.252635 -3.712635)
					(end -363.880001 -4.2812)
				)
				(xy -88.14438 -4.2812) (xy -87.5538 -3.69062) (xy -87.5538 16.9926) (xy -96.6089 26.0477) (xy -96.6089 26.9621)
				(xy -105.5878 35.941) (xy -105.5878 45.339) (xy -105.9688 45.72) (xy -148.6916 45.72) (xy -148.691605 45.719995)
				(xy -148.691605 17.754595) (xy -151.45893 14.98727) (xy -161.01187 14.98727) (xy -164.4396 18.415)
				(xy -179.6288 18.415) (xy -184.3532 23.1394) (xy -190.754 23.1394) (xy -190.754 45.9994) (xy -273.1262 45.9994)
				(xy -273.2532 45.8724) (xy -273.2532 39.9796) (xy -273.27606 39.9796) (xy -273.27606 28.96616) (xy -288.54908 28.96616)
				(xy -288.54908 28.92552) (xy -288.89706 28.92552) (xy -288.89706 28.66898) (xy -290.8681 28.66898)
				(xy -290.8681 30.42666) (xy -290.8808 30.42666) (xy -290.8808 30.4419) (xy -305.435 30.4419) (xy -306.30495 31.31185)
				(xy -306.2986 31.3182) (xy -306.2986 37.11702) (xy -321.82816 37.11702) (xy -323.08038 38.36924)
				(xy -323.08038 38.3921) (xy -324.36562 38.3921) (xy -324.38086 38.40734) (xy -324.38086 42.75328)
				(xy -325.68642 42.75328) (xy -325.68642 46.6598)
			)
		)
		(polygon
			(pts
				(xy -240.1697 11.6205) (xy -240.1697 14.224) (xy -247.4976 14.224) (xy -247.4976 11.6205)
			)
		)
		(polygon
			(pts
				(xy -240.1824 25.6794) (xy -247.4976 25.6794) (xy -247.4976 25.6667) (xy -247.523 25.6667) (xy -247.523 22.987)
				(xy -240.1316 22.987) (xy -240.1316 25.6667) (xy -240.1824 25.6667)
			)
		)
		(polygon
			(pts
				(xy -251.1933 22.9997) (xy -251.1933 25.6413) (xy -258.7498 25.6413) (xy -258.7498 22.9997)
			)
		)
		(polygon
			(pts
				(xy -250.8885 18.4531) (xy -250.8885 21.8694) (xy -258.7498 21.8694) (xy -258.7498 18.4531)
			)
		)
		(polygon
			(pts
				(xy -240.0808 18.4277) (xy -240.0808 21.9202) (xy -247.523 21.9202) (xy -247.523 18.4277)
			)
		)
		(polygon
			(pts
				(xy -240.2078 15.4432) (xy -240.2078 18.1102) (xy -247.5992 18.1102) (xy -247.5992 15.4432)
			)
		)
		(polygon
			(pts
				(xy -250.9647 15.4051) (xy -250.9647 18.0848) (xy -258.699 18.0848) (xy -258.699 15.4051)
			)
		)
		(polygon
			(pts
				(xy -258.7498 11.5697) (xy -250.9774 11.5697) (xy -250.9774 14.2748) (xy -258.7498 14.2748)
			)
		)
	)
	(zone
		(net "P3V3_B2_QSFP")
		(layer "In3.Cu")
		(hatch none 0.5)
		(connect_pads
			(clearance 0.5)
		)
		(min_thickness 0.25)
		(fill yes
			(thermal_gap 0.5)
			(thermal_bridge_width 0.5)
			(island_removal_mode 0)
		)
		(polygon
			(pts
				(xy -83.693 46.5836) (xy -83.693 31.9786) (xy -70.0786 31.9786) (xy -70.0786 40.5384) (xy -49.276 40.5384)
				(xy -49.276 46.5836)
			)
		)
	)
	(zone
		(net "P12V")
		(layer "In4.Cu")
		(hatch none 0.5)
		(connect_pads
			(clearance 0.5)
		)
		(min_thickness 0.25)
		(fill yes
			(thermal_gap 0.5)
			(thermal_bridge_width 0.5)
			(island_removal_mode 0)
		)
		(polygon
			(pts
				(xy -129.032 46.926599) (xy -148.3106 46.8884) (xy -148.6916 46.8884) (xy -148.69398 46.88602) (xy -148.69398 17.756944)
				(xy -154.025641 12.425284) (xy -192.785987 12.410631) (xy -193.946678 13.571322) (xy -193.946678 45.483678)
				(xy -194.5386 46.0756) (xy -236.1184 46.0756) (xy -236.207341 45.986659) (xy -236.207341 11.899859)
				(xy -238.7346 9.3726) (xy -260.67258 9.3726) (xy -260.77291 9.47293) (xy -260.77291 9.47801) (xy -263.3726 12.0777)
				(xy -263.3726 23.2156) (xy -265.1252 24.9682) (xy -302.26 24.9682) (xy -306.96789 29.67609) (xy -310.83377 29.67609)
				(xy -313.90336 32.74568) (xy -319.07988 32.74568) (xy -325.158191 38.823991) (xy -325.158191 46.139191)
				(xy -325.9328 46.9138) (xy -369.7224 46.9138) (xy -369.7097 46.9011) (xy -369.7097 18.6563) (xy -371.221 17.145)
				(xy -372.618 17.145) (xy -373.9388 15.8242) (xy -412.115 15.8242) (xy -413.0167 14.9225) (xy -413.0167 11.5443)
				(xy -415.6456 8.9154) (xy -421.926601 8.9154) (xy -421.926601 -4.119057) (xy -421.704798 -4.34086)
				(xy -412.765202 -4.34086) (xy -412.543399 -4.119057)
				(arc
					(start -412.543399 4.810001)
					(mid -411.66 5.6934)
					(end -410.7766 4.810001)
				)
				(xy -410.7766 -4.119057) (xy -410.557337 -4.33832) (xy -371.13464 -4.33832) (xy -371.13464 -4.340296)
				(xy -370.913401 -4.119057)
				(arc
					(start -370.913401 3.66)
					(mid -370.317832 5.097831)
					(end -368.880001 5.6934)
				)
				(arc
					(start -367.879998 5.6934)
					(mid -366.442167 5.097831)
					(end -365.846599 3.66)
				)
				(arc
					(start -365.846599 -2.34)
					(mid -365.270596 -3.730595)
					(end -363.880001 -4.3066)
				)
				(xy -105.9688 -4.3066) (xy -105.9688 46.926599)
			)
		)
	)
	(zone
		(net "GND")
		(layer "In4.Cu")
		(hatch none 0.5)
		(connect_pads
			(clearance 0.5)
		)
		(min_thickness 0.25)
		(fill yes
			(thermal_gap 0.5)
			(thermal_bridge_width 0.5)
			(island_removal_mode 0)
		)
		(polygon
			(pts
				(xy -105.1814 46.8884) (xy -105.1814 26.0858) (xy -105.1052 26.0858) (xy -105.2322 25.9588) (xy -105.2322 -3.81)
				(xy -40.513 -3.81) (xy 2.286 -3.81) (xy 3.683 -2.413) (xy 3.683 35.179) (xy 4.826 36.322) (xy 4.826 45.212)
				(xy 3.6322 46.4058) (xy -1.914911 46.863) (xy -85.5472 46.863) (xy -86.22032 47.53612) (xy -86.22032 47.59962)
				(xy -88.06434 49.44364) (xy -100.919013 49.44364) (xy -103.484792 46.877862)
			)
		)
	)
	(zone
		(net "GND")
		(layer "In4.Cu")
		(hatch none 0.5)
		(connect_pads
			(clearance 0.5)
		)
		(min_thickness 0.25)
		(fill yes
			(thermal_gap 0.5)
			(thermal_bridge_width 0.5)
			(island_removal_mode 0)
		)
		(polygon
			(pts
				(xy -149.733 19.2024) (xy -158.0134 19.2024) (xy -158.242 19.431) (xy -158.242 21.082) (xy -158.496 21.336)
				(xy -159.512 21.336) (xy -159.6517 21.1963) (xy -164.2618 16.5862) (xy -181.483 16.5862) (xy -188.6204 23.7236)
				(xy -188.6204 45.593) (xy -188.0616 46.1518) (xy -150.2156 46.1518) (xy -149.733 45.6692)
			)
		)
	)
	(zone
		(net "P12V_MEZZ_B2")
		(layer "In4.Cu")
		(hatch none 0.5)
		(connect_pads
			(clearance 0.5)
		)
		(min_thickness 0.25)
		(fill yes
			(thermal_gap 0.5)
			(thermal_bridge_width 0.5)
			(island_removal_mode 0)
		)
		(polygon
			(pts
				(xy -181.9402 16.0782) (xy -164.211 16.0782) (xy -159.2834 21.0058) (xy -158.8008 21.0058) (xy -158.623 20.828)
				(xy -158.623 19.05) (xy -158.496 18.923) (xy -156.083 18.923) (xy -155.936 18.776) (xy -155.936 13.355)
				(xy -156.337 12.954) (xy -192.405 12.954) (xy -193.0908 13.6398) (xy -193.0908 34.925) (xy -189.0014 34.925)
				(xy -189.0014 23.1394)
			)
		)
	)
	(zone
		(net "GND")
		(layer "In4.Cu")
		(hatch none 0.5)
		(connect_pads
			(clearance 0.5)
		)
		(min_thickness 0.25)
		(fill yes
			(thermal_gap 0.5)
			(thermal_bridge_width 0.5)
			(island_removal_mode 0)
		)
		(polygon
			(pts
				(xy -409.2956 16.3068) (xy -376.7074 16.3068) (xy -374.1166 16.3068) (xy -373.9642 16.4592) (xy -372.7704 17.653)
				(xy -371.6782 17.653) (xy -370.2558 19.0754) (xy -370.2558 45.9994) (xy -370.5987 46.3423) (xy -380.9619 46.3423)
				(xy -380.9746 46.355) (xy -408.8638 46.355) (xy -408.9146 46.4058) (xy -412.8262 46.4058) (xy -412.9532 46.2788)
				(xy -412.9532 38.1254) (xy -414.6296 36.449) (xy -420.8018 36.449) (xy -420.8018 22.2504) (xy -420.5732 22.0218)
				(xy -416.3822 22.0218) (xy -416.3568 21.9964) (xy -414.9852 21.9964)
			)
		)
	)
	(zone
		(net "GND")
		(layer "In4.Cu")
		(hatch none 0.5)
		(connect_pads
			(clearance 0.5)
		)
		(min_thickness 0.25)
		(fill yes
			(thermal_gap 0.5)
			(thermal_bridge_width 0.5)
			(island_removal_mode 0)
		)
		(polygon
			(pts
				(xy -322.9864 48.5648) (xy -324.5612 46.99) (xy -324.5612 38.9636) (xy -320.3194 34.7218) (xy -318.67919 33.08159)
				(xy -313.75604 33.08159) (xy -310.58232 29.90787) (xy -306.116553 29.90787) (xy -303.911 27.702317)
				(xy -262.509015 27.702317) (xy -262.49437 12.93937) (xy -262.49437 12.4841) (xy -262.49437 12.36787)
				(xy -262.49437 12.36726) (xy -260.79511 10.668) (xy -260.21599 10.08888) (xy -239.46612 10.08888)
				(xy -238.887 10.668) (xy -238.0234 11.5316) (xy -238.0234 11.5062) (xy -237.4138 12.1158) (xy -237.4138 46.8376)
				(xy -237.4392 46.8122) (xy -262.4582 46.8122) (xy -262.4582 27.7114) (xy -291.6174 27.7114) (xy -291.6174 46.7614)
				(xy -262.89 46.7614) (xy -262.89 46.8122) (xy -306.6542 46.8122) (xy -308.4068 48.5648) (xy -309.2831 49.4411)
				(xy -322.1101 49.4411)
			)
		)
	)
	(zone
		(net "P3V3_B2_QSFP")
		(layer "In5.Cu")
		(hatch none 0.5)
		(connect_pads
			(clearance 0.5)
		)
		(min_thickness 0.25)
		(fill yes
			(thermal_gap 0.5)
			(thermal_bridge_width 0.5)
			(island_removal_mode 0)
		)
		(polygon
			(pts
				(xy -54.0766 46.609) (xy -54.0766 44.3738) (xy -53.4924 43.7896) (xy -53.4924 25.0698) (xy -53.5432 25.1206)
				(xy -66.7766 11.8872) (xy -74.1934 11.8872) (xy -75.8952 10.1854) (xy -80.772 10.1854) (xy -83.6676 13.081)
				(xy -95.123 13.081) (xy -101.727 19.685) (xy -112.5474 19.685) (xy -114.4397 17.7927) (xy -114.4397 10.2997)
				(xy -112.268 8.128) (xy -104.013 8.128) (xy -102.489 6.604) (xy -102.489 -2.667) (xy -102.4636 -2.6924)
				(xy -43.7388 -2.6924) (xy -41.9862 -0.9398) (xy -41.9862 13.8684) (xy -48.9204 13.8684) (xy -49.2633 14.2113)
				(xy -49.2633 46.609)
			)
		)
	)
	(zone
		(net "P3V3_B1_QSFP")
		(layer "In5.Cu")
		(hatch none 0.5)
		(connect_pads
			(clearance 0.5)
		)
		(min_thickness 0.25)
		(fill yes
			(thermal_gap 0.5)
			(thermal_bridge_width 0.5)
			(island_removal_mode 0)
		)
		(polygon
			(pts
				(xy -288.9123 44.0436) (xy -276.86 44.0436) (xy -276.86 27.2034) (xy -280.67 23.3934) (xy -280.67 22.1996)
				(xy -280.0096 21.5392) (xy -270.7894 21.5392) (xy -270.383 21.9456) (xy -270.383 44.0436) (xy -270.383 46.951997)
				(xy -288.925 46.951997) (xy -288.9123 46.939297)
			)
		)
	)
	(zone
		(net "P12V_MEZZ_B1")
		(layer "In5.Cu")
		(hatch none 0.5)
		(connect_pads
			(clearance 0.5)
		)
		(min_thickness 0.25)
		(fill yes
			(thermal_gap 0.5)
			(thermal_bridge_width 0.5)
			(island_removal_mode 0)
		)
		(polygon
			(pts
				(xy -413.004 34.925) (xy -414.02 33.909) (xy -414.02 18.542) (xy -413.512 18.034) (xy -413.512 15.24)
				(xy -411.48 13.208) (xy -384.429 13.208) (xy -381.762 15.875) (xy -377.2408 15.875) (xy -377.0884 16.0274)
				(xy -377.0884 18.6436) (xy -377.1138 18.669) (xy -379.095 18.669) (xy -379.73 19.304) (xy -379.73 21.0058)
				(xy -379.7554 21.0312) (xy -381.8128 21.0312) (xy -386.842 16.002) (xy -402.844 16.002) (xy -409.702 22.86)
				(xy -409.702 34.925)
			)
		)
	)
	(zone
		(net "P12V")
		(layer "In5.Cu")
		(hatch none 0.5)
		(connect_pads
			(clearance 0.5)
		)
		(min_thickness 0.25)
		(fill yes
			(thermal_gap 0.5)
			(thermal_bridge_width 0.5)
			(island_removal_mode 0)
		)
		(polygon
			(pts
				(xy -369.5446 46.9138) (xy -369.5446 18.8214) (xy -371.348 17.018) (xy -372.618 17.018) (xy -374.396 15.24)
				(xy -381.635 15.24) (xy -384.048 12.827) (xy -411.48 12.827) (xy -413.004 11.303) (xy -413.004 6.894144)
				(arc
					(start -411.81529 5.705434)
					(mid -411.074856 5.505358)
					(end -410.7512 4.810001)
				)
				(xy -410.7512 -4.108536) (xy -410.521417 -4.33832) (xy -371.168585 -4.33832) (xy -370.938801 -4.108536)
				(arc
					(start -370.938801 3.66)
					(mid -370.335792 5.115791)
					(end -368.880001 5.7188)
				)
				(arc
					(start -367.879998 5.7188)
					(mid -366.424207 5.115791)
					(end -365.821199 3.66)
				)
				(arc
					(start -365.821199 -2.34)
					(mid -365.252635 -3.712635)
					(end -363.880001 -4.2812)
				)
				(xy -105.156 -4.2812) (xy -105.156 7.0866) (xy -105.537 7.4676) (xy -112.5982 7.4676) (xy -115.3922 10.2616)
				(xy -115.3922 17.7292) (xy -112.9538 20.1676) (xy -112.9538 20.193) (xy -105.1814 20.193) (xy -105.1814 19.9898)
				(xy -105.156 19.9898) (xy -105.156 45.847) (xy -106.172 46.863) (xy -144.145 46.863) (xy -147.447 43.561)
				(xy -147.447 17.526) (xy -149.987 14.986) (xy -182.626 14.986) (xy -190.3984 22.7584) (xy -190.4238 22.7584)
				(xy -190.7032 23.0378) (xy -190.7032 45.6438) (xy -191.0842 46.0248) (xy -236.474 46.0248) (xy -236.639489 45.859311)
				(xy -236.639489 12.336391) (xy -238.68888 10.287) (xy -252.16358 10.287) (xy -252.16358 10.09396)
				(xy -256.85496 10.09396) (xy -256.85496 10.03046) (xy -257.75158 10.03046) (xy -257.75158 10.30478)
				(xy -257.74904 10.30478) (xy -257.74904 10.30732) (xy -257.6068 10.30732) (xy -257.6068 10.3124)
				(xy -262.1788 10.3124) (xy -266.7762 14.9098) (xy -291.0332 14.9098) (xy -291.0332 16.4084) (xy -297.2308 22.606)
				(xy -308.8386 22.606) (xy -323.7484 37.5158) (xy -325.70166 37.5158) (xy -325.70166 46.10862) (xy -326.50684 46.9138)
			)
		)
	)
	(zone
		(net "GND")
		(layer "In6.Cu")
		(hatch none 0.5)
		(connect_pads
			(clearance 0.5)
		)
		(min_thickness 0.25)
		(fill yes
			(thermal_gap 0.5)
			(thermal_bridge_width 0.5)
			(island_removal_mode 0)
		)
		(polygon
			(pts
				(xy -324.266199 49.441199)
				(arc
					(start -324.266199 47.960001)
					(mid -324.576315 47.211315)
					(end -325.325001 46.901199)
				)
				(arc
					(start -420.960001 46.901199)
					(mid -421.625529 46.625528)
					(end -421.901201 45.96)
				)
				(xy -421.901201 -4.108536) (xy -421.668877 -4.34086) (xy -412.801123 -4.34086) (xy -412.568799 -4.108536)
				(arc
					(start -412.568799 4.810001)
					(mid -411.66 5.7188)
					(end -410.7512 4.810001)
				)
				(xy -410.7512 -4.108536) (xy -410.521417 -4.33832) (xy -371.168585 -4.33832) (xy -370.938801 -4.108536)
				(arc
					(start -370.938801 3.66)
					(mid -370.335792 5.115791)
					(end -368.880001 5.7188)
				)
				(arc
					(start -367.879998 5.7188)
					(mid -366.424207 5.115791)
					(end -365.821199 3.66)
				)
				(arc
					(start -365.821199 -2.34)
					(mid -365.252635 -3.712635)
					(end -363.880001 -4.2812)
				)
				(arc
					(start 1.38 -4.2812)
					(mid 3.106189 -3.566189)
					(end 3.821199 -1.839999)
				)
				(arc
					(start 3.821199 34.5)
					(mid 4.131315 35.248685)
					(end 4.88 35.558801)
				)
				(xy 4.981199 35.558801)
				(arc
					(start 4.981199 44.46)
					(mid 4.266188 46.186188)
					(end 2.54 46.901199)
				)
				(arc
					(start -85.175001 46.901199)
					(mid -85.923686 47.211316)
					(end -86.2338 47.960001)
				)
				(xy -86.2338 49.441199) (xy -103.266199 49.441199)
				(arc
					(start -103.266199 47.960001)
					(mid -103.576315 47.211315)
					(end -104.325001 46.901199)
				)
				(xy -229.8192 46.901199) (xy -229.869901 46.9519) (xy -306.539143 46.9519)
				(arc
					(start -306.56151 46.974267)
					(mid -307.049727 47.363418)
					(end -307.2338 47.960001)
				)
				(xy -307.2338 49.441199)
			)
		)
	)
	(zone
		(layer "Cmts.User")
		(hatch none 0.5)
		(connect_pads
			(clearance 0)
		)
		(min_thickness 0.25)
		(keepout
			(tracks allowed)
			(vias allowed)
			(pads allowed)
			(copperpour allowed)
			(footprints allowed)
		)
		(placement
			(enabled no)
			(sheetname "")
		)
		(fill
			(thermal_gap 0.5)
			(thermal_bridge_width 0.5)
			(island_removal_mode 0)
		)
		(polygon
			(pts
				(xy -411.396434 23.61631) (xy -391.464978 23.61631) (xy -391.464978 46.471383) (xy -411.396434 46.471383)
			)
		)
	)
	(zone
		(layer "Cmts.User")
		(hatch none 0.5)
		(connect_pads
			(clearance 0)
		)
		(min_thickness 0.25)
		(keepout
			(tracks allowed)
			(vias allowed)
			(pads allowed)
			(copperpour allowed)
			(footprints allowed)
		)
		(placement
			(enabled no)
			(sheetname "")
		)
		(fill
			(thermal_gap 0.5)
			(thermal_bridge_width 0.5)
			(island_removal_mode 0)
		)
		(polygon
			(pts
				(xy -246.817388 39.072566) (xy -246.817388 41.482772) (xy -246.817388 46.477682) (xy -258.417822 46.477682)
				(xy -258.417822 32.427926) (xy -258.417822 31.598108) (xy -246.83593 31.598108) (xy -246.83593 31.60395)
				(xy -246.817388 31.60395)
			)
		)
	)
	(zone
		(layer "Cmts.User")
		(hatch none 0.5)
		(connect_pads
			(clearance 0)
		)
		(min_thickness 0.25)
		(keepout
			(tracks allowed)
			(vias allowed)
			(pads allowed)
			(copperpour allowed)
			(footprints allowed)
		)
		(placement
			(enabled no)
			(sheetname "")
		)
		(fill
			(thermal_gap 0.5)
			(thermal_bridge_width 0.5)
			(island_removal_mode 0)
		)
		(polygon
			(pts
				(xy -25.817388 39.072566) (xy -25.817388 41.482772) (xy -25.817388 46.477682) (xy -37.417822 46.477682)
				(xy -37.417822 32.427926) (xy -37.417822 31.598108) (xy -25.83593 31.598108) (xy -25.83593 31.60395)
				(xy -25.817388 31.60395)
			)
		)
	)
	(zone
		(layer "Cmts.User")
		(hatch none 0.5)
		(connect_pads
			(clearance 0)
		)
		(min_thickness 0.25)
		(keepout
			(tracks allowed)
			(vias allowed)
			(pads allowed)
			(copperpour allowed)
			(footprints allowed)
		)
		(placement
			(enabled no)
			(sheetname "")
		)
		(fill
			(thermal_gap 0.5)
			(thermal_bridge_width 0.5)
			(island_removal_mode 0)
		)
		(polygon
			(pts
				(xy -190.36411 23.702924) (xy -168.9354 23.702924) (xy -168.9354 46.9646) (xy -190.36411 46.9646)
			)
		)
	)
	(zone
		(layer "Cmts.User")
		(hatch none 0.5)
		(connect_pads
			(clearance 0)
		)
		(min_thickness 0.25)
		(keepout
			(tracks allowed)
			(vias allowed)
			(pads allowed)
			(copperpour allowed)
			(footprints allowed)
		)
		(placement
			(enabled no)
			(sheetname "")
		)
		(fill
			(thermal_gap 0.5)
			(thermal_bridge_width 0.5)
			(island_removal_mode 0)
		)
		(polygon
			(pts
				(xy -72.243 41.7449) (xy -72.243 44.958) (xy -83.843434 44.958) (xy -83.843434 31.644336) (xy -72.261542 31.644336)
				(xy -72.261542 31.650178) (xy -71.373812 31.650178) (xy -71.373812 35.323526) (xy -71.373812 39.118794)
				(xy -72.243 39.118794) (xy -72.269924 39.118794) (xy -72.269924 41.7449)
			)
		)
	)
	(zone
		(layer "Cmts.User")
		(hatch none 0.5)
		(connect_pads
			(clearance 0)
		)
		(min_thickness 0.25)
		(keepout
			(tracks allowed)
			(vias allowed)
			(pads allowed)
			(copperpour allowed)
			(footprints allowed)
		)
		(placement
			(enabled no)
			(sheetname "")
		)
		(fill
			(thermal_gap 0.5)
			(thermal_bridge_width 0.5)
			(island_removal_mode 0)
		)
		(polygon
			(pts
				(xy -293.243 41.7449) (xy -293.243 45.9994) (xy -304.843434 45.9994) (xy -304.843434 31.644336)
				(xy -293.261542 31.644336) (xy -293.261542 31.650178) (xy -292.373812 31.650178) (xy -292.373812 35.323526)
				(xy -292.373812 39.118794) (xy -293.243 39.118794) (xy -293.269924 39.118794) (xy -293.269924 41.7449)
			)
		)
	)
)
